G04 ================== begin FILE IDENTIFICATION RECORD ==================*
G04 Layout Name:  15126-1b.brd*
G04 Film Name:    L13GND*
G04 File Format:  Gerber RS274X*
G04 File Origin:  Cadence Allegro 16.6-2015-S079*
G04 Origin Date:  Fri Feb 10 17:23:13 2017*
G04 *
G04 Layer:  VIA CLASS/L13GND*
G04 Layer:  PIN/L13GND*
G04 Layer:  ETCH/L13GND*
G04 Layer:  DRAWING FORMAT/LAYER_PCB_STORY*
G04 Layer:  DRAWING FORMAT/LAYER_L13GND*
G04 *
G04 Offset:    (0.00 0.00)*
G04 Mirror:    No*
G04 Mode:      Positive*
G04 Rotation:  0*
G04 FullContactRelief:  No*
G04 UndefLineWidth:     6.00*
G04 ================== end FILE IDENTIFICATION RECORD ====================*
%FSLAX35Y35*MOIN*%
%IR0*IPPOS*OFA0.00000B0.00000*MIA0B0*SFA1.00000B1.00000*%
%ADD12C,.02*%
%ADD42C,.03*%
%ADD29C,.04*%
%ADD28C,.031*%
%ADD10C,.022*%
%ADD23C,.05*%
%ADD21C,.06*%
%ADD31C,.052*%
%ADD13C,.034*%
%ADD17C,.071*%
%ADD16C,.044*%
%ADD39C,.045*%
%ADD26C,.054*%
%ADD22C,.018*%
%ADD40C,.055*%
%ADD25C,.064*%
%ADD20C,.028*%
%ADD14C,.046*%
%ADD34C,.047*%
%ADD24C,.056*%
%ADD19C,.039*%
%ADD18C,.057*%
%ADD36O,.041X.06*%
%AMMACRO38*
4,1,48,.0225,.036,
.026668,.035635,
.030708,.034553,
.0345,.032785,
.037927,.030385,
.040885,.027427,
.043285,.024,
.045053,.020208,
.046135,.016168,
.0465,.012,
.046135,.007832,
.045053,.003792,
.043285,0.0,
.040885,-.003427,
.037927,-.006385,
.0345,-.008785,
.030708,-.010553,
.026668,-.011635,
.0225,-.012,
.0015,-.012,
.001135,-.016168,
.000053,-.020208,
-.001715,-.024,
-.004115,-.027427,
-.007073,-.030385,
-.0105,-.032785,
-.014292,-.034553,
-.018332,-.035635,
-.0225,-.036,
-.026668,-.035635,
-.030708,-.034553,
-.0345,-.032785,
-.037927,-.030385,
-.040885,-.027427,
-.043285,-.024,
-.045053,-.020208,
-.046135,-.016168,
-.0465,-.012,
-.0465,.012,
-.046135,.016168,
-.045053,.020208,
-.043285,.024,
-.040885,.027427,
-.037927,.030385,
-.0345,.032785,
-.030708,.034553,
-.026668,.035635,
-.0225,.036,
.0225,.036,
0.0*
%
%ADD38MACRO38*%
%ADD30O,.032X.036*%
%ADD32O,.07X.046*%
%ADD15C,.14*%
%ADD41O,.094X.048*%
%ADD11C,.238*%
%ADD33O,.098X.046*%
%ADD27C,.276*%
%ADD35O,.099X.048*%
%ADD43C,.01*%
%ADD44C,.025*%
%ADD45C,.006*%
%ADD46C,.0045*%
%ADD97R,.05948X.06858*%
%ADD52O,.07202X.12102*%
%ADD64C,.03004*%
%ADD87C,.04004*%
%ADD74C,.03204*%
%ADD99C,.06104*%
%ADD69C,.07004*%
%ADD89C,.08004*%
%ADD79C,.06204*%
%ADD65C,.04404*%
%ADD81C,.07204*%
%ADD96C,.05504*%
%ADD84C,.06404*%
%ADD49C,.02804*%
%ADD95C,.06504*%
%ADD86C,.04704*%
%ADD71C,.07404*%
%ADD48C,.05604*%
%ADD98C,.05506*%
%ADD92C,.05704*%
%ADD88C,.09304*%
%ADD78C,.07504*%
%ADD68C,.08404*%
%ADD61C,.04804*%
%ADD70C,.07604*%
%ADD94C,.06804*%
%ADD73C,.05904*%
%ADD63C,.08604*%
%ADD80C,.07804*%
%ADD56C,.06943*%
%ADD59C,.11211*%
%ADD90R,.02002X.05502*%
%ADD76R,.02202X.07102*%
%ADD72C,.12104*%
%ADD62C,.11204*%
%ADD60C,.261*%
%ADD93R,.02004X.05502*%
%ADD83R,.05504X.02002*%
%ADD82R,.05502X.02004*%
%ADD75R,.02204X.07102*%
%ADD66C,.15004*%
%ADD51O,.15402X.21902*%
%ADD47C,.11404*%
%ADD91R,.02004X.05504*%
%ADD67R,.05504X.02004*%
%ADD58R,.03002X.03904*%
%ADD50O,.15404X.21904*%
%ADD57R,.03004X.03904*%
%ADD54C,.15504*%
%ADD53R,.03904X.03004*%
%ADD100R,.03902X.06302*%
%ADD55C,.15506*%
%ADD85C,.28404*%
%ADD77C,.17804*%
G75*
%LPD*%
G75*
G36*
G01X1973300Y-60000D02*
X-19810D01*
Y-34500D01*
X1973300D01*
Y-60000D01*
G37*
G36*
G01X1972441Y434402D02*
X1922315D01*
G02X1921957Y434979I1J400D01*
G03X1919533Y436377I-1257J621D01*
G02X1918867I-333J222D01*
G03X1916533I-1167J-777D01*
G02X1915867I-333J222D01*
G03X1913443Y434979I-1167J-777D01*
G02X1913085Y434402I-359J-177D01*
G01X1698400D01*
Y434399D01*
X1685866D01*
G03X1680128Y428661I0J-5738D01*
G01Y428595D01*
X1680127Y428584D01*
G03X1680088Y427908I6448J-711D01*
G01Y306403D01*
G02X1679558Y306025I-400J0D01*
G03X1678129Y303689I-458J-1325D01*
G02Y303111I-277J-289D01*
G03Y301089I971J-1011D01*
G02Y300511I-277J-289D01*
G03X1678090Y298527I971J-1011D01*
G02Y297973I-288J-277D01*
G03Y296027I1010J-973D01*
G02Y295473I-288J-277D01*
G03Y293527I1010J-973D01*
G02Y292973I-288J-277D01*
G03Y291027I1010J-973D01*
G02Y290473I-288J-277D01*
G03X1678271Y288369I1010J-973D01*
G02Y287724I-236J-323D01*
G03X1678090Y285620I829J-1131D01*
G02Y285066I-288J-277D01*
G03Y283120I1010J-973D01*
G02Y282566I-288J-277D01*
G03X1678158Y280555I1010J-972D01*
G02Y279962I-269J-297D01*
G03X1678099Y277942I942J-1038D01*
G02Y277382I-285J-280D01*
G03X1678090Y275427I1001J-982D01*
G02Y274873I-288J-277D01*
G03X1678129Y272889I1010J-973D01*
G02Y272311I-277J-289D01*
G03X1679729Y270047I971J-1011D01*
G02X1680297Y269787I180J-357D01*
G03X1685866Y265440I5569J1394D01*
G01X1686519D01*
G03X1686577Y265438I253J6483D01*
G01X1846588D01*
Y265440D01*
X1870747D01*
G02X1871097Y264846I0J-400D01*
G03X1873549I1226J-679D01*
G02X1873899Y265440I350J194D01*
G01X1883780D01*
G02X1885913Y263307I0J-2133D01*
G01Y250709D01*
G03X1891654Y244968I5741J0D01*
G01X1912260D01*
G02X1912615Y244384I0J-400D01*
G03X1915459I1422J-738D01*
G02X1915814Y244968I355J184D01*
G01X1946598D01*
Y236102D01*
X1954390D01*
G03X1959543Y236615I2500J1024D01*
G02X1960225Y236815I393J-76D01*
G03X1959666Y239000I1665J1590D01*
G02X1958972Y238849I-386J104D01*
G03X1957693Y239706I-2081J-1723D01*
G01X1957552Y239750D01*
Y244968D01*
X1965840D01*
Y239440D01*
X1974574D01*
Y210008D01*
X1965840D01*
Y204006D01*
X1974574D01*
Y148894D01*
G02X1973986Y148541I-400J0D01*
G03Y146065I-658J-1238D01*
G02X1974574Y145712I188J-353D01*
G01Y144490D01*
G02X1973914Y144186I-400J0D01*
G03Y142054I-910J-1066D01*
G02X1974574Y141750I260J-304D01*
G01Y59055D01*
G02X1972441Y56922I-2133J0D01*
G01X1906889D01*
G03X1903117Y53150I1J-3773D01*
G01Y52762D01*
G02X1902520Y52414I-400J0D01*
G03X1897805Y48998I-1575J-2788D01*
G02X1897250Y48554I-392J-79D01*
G03Y42706I-1305J-2924D01*
G02X1897805Y42262I163J-365D01*
G03Y41006I3140J-628D01*
G02X1897250Y40562I-392J-79D01*
G03Y34714I-1305J-2924D01*
G02X1897805Y34270I163J-365D01*
G03Y33014I3140J-628D01*
G02X1897250Y32570I-392J-79D01*
G03Y26722I-1305J-2924D01*
G02X1897805Y26278I163J-365D01*
G03X1897829Y24913I3140J-628D01*
G02X1897269Y24459I-389J-92D01*
G03Y18849I-1324J-2805D01*
G02X1897829Y18395I171J-362D01*
G03X1897805Y17030I3116J-737D01*
G02X1897250Y16586I-392J-79D01*
G03Y10738I-1305J-2924D01*
G02X1897805Y10294I163J-365D01*
G03Y9038I3140J-628D01*
G02X1897250Y8594I-392J-79D01*
G03Y2746I-1305J-2924D01*
G02X1897805Y2302I163J-365D01*
G03Y1046I3140J-628D01*
G02X1897250Y602I-392J-79D01*
G03Y-5246I-1305J-2924D01*
G02X1897805Y-5690I163J-365D01*
G03X1902520Y-9106I3140J-628D01*
G02X1903117Y-9454I197J-348D01*
G01Y-9843D01*
G03X1906889Y-13615I3773J1D01*
G01X1972441D01*
G02X1974574Y-15748I0J-2133D01*
G01Y-19685D01*
G02X1972441Y-21818I-2133J0D01*
G01X1894747D01*
G02X1894378Y-21266I1J400D01*
G03X1891784I-1297J531D01*
G02X1891415Y-21818I-370J-152D01*
G01X658438D01*
G02X658076Y-21248I0J400D01*
G03X655538I-1269J596D01*
G02X655176Y-21818I-362J-170D01*
G01X69236D01*
G02X68865Y-21269I0J400D01*
G03X67065Y-19435I-1301J524D01*
G02X66532Y-19149I-143J374D01*
G03X64216Y-18423I-1368J-307D01*
G02X63622Y-18362I-270J295D01*
G03X63434Y-20217I-1136J-822D01*
G02X64028Y-20278I270J-295D01*
G03X65663Y-20766I1136J822D01*
G02X66196Y-21052I143J-374D01*
G03X66263Y-21269I1369J304D01*
G02X65892Y-21818I-371J-149D01*
G01X52233D01*
G02X51867Y-21256I0J400D01*
G03X49305I-1281J569D01*
G02X48939Y-21818I-366J-162D01*
G01X39768D01*
G02X39426Y-21211I0J400D01*
G03X37028I-1199J726D01*
G02X36686Y-21818I-342J-207D01*
G01X-19685D01*
G02X-21818Y-19685I0J2133D01*
G01Y622441D01*
G02X-19685Y624574I2133J0D01*
G01X385284D01*
G02X385658Y624033I0J-400D01*
G03X388282I1312J-494D01*
G02X388656Y624574I374J141D01*
G01X451663D01*
G02X452015Y623984I0J-400D01*
G03X454485I1235J-664D01*
G02X454837Y624574I352J190D01*
G01X455323D01*
G02X455675Y623984I0J-400D01*
G03X458145I1235J-664D01*
G02X458497Y624574I352J190D01*
G01X726329D01*
G02X726700Y624024I0J-400D01*
G03X729300I1300J-524D01*
G02X729671Y624574I371J150D01*
G01X1044829D01*
G02X1045200Y624024I0J-400D01*
G03X1047800I1300J-524D01*
G02X1048171Y624574I371J150D01*
G01X1550535D01*
G02X1550904Y624020I0J-400D01*
G03X1553492I1294J-541D01*
G02X1553861Y624574I369J154D01*
G01X1555881D01*
G02X1556257Y624038I0J-400D01*
G03X1558813Y622900I1318J-479D01*
G02X1559517Y622904I353J-188D01*
G03X1562070Y624041I1230J672D01*
G02X1562447Y624574I377J133D01*
G01X1564902D01*
G02X1565261Y623998I0J-400D01*
G03X1567673Y622584I1259J-616D01*
G02X1568333Y622580I329J-228D01*
G03X1570748Y623994I1162J784D01*
G02X1571105Y624574I357J180D01*
G01X1972441D01*
G02X1974574Y622441I0J-2133D01*
G01Y598567D01*
G02X1973913Y598264I-400J0D01*
G03Y596136I-913J-1064D01*
G02X1974574Y595833I261J-303D01*
G01Y566366D01*
G02X1973869Y566107I-400J0D01*
G03Y564293I-1069J-907D01*
G02X1974574Y564034I305J-259D01*
G01Y537966D01*
G02X1973869Y537707I-400J0D01*
G03Y535893I-1069J-907D01*
G02X1974574Y535634I305J-259D01*
G01Y436535D01*
G02X1972441Y434402I-2133J0D01*
G37*
G36*
G01X-20621Y661811D02*
G02X-19685Y662747I936J0D01*
G01X1972600D01*
Y637600D01*
X-20412D01*
G02X-20621Y638189I726J589D01*
G01Y661811D01*
G37*
%LPC*%
G75*
G36*
G01X1603820Y433694D02*
G02X1602241Y433668I-770J-1171D01*
G03X1602230Y434329I-231J327D01*
G02X1603809Y434355I770J1171D01*
G03X1603820Y433694I231J-327D01*
G37*
G36*
G01X1685017Y192029D02*
G02X1685249Y190205I1166J-778D01*
G03X1684650Y190129I-266J-298D01*
G02X1684418Y191953I-1166J778D01*
G03X1685017Y192029I266J298D01*
G37*
G36*
G01X1675832Y195852D02*
G03X1675197Y195838I-312J-250D01*
G02X1675158Y197545I-1131J828D01*
G03X1675793Y197559I312J250D01*
G02X1675832Y195852I1131J-828D01*
G37*
G36*
G01X1610999Y609639D02*
G03X1610602Y609240I3J-400D01*
G01Y606698D01*
X1606698D01*
Y609702D01*
X1608174D01*
G03X1608408Y610426I0J400D01*
G02X1615979Y618295I2875J4810D01*
G02X1613472Y610077I-4694J-3059D01*
G02X1610999Y609639I-2189J5159D01*
G37*
G36*
G01X1606022Y557644D02*
Y561645D01*
G02X1607233Y563125I1511J-1D01*
G03X1607452Y563785I-79J393D01*
G02X1616289Y570393I3831J4090D01*
G02X1611415Y562272I-5004J-2520D01*
G02X1609474Y562570I-133J5602D01*
G03X1608983Y562072I-108J-385D01*
G02X1609044Y561654I-1450J-425D01*
G01Y557559D01*
X1609035Y557475D01*
G02X1606022Y557644I-1502J169D01*
G37*
G36*
G01X1514847Y92931D02*
X1514848D01*
Y92928D01*
X1514846D01*
Y92924D01*
X1514847D01*
G02X1514846Y92853I-1512J-14D01*
G01Y92836D01*
X1514844Y92817D01*
G02X1511844Y92664I-1509J102D01*
G01X1511820Y92780D01*
Y92784D01*
X1511819D01*
X1511496Y96414D01*
X1511497D01*
Y96415D01*
X1511501Y96542D01*
G02X1512516Y97974I1512J4D01*
G02X1513224Y98044I499J-1427D01*
G02X1514519Y96682I-211J-1498D01*
G01X1514529Y96683D01*
X1514541Y96554D01*
X1514534D01*
X1514535Y96548D01*
X1514541D01*
X1514852Y93055D01*
X1514849Y93053D01*
X1514848D01*
X1514843Y93048D01*
X1514844Y93026D01*
G02X1514847Y92931I-1509J-95D01*
G37*
G36*
G01X1756912Y37661D02*
Y37615D01*
X1756908Y37577D01*
G02X1754912Y36269I-1507J123D01*
G01X1754909Y36259D01*
X1751506Y37425D01*
Y37430D01*
X1751440Y37460D01*
G02X1751250Y37551I557J1406D01*
G03X1751065Y37198I-78J-184D01*
G02X1751762Y35935I-815J-1273D01*
G01Y35840D01*
X1751752Y35756D01*
G02X1750250Y34414I-1502J170D01*
G01X1746550D01*
G02X1745673Y37156I0J1511D01*
G03X1745687Y37796I-233J325D01*
G02X1747684Y38073I865J1104D01*
G03X1748006Y37436I323J-237D01*
G01X1750251D01*
G02X1750363Y37432I2J-1511D01*
G03X1750741Y38027I29J399D01*
G02X1752488Y40296I1260J837D01*
G01X1752491Y40306D01*
X1755896Y39140D01*
Y39138D01*
X1756013Y39082D01*
G02X1756350Y38877I-611J-1383D01*
G01Y38876D01*
G02X1756360Y38868I-939J-1184D01*
G01X1756362D01*
G02X1756912Y37710I-963J-1167D01*
G01Y37702D01*
G02Y37661I-1512J-20D01*
G37*
G36*
G01X47653Y260576D02*
X58217Y271140D01*
X74643D01*
X79079Y266704D01*
Y223005D01*
X75265Y219191D01*
X51313D01*
X47653Y222851D01*
Y260576D01*
G37*
G36*
G01X1928253Y535242D02*
X1930653D01*
G02Y529840I0J-2701D01*
G01X1928253D01*
G02Y535242I0J2701D01*
G37*
G36*
G01X1926853Y513904D02*
X1932053D01*
G02Y508500I0J-2702D01*
G01X1926853D01*
G02Y513904I0J2702D01*
G37*
G36*
G01X1951554Y127860D02*
X1958054D01*
G02Y112456I0J-7702D01*
G01X1951554D01*
G02Y127860I0J7702D01*
G37*
G36*
G01X1884727Y535242D02*
X1889927D01*
G02Y529840I0J-2701D01*
G01X1884727D01*
G02Y535242I0J2701D01*
G37*
G36*
G01X1886127Y513904D02*
X1888527D01*
G02Y508500I0J-2702D01*
G01X1886127D01*
G02Y513904I0J2702D01*
G37*
G36*
G01X1833443Y127860D02*
X1839943D01*
G02Y112456I0J-7702D01*
G01X1833443D01*
G02Y127860I0J7702D01*
G37*
G36*
G01X1857035Y602728D02*
X1854331D01*
G02Y618532I1J7902D01*
G01X1857044D01*
G03X1860510Y619640I-2J5982D01*
G02X1860511Y601620I7622J-9010D01*
G03X1857035Y602728I-3476J-4898D01*
G37*
G36*
G01Y-15776D02*
X1854331D01*
G02Y28I1J7902D01*
G01X1857044D01*
G03X1860510Y1136I-2J5982D01*
G02X1860511Y-16884I7622J-9010D01*
G03X1857035Y-15776I-3476J-4898D01*
G37*
G36*
G01X1684261Y616623D02*
X1687214Y611111D01*
G02X1683070Y608889I-2072J-1111D01*
G01X1680117Y614401D01*
G02X1684261Y616623I2072J1111D01*
G37*
G36*
G01Y601662D02*
X1687214Y596150D01*
G02X1683070Y593928I-2072J-1111D01*
G01X1680117Y599440D01*
G02X1684261Y601662I2072J1111D01*
G37*
G36*
G01X1675404Y616622D02*
X1678356Y611110D01*
G02X1674210Y608890I-2073J-1110D01*
G01X1671258Y614402D01*
G02X1675404Y616622I2073J1110D01*
G37*
G36*
G01Y601661D02*
X1678356Y596149D01*
G02X1674210Y593929I-2073J-1110D01*
G01X1671258Y599441D01*
G02X1675404Y601661I2073J1110D01*
G37*
G36*
G01X1408216Y602728D02*
X1405512D01*
G02Y618532I1J7902D01*
G01X1408225D01*
G03X1411691Y619640I-2J5982D01*
G02X1411692Y601620I7622J-9010D01*
G03X1408216Y602728I-3476J-4898D01*
G37*
G36*
G01Y-15776D02*
X1405512D01*
G02Y28I1J7902D01*
G01X1408225D01*
G03X1411691Y1136I-2J5982D01*
G02X1411692Y-16884I7622J-9010D01*
G03X1408216Y-15776I-3476J-4898D01*
G37*
G36*
G01X679869Y602728D02*
X677165D01*
G02Y618532I1J7902D01*
G01X679878D01*
G03X683344Y619640I-2J5982D01*
G02X683345Y601620I7622J-9010D01*
G03X679869Y602728I-3476J-4898D01*
G37*
G36*
G01Y-15776D02*
X677165D01*
G02Y28I1J7902D01*
G01X679878D01*
G03X683344Y1136I-2J5982D01*
G02X683345Y-16884I7622J-9010D01*
G03X679869Y-15776I-3476J-4898D01*
G37*
G36*
G01X2704Y602728D02*
X0D01*
G02Y618532I1J7902D01*
G01X2713D01*
G03X6179Y619640I-2J5982D01*
G02X6180Y601620I7622J-9010D01*
G03X2704Y602728I-3476J-4898D01*
G37*
G36*
G01X1313465Y618530D02*
G03X1312887I-289J-277D01*
G02Y620472I-1011J971D01*
G03X1313465I289J277D01*
G02Y618530I1011J-971D01*
G37*
G36*
G01X1591926Y619723D02*
G03X1592512Y619711I299J266D01*
G02X1592474Y617801I1007J-975D01*
G03X1591888Y617813I-299J-266D01*
G02X1591926Y619723I-1007J975D01*
G37*
G36*
G01X1602539Y617279D02*
G03X1601961I-289J-277D01*
G02Y619221I-1011J971D01*
G03X1602539I289J277D01*
G02Y617279I1011J-971D01*
G37*
G36*
G01X1962583Y618411D02*
G03Y617789I252J-311D01*
G02X1960817I-883J-1089D01*
G03Y618411I-252J311D01*
G02X1962583I883J1089D01*
G37*
G36*
G01X713345Y616607D02*
G03X712901Y616223I-44J-398D01*
G02X711655Y617667I-1401J51D01*
G03X712099Y618051I44J398D01*
G02X713345Y616607I1401J-51D01*
G37*
G36*
G01X1931383Y617811D02*
G03Y617189I252J-311D01*
G02X1929617I-883J-1089D01*
G03Y617811I-252J311D01*
G02X1931383I883J1089D01*
G37*
G36*
G01X1372904Y615115D02*
G03X1372297Y615025I-266J-298D01*
G02X1372034Y616802I-1197J731D01*
G03X1372641Y616892I266J298D01*
G02X1372904Y615115I1197J-731D01*
G37*
G36*
G01X629517Y611700D02*
G03X629012Y611466I-132J-378D01*
G02X628165Y613297I-1307J507D01*
G03X628670Y613531I132J378D01*
G02X629517Y611700I1307J-507D01*
G37*
G36*
G01X656071Y613089D02*
G03Y612511I277J-289D01*
G02X654129I-971J-1011D01*
G03Y613089I-277J289D01*
G02X656071I971J1011D01*
G37*
G36*
G01X1533154Y612419D02*
G03X1533178Y611832I283J-282D01*
G02X1531276Y611753I-908J-1068D01*
G03X1531252Y612340I-283J282D01*
G02X1531212Y612375I903J1072D01*
G03X1530665Y612370I-271J-294D01*
G02X1528864Y612257I-968J1014D01*
G03X1528294Y612159I-238J-322D01*
G02X1528149Y614024I-1244J841D01*
G03X1528470Y614063I146J136D01*
G02X1528563Y614209I1227J-679D01*
G03X1528485Y614509I-161J118D01*
G02X1530296Y615109I582J1275D01*
G03X1530435Y614576I350J-193D01*
G02X1530645Y614417I-738J-1192D01*
G03X1531192Y614422I271J294D01*
G02X1533154Y612419I969J-1014D01*
G37*
G36*
G01X1383607Y611122D02*
G03X1383603Y610567I286J-280D01*
G02X1381584Y610582I-1017J-965D01*
G03X1381588Y611137I-286J280D01*
G02X1383607Y611122I1017J965D01*
G37*
G36*
G01X1652380Y614210D02*
Y609115D01*
X1652371Y609031D01*
G02X1649358Y609200I-1502J169D01*
G01Y614201D01*
G02X1652380Y614210I1511J-1D01*
G37*
G36*
G01X1637045Y616571D02*
X1637046Y616569D01*
X1639942Y611164D01*
X1639943Y611162D01*
G02X1635798Y608941I-2045J-1162D01*
G01X1635797Y608943D01*
X1632901Y614348D01*
X1632900Y614350D01*
G02X1637045Y616571I2045J1162D01*
G37*
G36*
G01X1626947Y608926D02*
X1626946Y608927D01*
X1624034Y614364D01*
X1624033Y614366D01*
G02X1628179Y616586I2054J1146D01*
G01X1628180Y616585D01*
X1631092Y611148D01*
X1631093Y611146D01*
G02X1626947Y608926I-2054J-1146D01*
G37*
G36*
G01X1505671Y610089D02*
G03Y609511I277J-289D01*
G02X1503729I-971J-1011D01*
G03Y610089I-277J289D01*
G02X1505671I971J1011D01*
G37*
G36*
G01X1307614Y609031D02*
G03X1307604Y608489I289J-276D01*
G02X1305542Y608527I-1049J-931D01*
G03X1305552Y609069I-289J276D01*
G02X1307614Y609031I1049J931D01*
G37*
G36*
G01X1225862Y608964D02*
G03X1225868Y608407I290J-275D01*
G02X1223712Y608385I-1067J-1057D01*
G03X1223706Y608942I-290J275D01*
G02X1225862Y608964I1067J1057D01*
G37*
G36*
G01X1189051D02*
G03X1189057Y608407I290J-275D01*
G02X1186901Y608385I-1067J-1057D01*
G03X1186895Y608942I-290J275D01*
G02X1189051Y608964I1067J1057D01*
G37*
G36*
G01X1152240D02*
G03X1152246Y608407I290J-275D01*
G02X1150090Y608385I-1067J-1057D01*
G03X1150084Y608942I-290J275D01*
G02X1152240Y608964I1067J1057D01*
G37*
G36*
G01X1115428D02*
G03X1115434Y608407I290J-275D01*
G02X1113278Y608385I-1067J-1057D01*
G03X1113272Y608942I-290J275D01*
G02X1115428Y608964I1067J1057D01*
G37*
G36*
G01X934720D02*
G03X934726Y608407I290J-275D01*
G02X932570Y608385I-1067J-1057D01*
G03X932564Y608942I-290J275D01*
G02X934720Y608964I1067J1057D01*
G37*
G36*
G01X897909D02*
G03X897915Y608407I290J-275D01*
G02X895759Y608385I-1067J-1057D01*
G03X895753Y608942I-290J275D01*
G02X897909Y608964I1067J1057D01*
G37*
G36*
G01X861098D02*
G03X861104Y608407I290J-275D01*
G02X858948Y608385I-1067J-1057D01*
G03X858942Y608942I-290J275D01*
G02X861098Y608964I1067J1057D01*
G37*
G36*
G01X824287D02*
G03X824293Y608407I290J-275D01*
G02X822137Y608385I-1067J-1057D01*
G03X822131Y608942I-290J275D01*
G02X824287Y608964I1067J1057D01*
G37*
G36*
G01X787476D02*
G03X787482Y608407I290J-275D01*
G02X785326Y608385I-1067J-1057D01*
G03X785320Y608942I-290J275D01*
G02X787476Y608964I1067J1057D01*
G37*
G36*
G01X576254D02*
G03X576260Y608407I290J-275D01*
G02X574104Y608385I-1067J-1057D01*
G03X574098Y608942I-290J275D01*
G02X576254Y608964I1067J1057D01*
G37*
G36*
G01X539443D02*
G03X539449Y608407I290J-275D01*
G02X537293Y608385I-1067J-1057D01*
G03X537287Y608942I-290J275D01*
G02X539443Y608964I1067J1057D01*
G37*
G36*
G01X502632D02*
G03X502638Y608407I290J-275D01*
G02X500482Y608385I-1067J-1057D01*
G03X500476Y608942I-290J275D01*
G02X502632Y608964I1067J1057D01*
G37*
G36*
G01X465820D02*
G03X465826Y608407I290J-275D01*
G02X463670Y608385I-1067J-1057D01*
G03X463664Y608942I-290J275D01*
G02X465820Y608964I1067J1057D01*
G37*
G36*
G01X285112D02*
G03X285118Y608407I290J-275D01*
G02X282962Y608385I-1067J-1057D01*
G03X282956Y608942I-290J275D01*
G02X285112Y608964I1067J1057D01*
G37*
G36*
G01X248301D02*
G03X248307Y608407I290J-275D01*
G02X246151Y608385I-1067J-1057D01*
G03X246145Y608942I-290J275D01*
G02X248301Y608964I1067J1057D01*
G37*
G36*
G01X211490D02*
G03X211496Y608407I290J-275D01*
G02X209340Y608385I-1067J-1057D01*
G03X209334Y608942I-290J275D01*
G02X211490Y608964I1067J1057D01*
G37*
G36*
G01X174679D02*
G03X174685Y608407I290J-275D01*
G02X172529Y608385I-1067J-1057D01*
G03X172523Y608942I-290J275D01*
G02X174679Y608964I1067J1057D01*
G37*
G36*
G01X135718Y608385D02*
G03X135712Y608942I-290J275D01*
G02X137868Y608964I1067J1057D01*
G03X137874Y608407I290J-275D01*
G02X135718Y608385I-1067J-1057D01*
G37*
G36*
G01X1230967Y608719D02*
G03Y608170I291J-274D01*
G02X1228781I-1093J-1030D01*
G03Y608719I-291J274D01*
G02X1230967I1093J1030D01*
G37*
G36*
G01X1194156D02*
G03Y608170I291J-274D01*
G02X1191970I-1093J-1030D01*
G03Y608719I-291J274D01*
G02X1194156I1093J1030D01*
G37*
G36*
G01X1157345D02*
G03Y608170I291J-274D01*
G02X1155159I-1093J-1030D01*
G03Y608719I-291J274D01*
G02X1157345I1093J1030D01*
G37*
G36*
G01X1120533D02*
G03Y608170I291J-274D01*
G02X1118347I-1093J-1030D01*
G03Y608719I-291J274D01*
G02X1120533I1093J1030D01*
G37*
G36*
G01X939825D02*
G03Y608170I291J-274D01*
G02X937639I-1093J-1030D01*
G03Y608719I-291J274D01*
G02X939825I1093J1030D01*
G37*
G36*
G01X903014D02*
G03Y608170I291J-274D01*
G02X900828I-1093J-1030D01*
G03Y608719I-291J274D01*
G02X903014I1093J1030D01*
G37*
G36*
G01X866203D02*
G03Y608170I291J-274D01*
G02X864017I-1093J-1030D01*
G03Y608719I-291J274D01*
G02X866203I1093J1030D01*
G37*
G36*
G01X829392D02*
G03Y608170I291J-274D01*
G02X827206I-1093J-1030D01*
G03Y608719I-291J274D01*
G02X829392I1093J1030D01*
G37*
G36*
G01X792581D02*
G03Y608170I291J-274D01*
G02X790395I-1093J-1030D01*
G03Y608719I-291J274D01*
G02X792581I1093J1030D01*
G37*
G36*
G01X581359D02*
G03Y608170I291J-274D01*
G02X579173I-1093J-1030D01*
G03Y608719I-291J274D01*
G02X581359I1093J1030D01*
G37*
G36*
G01X544548D02*
G03Y608170I291J-274D01*
G02X542362I-1093J-1030D01*
G03Y608719I-291J274D01*
G02X544548I1093J1030D01*
G37*
G36*
G01X507737D02*
G03Y608170I291J-274D01*
G02X505551I-1093J-1030D01*
G03Y608719I-291J274D01*
G02X507737I1093J1030D01*
G37*
G36*
G01X470925D02*
G03X470926Y608171I292J-273D01*
G02X468740Y608170I-1093J-1031D01*
G03X468739Y608718I-292J273D01*
G02X470925Y608719I1093J1031D01*
G37*
G36*
G01X290217D02*
G03Y608170I291J-274D01*
G02X288031I-1093J-1030D01*
G03Y608719I-291J274D01*
G02X290217I1093J1030D01*
G37*
G36*
G01X253406D02*
G03Y608170I291J-274D01*
G02X251220I-1093J-1030D01*
G03Y608719I-291J274D01*
G02X253406I1093J1030D01*
G37*
G36*
G01X216595D02*
G03Y608170I291J-274D01*
G02X214409I-1093J-1030D01*
G03Y608719I-291J274D01*
G02X216595I1093J1030D01*
G37*
G36*
G01X179784D02*
G03Y608170I291J-274D01*
G02X177598I-1093J-1030D01*
G03Y608719I-291J274D01*
G02X179784I1093J1030D01*
G37*
G36*
G01X142973D02*
G03Y608170I291J-274D01*
G02X140787I-1093J-1030D01*
G03Y608719I-291J274D01*
G02X142973I1093J1030D01*
G37*
G36*
G01X1545090Y606559D02*
G03X1545469Y606114I397J-46D01*
G02X1544014Y604873I-62J-1401D01*
G03X1543635Y605318I-397J46D01*
G02X1542337Y606379I62J1401D01*
G03X1541774Y606642I-388J-97D01*
G02X1542522Y608243I-612J1261D01*
G03X1543085Y607980I388J97D01*
G02X1545090Y606559I612J-1261D01*
G37*
G36*
G01X1605380Y608460D02*
Y604365D01*
X1605371Y604281D01*
G02X1602358Y604450I-1502J169D01*
G01Y608451D01*
G02X1605380Y608460I1511J-1D01*
G37*
G36*
G01X1659880Y606260D02*
Y602165D01*
X1659871Y602081D01*
G02X1656858Y602250I-1502J169D01*
G01Y606251D01*
G02X1659880Y606260I1511J-1D01*
G37*
G36*
G01X1572237Y600367D02*
G03X1571718Y600360I-255J-308D01*
G02X1571683Y602796I-1058J1203D01*
G03X1572202Y602803I255J308D01*
G02X1572237Y600367I1058J-1203D01*
G37*
G36*
G01X1804772Y601902D02*
G03X1804178Y601662I-207J-342D01*
G02X1803850Y604145I-3193J841D01*
G03X1804486Y604068I347J199D01*
G02X1804772Y601902I1014J-968D01*
G37*
G36*
G01X1614860Y603260D02*
Y599165D01*
X1614851Y599081D01*
G02X1611838Y599250I-1502J169D01*
G01Y603251D01*
G02X1614860Y603260I1511J-1D01*
G37*
G36*
G01X1325210Y599127D02*
G03Y598573I288J-277D01*
G02X1323190I-1010J-973D01*
G03Y599127I-288J277D01*
G02X1323229Y601111I1010J973D01*
G03Y601689I-277J289D01*
G02X1323154Y603634I971J1011D01*
G03Y604166I-298J266D01*
G02Y606034I1046J934D01*
G03Y606566I-298J266D01*
G02X1323229Y608511I1046J934D01*
G03Y609089I-277J289D01*
G02X1325171I971J1011D01*
G03Y608511I277J-289D01*
G02X1325246Y606566I-971J-1011D01*
G03Y606034I298J-266D01*
G02Y604166I-1046J-934D01*
G03Y603634I298J-266D01*
G02X1325171Y601689I-1046J-934D01*
G03Y601111I277J-289D01*
G02X1325210Y599127I-971J-1011D01*
G37*
G36*
G01X713010Y598527D02*
G03Y597973I288J-277D01*
G02X710990I-1010J-973D01*
G03Y598527I-288J277D01*
G02X713010I1010J973D01*
G37*
G36*
G01X1589293Y595924D02*
G03X1588711Y595918I-288J-277D01*
G02X1586692Y595871I-1032J949D01*
G03X1586137Y595879I-282J-284D01*
G02X1586166Y597898I-958J1023D01*
G03X1586721Y597890I282J284D01*
G02X1588690Y597839I959J-1023D01*
G03X1589272Y597845I288J277D01*
G02X1589293Y595924I1032J-949D01*
G37*
G36*
G01X709771Y598289D02*
G03Y597711I277J-289D01*
G02X707829I-971J-1011D01*
G03Y598289I-277J289D01*
G02X709771I971J1011D01*
G37*
G36*
G01X1637045Y601610D02*
X1637046Y601608D01*
X1639942Y596203D01*
X1639943Y596201D01*
G02X1635798Y593980I-2045J-1162D01*
G01X1635797Y593982D01*
X1632901Y599387D01*
X1632900Y599389D01*
G02X1637045Y601610I2045J1162D01*
G37*
G36*
G01X1628179Y601625D02*
X1628180Y601624D01*
X1631092Y596187D01*
X1631093Y596185D01*
G02X1626947Y593965I-2054J-1146D01*
G01X1626946Y593966D01*
X1624034Y599403D01*
X1624033Y599405D01*
G02X1628179Y601625I2054J1146D01*
G37*
G36*
G01X1654010Y597960D02*
Y593865D01*
X1654001Y593781D01*
G02X1650988Y593950I-1502J169D01*
G01Y597951D01*
G02X1654010Y597960I1511J-1D01*
G37*
G36*
G01X869174Y594782D02*
Y602284D01*
X871376D01*
Y594782D01*
G02X869174I-1101J-1021D01*
G37*
G36*
G01X219566D02*
Y602284D01*
X221768D01*
Y594782D01*
G02X219566I-1101J-1021D01*
G37*
G36*
G01X1240630Y594778D02*
Y602284D01*
X1242834D01*
Y594778D01*
G02X1240630I-1102J-1021D01*
G37*
G36*
G01X1233938D02*
Y602284D01*
X1236140D01*
Y594778D01*
G02X1233938I-1101J-1021D01*
G37*
G36*
G01X1217204Y594777D02*
Y602284D01*
X1219408D01*
Y594779D01*
G02X1217204Y594777I-1101J-1022D01*
G37*
G36*
G01X1210512D02*
Y602284D01*
X1212714D01*
Y594779D01*
G02X1210512Y594777I-1100J-1022D01*
G37*
G36*
G01X1203820Y594778D02*
Y602284D01*
X1206022D01*
Y594778D01*
G02X1203820I-1101J-1021D01*
G37*
G36*
G01X1197126D02*
Y602284D01*
X1199330D01*
Y594778D01*
G02X1197126I-1102J-1021D01*
G37*
G36*
G01X1180394Y594777D02*
Y602284D01*
X1182596D01*
Y594779D01*
G02X1180394Y594777I-1100J-1022D01*
G37*
G36*
G01X1173700D02*
Y602284D01*
X1175904D01*
Y594779D01*
G02X1173700Y594777I-1101J-1022D01*
G37*
G36*
G01X1167008Y594778D02*
Y602284D01*
X1169212D01*
Y594778D01*
G02X1167008I-1102J-1021D01*
G37*
G36*
G01X1160316D02*
Y602284D01*
X1162518D01*
Y594778D01*
G02X1160316I-1101J-1021D01*
G37*
G36*
G01X1143582Y594777D02*
Y602284D01*
X1145786D01*
Y594779D01*
G02X1143582Y594777I-1101J-1022D01*
G37*
G36*
G01X1136890D02*
Y602284D01*
X1139092D01*
Y594779D01*
G02X1136890Y594777I-1100J-1022D01*
G37*
G36*
G01X1130198Y594778D02*
Y602284D01*
X1132400D01*
Y594778D01*
G02X1130198I-1101J-1021D01*
G37*
G36*
G01X1123504D02*
Y602284D01*
X1125708D01*
Y594778D01*
G02X1123504I-1102J-1021D01*
G37*
G36*
G01X1106772Y594777D02*
Y602284D01*
X1108974D01*
Y594779D01*
G02X1106772Y594777I-1100J-1022D01*
G37*
G36*
G01X1100078D02*
Y602284D01*
X1102282D01*
Y594779D01*
G02X1100078Y594777I-1101J-1022D01*
G37*
G36*
G01X949490Y594779D02*
Y602284D01*
X951692D01*
Y594777D01*
G02X949490Y594779I-1102J-1020D01*
G37*
G36*
G01X942796Y594778D02*
Y602284D01*
X944998D01*
Y594778D01*
G02X942796I-1101J-1021D01*
G37*
G36*
G01X926064D02*
Y602284D01*
X928266D01*
Y594778D01*
G02X926064I-1101J-1021D01*
G37*
G36*
G01X919370D02*
Y602284D01*
X921574D01*
Y594778D01*
G02X919370I-1102J-1021D01*
G37*
G36*
G01X912678D02*
Y602284D01*
X914880D01*
Y594778D01*
G02X912678I-1101J-1021D01*
G37*
G36*
G01X905984D02*
Y602284D01*
X908188D01*
Y594778D01*
G02X905984I-1102J-1021D01*
G37*
G36*
G01X889252D02*
Y602284D01*
X891456D01*
Y594778D01*
G02X889252I-1102J-1021D01*
G37*
G36*
G01X882560D02*
Y602284D01*
X884762D01*
Y594778D01*
G02X882560I-1101J-1021D01*
G37*
G36*
G01X875866D02*
Y602284D01*
X878070D01*
Y594778D01*
G02X875866I-1102J-1021D01*
G37*
G36*
G01X852442D02*
Y602284D01*
X854644D01*
Y594778D01*
G02X852442I-1101J-1021D01*
G37*
G36*
G01X845748D02*
Y602284D01*
X847952D01*
Y594778D01*
G02X845748I-1102J-1021D01*
G37*
G36*
G01X839056D02*
Y602284D01*
X841258D01*
Y594778D01*
G02X839056I-1101J-1021D01*
G37*
G36*
G01X832362D02*
Y602284D01*
X834566D01*
Y594778D01*
G02X832362I-1102J-1021D01*
G37*
G36*
G01X815630D02*
Y602284D01*
X817834D01*
Y594778D01*
G02X815630I-1102J-1021D01*
G37*
G36*
G01X808938D02*
Y602284D01*
X811140D01*
Y594778D01*
G02X808938I-1101J-1021D01*
G37*
G36*
G01X802244D02*
Y602284D01*
X804448D01*
Y594778D01*
G02X802244I-1102J-1021D01*
G37*
G36*
G01X795552D02*
Y602284D01*
X797754D01*
Y594778D01*
G02X795552I-1101J-1021D01*
G37*
G36*
G01X778820D02*
Y602284D01*
X781022D01*
Y594778D01*
G02X778820I-1101J-1021D01*
G37*
G36*
G01X772126D02*
Y602284D01*
X774330D01*
Y594778D01*
G02X772126I-1102J-1021D01*
G37*
G36*
G01X591022D02*
Y602284D01*
X593226D01*
Y594778D01*
G02X591022I-1102J-1021D01*
G37*
G36*
G01X584330D02*
Y602284D01*
X586532D01*
Y594778D01*
G02X584330I-1101J-1021D01*
G37*
G36*
G01X567596Y594777D02*
Y602284D01*
X569800D01*
Y594779D01*
G02X567596Y594777I-1101J-1022D01*
G37*
G36*
G01X560904D02*
Y602284D01*
X563106D01*
Y594779D01*
G02X560904Y594777I-1100J-1022D01*
G37*
G36*
G01X554212Y594778D02*
Y602284D01*
X556414D01*
Y594778D01*
G02X554212I-1101J-1021D01*
G37*
G36*
G01X547518D02*
Y602284D01*
X549722D01*
Y594778D01*
G02X547518I-1102J-1021D01*
G37*
G36*
G01X530786Y594777D02*
Y602284D01*
X532988D01*
Y594779D01*
G02X530786Y594777I-1100J-1022D01*
G37*
G36*
G01X524092D02*
Y602284D01*
X526296D01*
Y594779D01*
G02X524092Y594777I-1101J-1022D01*
G37*
G36*
G01X517400Y594778D02*
Y602284D01*
X519604D01*
Y594778D01*
G02X517400I-1102J-1021D01*
G37*
G36*
G01X510708D02*
Y602284D01*
X512910D01*
Y594778D01*
G02X510708I-1101J-1021D01*
G37*
G36*
G01X493974Y594777D02*
Y602284D01*
X496178D01*
Y594779D01*
G02X493974Y594777I-1101J-1022D01*
G37*
G36*
G01X487282D02*
Y602284D01*
X489484D01*
Y594779D01*
G02X487282Y594777I-1100J-1022D01*
G37*
G36*
G01X480590Y594778D02*
Y602284D01*
X482792D01*
Y594778D01*
G02X480590I-1101J-1021D01*
G37*
G36*
G01X473896D02*
Y602284D01*
X476100D01*
Y594778D01*
G02X473896I-1102J-1021D01*
G37*
G36*
G01X457164Y594777D02*
Y602284D01*
X459366D01*
Y594779D01*
G02X457164Y594777I-1100J-1022D01*
G37*
G36*
G01X450470D02*
Y602284D01*
X452674D01*
Y594779D01*
G02X450470Y594777I-1101J-1022D01*
G37*
G36*
G01X299882Y594779D02*
Y602284D01*
X302084D01*
Y594777D01*
G02X299882Y594779I-1102J-1020D01*
G37*
G36*
G01X293188Y594778D02*
Y602284D01*
X295390D01*
Y594778D01*
G02X293188I-1101J-1021D01*
G37*
G36*
G01X276456D02*
Y602284D01*
X278658D01*
Y594778D01*
G02X276456I-1101J-1021D01*
G37*
G36*
G01X269762D02*
Y602284D01*
X271966D01*
Y594778D01*
G02X269762I-1102J-1021D01*
G37*
G36*
G01X263070D02*
Y602284D01*
X265272D01*
Y594778D01*
G02X263070I-1101J-1021D01*
G37*
G36*
G01X256376D02*
Y602284D01*
X258580D01*
Y594778D01*
G02X256376I-1102J-1021D01*
G37*
G36*
G01X239644D02*
Y602284D01*
X241848D01*
Y594778D01*
G02X239644I-1102J-1021D01*
G37*
G36*
G01X232952D02*
Y602284D01*
X235154D01*
Y594778D01*
G02X232952I-1101J-1021D01*
G37*
G36*
G01X226258D02*
Y602284D01*
X228462D01*
Y594778D01*
G02X226258I-1102J-1021D01*
G37*
G36*
G01X202834D02*
Y602284D01*
X205036D01*
Y594778D01*
G02X202834I-1101J-1021D01*
G37*
G36*
G01X196140D02*
Y602284D01*
X198344D01*
Y594778D01*
G02X196140I-1102J-1021D01*
G37*
G36*
G01X189448D02*
Y602284D01*
X191650D01*
Y594778D01*
G02X189448I-1101J-1021D01*
G37*
G36*
G01X182754D02*
Y602284D01*
X184958D01*
Y594778D01*
G02X182754I-1102J-1021D01*
G37*
G36*
G01X166022D02*
Y602284D01*
X168226D01*
Y594778D01*
G02X166022I-1102J-1021D01*
G37*
G36*
G01X159330D02*
Y602284D01*
X161532D01*
Y594778D01*
G02X159330I-1101J-1021D01*
G37*
G36*
G01X152636D02*
Y602284D01*
X154840D01*
Y594778D01*
G02X152636I-1102J-1021D01*
G37*
G36*
G01X145944D02*
Y602284D01*
X148146D01*
Y594778D01*
G02X145944I-1101J-1021D01*
G37*
G36*
G01X129212D02*
Y602284D01*
X131414D01*
Y594778D01*
G02X129212I-1101J-1021D01*
G37*
G36*
G01X122518D02*
Y602284D01*
X124722D01*
Y594778D01*
G02X122518I-1102J-1021D01*
G37*
G36*
G01X754907Y592660D02*
G03X754330Y592649I-283J-282D01*
G02X754293Y594590I-1030J951D01*
G03X754870Y594601I283J282D01*
G02X754907Y592660I1030J-951D01*
G37*
G36*
G01X1801343Y595110D02*
G03X1801349Y594538I283J-283D01*
G02X1799387Y594518I-971J-1011D01*
G03X1799381Y595090I-283J283D01*
G02X1801343Y595110I971J1011D01*
G37*
G36*
G01X1710951Y594470D02*
G03X1710940Y593893I271J-294D01*
G02X1708999Y593930I-990J-993D01*
G03X1709010Y594507I-271J294D01*
G02X1710951Y594470I990J993D01*
G37*
G36*
G01X1605430Y596760D02*
Y592665D01*
X1605421Y592581D01*
G02X1602408Y592750I-1502J169D01*
G01Y596751D01*
G02X1605430Y596760I1511J-1D01*
G37*
G36*
G01X1718962Y593631D02*
G03X1718956Y593035I264J-301D01*
G02X1717083Y593055I-948J-1033D01*
G03X1717089Y593651I-264J301D01*
G02X1717027Y595657I948J1033D01*
G03Y596211I-288J277D01*
G02X1719047I1010J973D01*
G03Y595657I288J-277D01*
G02X1718962Y593631I-1010J-972D01*
G37*
G36*
G01X1554589Y590129D02*
G03X1554011I-289J-277D01*
G02Y592071I-1011J971D01*
G03X1554589I289J277D01*
G02Y590129I1011J-971D01*
G37*
G36*
G01X648104Y592592D02*
G03X648419Y592084I383J-114D01*
G02X646836Y591102I-239J-1382D01*
G03X646521Y591610I-383J114D01*
G02X645381Y592738I239J1382D01*
G03X644880Y593050I-393J-73D01*
G02X645879Y594654I-380J1350D01*
G03X646380Y594342I393J73D01*
G02X648104Y592592I380J-1350D01*
G37*
G36*
G01X2515Y591438D02*
G03X2495Y590851I262J-303D01*
G02X516Y590968I-1056J-1068D01*
G03X566Y591554I-245J316D01*
G02X506Y591623I1027J954D01*
G03X194I-156J-125D01*
G02X73Y593510I-1094J877D01*
G03X627I277J288D01*
G02X2515Y591438I973J-1010D01*
G37*
G36*
G01X1763216Y590944D02*
G03Y590666I144J-139D01*
G02X1760908I-1154J-1111D01*
G03Y590944I-144J139D01*
G02X1763216I1154J1111D01*
G37*
G36*
G01X1230970Y590087D02*
G03Y589541I292J-273D01*
G02X1228778I-1096J-1027D01*
G03Y590087I-292J273D01*
G02X1230970I1096J1027D01*
G37*
G36*
G01X1194159D02*
G03Y589541I292J-273D01*
G02X1191967I-1096J-1027D01*
G03Y590087I-292J273D01*
G02X1194159I1096J1027D01*
G37*
G36*
G01X1157348D02*
G03Y589541I292J-273D01*
G02X1155156I-1096J-1027D01*
G03Y590087I-292J273D01*
G02X1157348I1096J1027D01*
G37*
G36*
G01X1120536D02*
G03Y589541I292J-273D01*
G02X1118344I-1096J-1027D01*
G03Y590087I-292J273D01*
G02X1120536I1096J1027D01*
G37*
G36*
G01X939828D02*
G03Y589541I292J-273D01*
G02X937636I-1096J-1027D01*
G03Y590087I-292J273D01*
G02X939828I1096J1027D01*
G37*
G36*
G01X903017D02*
G03Y589541I292J-273D01*
G02X900825I-1096J-1027D01*
G03Y590087I-292J273D01*
G02X903017I1096J1027D01*
G37*
G36*
G01X866206D02*
G03Y589541I292J-273D01*
G02X864014I-1096J-1027D01*
G03Y590087I-292J273D01*
G02X866206I1096J1027D01*
G37*
G36*
G01X829395D02*
G03Y589541I292J-273D01*
G02X827203I-1096J-1027D01*
G03Y590087I-292J273D01*
G02X829395I1096J1027D01*
G37*
G36*
G01X792584D02*
G03Y589541I292J-273D01*
G02X790392I-1096J-1027D01*
G03Y590087I-292J273D01*
G02X792584I1096J1027D01*
G37*
G36*
G01X581362D02*
G03Y589541I292J-273D01*
G02X579170I-1096J-1027D01*
G03Y590087I-292J273D01*
G02X581362I1096J1027D01*
G37*
G36*
G01X544551D02*
G03Y589541I292J-273D01*
G02X542359I-1096J-1027D01*
G03Y590087I-292J273D01*
G02X544551I1096J1027D01*
G37*
G36*
G01X507740D02*
G03Y589541I292J-273D01*
G02X505548I-1096J-1027D01*
G03Y590087I-292J273D01*
G02X507740I1096J1027D01*
G37*
G36*
G01X470928D02*
G03Y589541I292J-273D01*
G02X468736I-1096J-1027D01*
G03Y590087I-292J273D01*
G02X470928I1096J1027D01*
G37*
G36*
G01X290220D02*
G03Y589541I292J-273D01*
G02X288028I-1096J-1027D01*
G03Y590087I-292J273D01*
G02X290220I1096J1027D01*
G37*
G36*
G01X253409D02*
G03Y589541I292J-273D01*
G02X251217I-1096J-1027D01*
G03Y590087I-292J273D01*
G02X253409I1096J1027D01*
G37*
G36*
G01X216598D02*
G03Y589541I292J-273D01*
G02X214406I-1096J-1027D01*
G03Y590087I-292J273D01*
G02X216598I1096J1027D01*
G37*
G36*
G01X179787D02*
G03Y589541I292J-273D01*
G02X177595I-1096J-1027D01*
G03Y590087I-292J273D01*
G02X179787I1096J1027D01*
G37*
G36*
G01X142976D02*
G03Y589541I292J-273D01*
G02X140784I-1096J-1027D01*
G03Y590087I-292J273D01*
G02X142976I1096J1027D01*
G37*
G36*
G01X1225870Y589873D02*
G03Y589327I292J-273D01*
G02X1223678I-1096J-1027D01*
G03Y589873I-292J273D01*
G02X1225870I1096J1027D01*
G37*
G36*
G01X1189059D02*
G03Y589327I292J-273D01*
G02X1186867I-1096J-1027D01*
G03Y589873I-292J273D01*
G02X1189059I1096J1027D01*
G37*
G36*
G01X1152248D02*
G03Y589327I292J-273D01*
G02X1150056I-1096J-1027D01*
G03Y589873I-292J273D01*
G02X1152248I1096J1027D01*
G37*
G36*
G01X1115436D02*
G03Y589327I292J-273D01*
G02X1113244I-1096J-1027D01*
G03Y589873I-292J273D01*
G02X1115436I1096J1027D01*
G37*
G36*
G01X934728D02*
G03Y589327I292J-273D01*
G02X932536I-1096J-1027D01*
G03Y589873I-292J273D01*
G02X934728I1096J1027D01*
G37*
G36*
G01X897917D02*
G03Y589327I292J-273D01*
G02X895725I-1096J-1027D01*
G03Y589873I-292J273D01*
G02X897917I1096J1027D01*
G37*
G36*
G01X861106D02*
G03Y589327I292J-273D01*
G02X858914I-1096J-1027D01*
G03Y589873I-292J273D01*
G02X861106I1096J1027D01*
G37*
G36*
G01X824295D02*
G03Y589327I292J-273D01*
G02X822103I-1096J-1027D01*
G03Y589873I-292J273D01*
G02X824295I1096J1027D01*
G37*
G36*
G01X787484D02*
G03Y589327I292J-273D01*
G02X785292I-1096J-1027D01*
G03Y589873I-292J273D01*
G02X787484I1096J1027D01*
G37*
G36*
G01X576262D02*
G03Y589327I292J-273D01*
G02X574070I-1096J-1027D01*
G03Y589873I-292J273D01*
G02X576262I1096J1027D01*
G37*
G36*
G01X539451D02*
G03Y589327I292J-273D01*
G02X537259I-1096J-1027D01*
G03Y589873I-292J273D01*
G02X539451I1096J1027D01*
G37*
G36*
G01X502640D02*
G03Y589327I292J-273D01*
G02X500448I-1096J-1027D01*
G03Y589873I-292J273D01*
G02X502640I1096J1027D01*
G37*
G36*
G01X465828D02*
G03Y589327I292J-273D01*
G02X463636I-1096J-1027D01*
G03Y589873I-292J273D01*
G02X465828I1096J1027D01*
G37*
G36*
G01X285120D02*
G03Y589327I292J-273D01*
G02X282928I-1096J-1027D01*
G03Y589873I-292J273D01*
G02X285120I1096J1027D01*
G37*
G36*
G01X248309D02*
G03Y589327I292J-273D01*
G02X246117I-1096J-1027D01*
G03Y589873I-292J273D01*
G02X248309I1096J1027D01*
G37*
G36*
G01X211498D02*
G03Y589327I292J-273D01*
G02X209306I-1096J-1027D01*
G03Y589873I-292J273D01*
G02X211498I1096J1027D01*
G37*
G36*
G01X174687D02*
G03Y589327I292J-273D01*
G02X172495I-1096J-1027D01*
G03Y589873I-292J273D01*
G02X174687I1096J1027D01*
G37*
G36*
G01X137876D02*
G03Y589327I292J-273D01*
G02X135684I-1096J-1027D01*
G03Y589873I-292J273D01*
G02X137876I1096J1027D01*
G37*
G36*
G01X1662192Y590760D02*
Y586665D01*
X1662182Y586581D01*
G02X1659168Y586750I-1502J169D01*
G01Y590751D01*
G02X1662192Y590760I1512J-1D01*
G37*
G36*
G01X1419447Y585240D02*
G03X1418893I-277J-288D01*
G02X1416824Y585375I-973J1010D01*
G03X1416215Y585394I-313J-249D01*
G02X1414200Y585322I-1042J938D01*
G03X1413646I-277J-288D01*
G02Y587342I-973J1010D01*
G03X1414200I277J288D01*
G02X1416269Y587207I973J-1010D01*
G03X1416878Y587188I313J249D01*
G02X1418893Y587260I1042J-938D01*
G03X1419447I277J288D01*
G02X1421393I973J-1010D01*
G03X1421947I277J288D01*
G02Y585240I973J-1010D01*
G03X1421393I-277J-288D01*
G02X1419447I-973J1010D01*
G37*
G36*
G01X1544189Y584753D02*
G03X1543611I-289J-277D01*
G02Y586695I-1011J971D01*
G03X1544189I289J277D01*
G02Y584753I1011J-971D01*
G37*
G36*
G01X1372689Y583685D02*
G03X1372111I-289J-277D01*
G02Y585627I-1011J971D01*
G03X1372689I289J277D01*
G02Y583685I1011J-971D01*
G37*
G36*
G01X1815255Y582948D02*
G03X1814679Y582814I-227J-329D01*
G02X1814253Y584653I-1223J686D01*
G03X1814829Y584787I227J329D01*
G02X1815255Y582948I1223J-686D01*
G37*
G36*
G01X1731818Y580896D02*
G03X1732393Y580876I297J267D01*
G02X1732324Y578932I975J-1008D01*
G03X1731749Y578952I-297J-267D01*
G02X1731818Y580896I-975J1008D01*
G37*
G36*
G01X1294692Y581162D02*
G03X1295092Y580762I400J0D01*
G02X1293688Y579358I-2J-1402D01*
G03X1293288Y579758I-400J0D01*
G02X1294692Y581162I2J1402D01*
G37*
G36*
G01X1684289Y586650D02*
X1684290Y586648D01*
X1687186Y581243D01*
X1687187Y581241D01*
G02X1683042Y579020I-2045J-1162D01*
G01X1683041Y579022D01*
X1680145Y584427D01*
X1680144Y584429D01*
G02X1684289Y586650I2045J1162D01*
G37*
G36*
G01X1675423Y586665D02*
X1675424Y586664D01*
X1678336Y581227D01*
X1678337Y581225D01*
G02X1674191Y579005I-2054J-1146D01*
G01X1674190Y579006D01*
X1671278Y584443D01*
X1671277Y584445D01*
G02X1675423Y586665I2054J1146D01*
G37*
G36*
G01X1637045Y586650D02*
X1637046Y586648D01*
X1639942Y581243D01*
X1639943Y581241D01*
G02X1635798Y579020I-2045J-1162D01*
G01X1635797Y579022D01*
X1632901Y584427D01*
X1632900Y584429D01*
G02X1637045Y586650I2045J1162D01*
G37*
G36*
G01X1628179Y586665D02*
X1628180Y586664D01*
X1631092Y581227D01*
X1631093Y581225D01*
G02X1626947Y579005I-2054J-1146D01*
G01X1626946Y579006D01*
X1624034Y584443D01*
X1624033Y584445D01*
G02X1628179Y586665I2054J1146D01*
G37*
G36*
G01X410550Y587511D02*
Y587462D01*
G03X411053Y587076I400J1D01*
G02X410869Y584431I363J-1354D01*
G01X410745Y584484D01*
X409011Y582750D01*
X405824D01*
Y577072D01*
X403620D01*
Y582750D01*
X402478D01*
Y577072D01*
X400274D01*
Y582750D01*
X395784D01*
Y577072D01*
X393582D01*
Y582958D01*
X392250Y584289D01*
Y588811D01*
X393432Y589993D01*
G02X394025Y590240I558J-504D01*
G01X406157D01*
X407647Y588750D01*
X409311D01*
X410550Y587511D01*
G37*
G36*
G01X1607506Y582510D02*
Y578415D01*
X1607496Y578331D01*
G02X1604482Y578500I-1502J169D01*
G01Y582501D01*
G02X1607506Y582510I1512J-1D01*
G37*
G36*
G01X1654180Y582360D02*
Y578265D01*
X1654171Y578181D01*
G02X1651158Y578350I-1502J169D01*
G01Y582351D01*
G02X1654180Y582360I1511J-1D01*
G37*
G36*
G01X651238Y573438D02*
G03X650696Y573413I-257J-306D01*
G02X648729Y575411I-996J987D01*
G03Y575989I-277J289D01*
G02X650645Y578036I971J1011D01*
G03X651186Y578039I269J296D01*
G02X653150Y576038I954J-1028D01*
G03Y575484I288J-277D01*
G02X651238Y573438I-1009J-973D01*
G37*
G36*
G01X664689Y573229D02*
G03X664111I-289J-277D01*
G02Y575171I-1011J971D01*
G03X664689I289J277D01*
G02Y573229I1011J-971D01*
G37*
G36*
G01X1772522Y574592D02*
G03X1772110Y574142I-15J-400D01*
G02X1770775Y575365I-1391J-178D01*
G03X1771187Y575815I15J400D01*
G02X1772522Y574592I1391J178D01*
G37*
G36*
G01X660489Y568829D02*
G03X659911I-289J-277D01*
G02Y570771I-1011J971D01*
G03X660489I289J277D01*
G02Y568829I1011J-971D01*
G37*
G36*
G01X1225862Y571164D02*
G03X1225868Y570607I290J-275D01*
G02X1223712Y570585I-1067J-1057D01*
G03X1223706Y571142I-290J275D01*
G02X1225862Y571164I1067J1057D01*
G37*
G36*
G01X1189051D02*
G03X1189057Y570607I290J-275D01*
G02X1186901Y570585I-1067J-1057D01*
G03X1186895Y571142I-290J275D01*
G02X1189051Y571164I1067J1057D01*
G37*
G36*
G01X1152240D02*
G03X1152246Y570607I290J-275D01*
G02X1150090Y570585I-1067J-1057D01*
G03X1150084Y571142I-290J275D01*
G02X1152240Y571164I1067J1057D01*
G37*
G36*
G01X1115428D02*
G03X1115434Y570607I290J-275D01*
G02X1113278Y570585I-1067J-1057D01*
G03X1113272Y571142I-290J275D01*
G02X1115428Y571164I1067J1057D01*
G37*
G36*
G01X934720D02*
G03X934726Y570607I290J-275D01*
G02X932570Y570585I-1067J-1057D01*
G03X932564Y571142I-290J275D01*
G02X934720Y571164I1067J1057D01*
G37*
G36*
G01X897909D02*
G03X897915Y570607I290J-275D01*
G02X895759Y570585I-1067J-1057D01*
G03X895753Y571142I-290J275D01*
G02X897909Y571164I1067J1057D01*
G37*
G36*
G01X861098D02*
G03X861104Y570607I290J-275D01*
G02X858948Y570585I-1067J-1057D01*
G03X858942Y571142I-290J275D01*
G02X861098Y571164I1067J1057D01*
G37*
G36*
G01X824287D02*
G03X824293Y570607I290J-275D01*
G02X822137Y570585I-1067J-1057D01*
G03X822131Y571142I-290J275D01*
G02X824287Y571164I1067J1057D01*
G37*
G36*
G01X787476D02*
G03X787482Y570607I290J-275D01*
G02X785326Y570585I-1067J-1057D01*
G03X785320Y571142I-290J275D01*
G02X787476Y571164I1067J1057D01*
G37*
G36*
G01X576254D02*
G03X576260Y570607I290J-275D01*
G02X574104Y570585I-1067J-1057D01*
G03X574098Y571142I-290J275D01*
G02X576254Y571164I1067J1057D01*
G37*
G36*
G01X539443D02*
G03X539449Y570607I290J-275D01*
G02X537293Y570585I-1067J-1057D01*
G03X537287Y571142I-290J275D01*
G02X539443Y571164I1067J1057D01*
G37*
G36*
G01X502632D02*
G03X502638Y570607I290J-275D01*
G02X500482Y570585I-1067J-1057D01*
G03X500476Y571142I-290J275D01*
G02X502632Y571164I1067J1057D01*
G37*
G36*
G01X465820D02*
G03X465826Y570607I290J-275D01*
G02X463670Y570585I-1067J-1057D01*
G03X463664Y571142I-290J275D01*
G02X465820Y571164I1067J1057D01*
G37*
G36*
G01X285112D02*
G03X285118Y570607I290J-275D01*
G02X282962Y570585I-1067J-1057D01*
G03X282956Y571142I-290J275D01*
G02X285112Y571164I1067J1057D01*
G37*
G36*
G01X248301D02*
G03X248307Y570607I290J-275D01*
G02X246151Y570585I-1067J-1057D01*
G03X246145Y571142I-290J275D01*
G02X248301Y571164I1067J1057D01*
G37*
G36*
G01X211490D02*
G03X211496Y570607I290J-275D01*
G02X209340Y570585I-1067J-1057D01*
G03X209334Y571142I-290J275D01*
G02X211490Y571164I1067J1057D01*
G37*
G36*
G01X174679D02*
G03X174685Y570607I290J-275D01*
G02X172529Y570585I-1067J-1057D01*
G03X172523Y571142I-290J275D01*
G02X174679Y571164I1067J1057D01*
G37*
G36*
G01X135718Y570585D02*
G03X135712Y571142I-290J275D01*
G02X137868Y571164I1067J1057D01*
G03X137874Y570607I290J-275D01*
G02X135718Y570585I-1067J-1057D01*
G37*
G36*
G01X1230967Y570919D02*
G03Y570370I291J-274D01*
G02X1228781I-1093J-1030D01*
G03Y570919I-291J274D01*
G02X1230967I1093J1030D01*
G37*
G36*
G01X1194156D02*
G03Y570370I291J-274D01*
G02X1191970I-1093J-1030D01*
G03Y570919I-291J274D01*
G02X1194156I1093J1030D01*
G37*
G36*
G01X1157345D02*
G03Y570370I291J-274D01*
G02X1155159I-1093J-1030D01*
G03Y570919I-291J274D01*
G02X1157345I1093J1030D01*
G37*
G36*
G01X1120533D02*
G03Y570370I291J-274D01*
G02X1118347I-1093J-1030D01*
G03Y570919I-291J274D01*
G02X1120533I1093J1030D01*
G37*
G36*
G01X939825D02*
G03Y570370I291J-274D01*
G02X937639I-1093J-1030D01*
G03Y570919I-291J274D01*
G02X939825I1093J1030D01*
G37*
G36*
G01X903014D02*
G03Y570370I291J-274D01*
G02X900828I-1093J-1030D01*
G03Y570919I-291J274D01*
G02X903014I1093J1030D01*
G37*
G36*
G01X866203D02*
G03Y570370I291J-274D01*
G02X864017I-1093J-1030D01*
G03Y570919I-291J274D01*
G02X866203I1093J1030D01*
G37*
G36*
G01X829392D02*
G03Y570370I291J-274D01*
G02X827206I-1093J-1030D01*
G03Y570919I-291J274D01*
G02X829392I1093J1030D01*
G37*
G36*
G01X792581D02*
G03Y570370I291J-274D01*
G02X790395I-1093J-1030D01*
G03Y570919I-291J274D01*
G02X792581I1093J1030D01*
G37*
G36*
G01X581359D02*
G03Y570370I291J-274D01*
G02X579173I-1093J-1030D01*
G03Y570919I-291J274D01*
G02X581359I1093J1030D01*
G37*
G36*
G01X544548D02*
G03Y570370I291J-274D01*
G02X542362I-1093J-1030D01*
G03Y570919I-291J274D01*
G02X544548I1093J1030D01*
G37*
G36*
G01X507737D02*
G03Y570370I291J-274D01*
G02X505551I-1093J-1030D01*
G03Y570919I-291J274D01*
G02X507737I1093J1030D01*
G37*
G36*
G01X470925D02*
G03Y570370I291J-274D01*
G02X468739I-1093J-1030D01*
G03Y570919I-291J274D01*
G02X470925I1093J1030D01*
G37*
G36*
G01X290217D02*
G03Y570370I291J-274D01*
G02X288031I-1093J-1030D01*
G03Y570919I-291J274D01*
G02X290217I1093J1030D01*
G37*
G36*
G01X253406D02*
G03Y570370I291J-274D01*
G02X251220I-1093J-1030D01*
G03Y570919I-291J274D01*
G02X253406I1093J1030D01*
G37*
G36*
G01X216595D02*
G03Y570370I291J-274D01*
G02X214409I-1093J-1030D01*
G03Y570919I-291J274D01*
G02X216595I1093J1030D01*
G37*
G36*
G01X179784D02*
G03Y570370I291J-274D01*
G02X177598I-1093J-1030D01*
G03Y570919I-291J274D01*
G02X179784I1093J1030D01*
G37*
G36*
G01X142973D02*
G03Y570370I291J-274D01*
G02X140787I-1093J-1030D01*
G03Y570919I-291J274D01*
G02X142973I1093J1030D01*
G37*
G36*
G01X703008Y570426D02*
G03X703030Y569849I288J-278D01*
G02X701092Y569774I-930J-1049D01*
G03X701070Y570351I-288J278D01*
G02X703008Y570426I930J1049D01*
G37*
G36*
G01X649000Y567694D02*
G03X648400I-300J-265D01*
G02Y569552I-1050J929D01*
G03X649000I300J265D01*
G02Y567694I1050J-929D01*
G37*
G36*
G01X1603336Y572335D02*
Y568240D01*
X1603327Y568156D01*
G02X1600314Y568325I-1502J169D01*
G01Y572326D01*
G02X1603336Y572335I1511J-1D01*
G37*
G36*
G01X4611Y568271D02*
G03X5189I289J277D01*
G02Y566329I1011J-971D01*
G03X4611I-289J-277D01*
G02Y568271I-1011J971D01*
G37*
G36*
G01X1684289Y571689D02*
X1684290Y571687D01*
X1687186Y566282D01*
X1687187Y566280D01*
G02X1683042Y564059I-2045J-1162D01*
G01X1683041Y564061D01*
X1680145Y569466D01*
X1680144Y569468D01*
G02X1684289Y571689I2045J1162D01*
G37*
G36*
G01X1675423Y571704D02*
X1675424Y571703D01*
X1678336Y566266D01*
X1678337Y566264D01*
G02X1674191Y564044I-2054J-1146D01*
G01X1674190Y564045D01*
X1671278Y569482D01*
X1671277Y569484D01*
G02X1675423Y571704I2054J1146D01*
G37*
G36*
G01X1637045Y571689D02*
X1637046Y571687D01*
X1639942Y566282D01*
X1639943Y566280D01*
G02X1635798Y564059I-2045J-1162D01*
G01X1635797Y564061D01*
X1632901Y569466D01*
X1632900Y569468D01*
G02X1637045Y571689I2045J1162D01*
G37*
G36*
G01X1628179Y571704D02*
X1628180Y571703D01*
X1631092Y566266D01*
X1631093Y566264D01*
G02X1626947Y564044I-2054J-1146D01*
G01X1626946Y564045D01*
X1624034Y569482D01*
X1624033Y569484D01*
G02X1628179Y571704I2054J1146D01*
G37*
G36*
G01X1448220Y562717D02*
G03X1447680I-270J-295D01*
G02Y565083I-1080J1183D01*
G03X1448220I270J295D01*
G02X1450340Y565118I1080J-1183D01*
G03X1450860I260J304D01*
G02X1452980Y565083I1040J-1218D01*
G03X1453520I270J295D01*
G02X1455680I1080J-1183D01*
G03X1456220I270J295D01*
G02Y562717I1080J-1183D01*
G03X1455680I-270J-295D01*
G02X1453520I-1080J1183D01*
G03X1452980I-270J-295D01*
G02X1450860Y562682I-1080J1183D01*
G03X1450340I-260J-304D01*
G02X1448220Y562717I-1040J1218D01*
G37*
G36*
G01X1655911Y562918D02*
G03X1655333Y562646I-187J-354D01*
G02X1653568Y564276I-1373J284D01*
G03X1653794Y564874I-112J384D01*
G02X1655911Y562918I4734J3000D01*
G37*
G36*
G01X1598097Y561256D02*
G03X1597543I-277J-288D01*
G02X1595579Y563258I-973J1010D01*
G03X1595590Y563812I-283J283D01*
G02X1595597Y565723I1030J952D01*
G03X1595593Y566275I-292J274D01*
G02X1597623Y566291I1007J975D01*
G03X1597627Y565739I292J-274D01*
G02X1597714Y565641I-1004J-979D01*
G03X1598026I156J125D01*
G02X1600111Y563772I1093J-878D01*
G03X1600100Y563218I283J-283D01*
G02X1598097Y561256I-1030J-952D01*
G37*
G36*
G01X1469286Y560694D02*
G03X1468767Y560689I-257J-307D01*
G02X1468742Y563125I-1053J1207D01*
G03X1469261Y563130I257J307D01*
G02X1471361Y563136I1053J-1207D01*
G03X1471901Y563152I261J302D01*
G02X1471971Y560790I1117J-1149D01*
G03X1471431Y560774I-261J-302D01*
G02X1469286Y560694I-1117J1149D01*
G37*
G36*
G01X1491077Y560687D02*
G03X1490504Y560667I-277J-289D01*
G02X1490426Y562897I-1188J1075D01*
G03X1490999Y562917I277J289D01*
G02X1493387Y562903I1188J-1075D01*
G03X1493987I300J265D01*
G02X1496267Y563025I1200J-1061D01*
G03X1496812Y563031I269J296D01*
G02X1498963Y563086I1106J-1159D01*
G03X1499485I261J303D01*
G02Y560658I1045J-1214D01*
G03X1498963I-261J-303D01*
G02X1496838Y560689I-1045J1214D01*
G03X1496293Y560683I-269J-296D01*
G02X1493987Y560781I-1106J1159D01*
G03X1493387I-300J-265D01*
G02X1491077Y560687I-1200J1061D01*
G37*
G36*
G01X1383118Y561641D02*
G03X1383081Y561073I262J-302D01*
G02X1381114Y561202I-1049J-930D01*
G03X1381151Y561770I-262J302D01*
G02X1383118Y561641I1049J930D01*
G37*
G36*
G01X1739133Y559735D02*
G03X1739297Y559155I335J-218D01*
G02X1737522Y558653I-600J-1267D01*
G03X1737358Y559233I-335J218D01*
G02X1739133Y559735I600J1267D01*
G37*
G36*
G01X869174Y556982D02*
Y564484D01*
X871376D01*
Y556982D01*
G02X869174I-1101J-1021D01*
G37*
G36*
G01X219566D02*
Y564484D01*
X221768D01*
Y556982D01*
G02X219566I-1101J-1021D01*
G37*
G36*
G01X1240630Y556978D02*
Y564484D01*
X1242834D01*
Y556978D01*
G02X1240630I-1102J-1021D01*
G37*
G36*
G01X1233938D02*
Y564484D01*
X1236140D01*
Y556978D01*
G02X1233938I-1101J-1021D01*
G37*
G36*
G01X1217204Y556977D02*
Y564484D01*
X1219408D01*
Y556979D01*
G02X1217204Y556977I-1101J-1022D01*
G37*
G36*
G01X1210512D02*
Y564484D01*
X1212714D01*
Y556979D01*
G02X1210512Y556977I-1100J-1022D01*
G37*
G36*
G01X1203820Y556978D02*
Y564484D01*
X1206022D01*
Y556978D01*
G02X1203820I-1101J-1021D01*
G37*
G36*
G01X1197126D02*
Y564484D01*
X1199330D01*
Y556978D01*
G02X1197126I-1102J-1021D01*
G37*
G36*
G01X1180394Y556977D02*
Y564484D01*
X1182596D01*
Y556979D01*
G02X1180394Y556977I-1100J-1022D01*
G37*
G36*
G01X1173700D02*
Y564484D01*
X1175904D01*
Y556979D01*
G02X1173700Y556977I-1101J-1022D01*
G37*
G36*
G01X1167008Y556978D02*
Y564484D01*
X1169212D01*
Y556978D01*
G02X1167008I-1102J-1021D01*
G37*
G36*
G01X1160316D02*
Y564484D01*
X1162518D01*
Y556978D01*
G02X1160316I-1101J-1021D01*
G37*
G36*
G01X1143582Y556977D02*
Y564484D01*
X1145786D01*
Y556979D01*
G02X1143582Y556977I-1101J-1022D01*
G37*
G36*
G01X1136890D02*
Y564484D01*
X1139092D01*
Y556979D01*
G02X1136890Y556977I-1100J-1022D01*
G37*
G36*
G01X1130198Y556978D02*
Y564484D01*
X1132400D01*
Y556978D01*
G02X1130198I-1101J-1021D01*
G37*
G36*
G01X1123504D02*
Y564484D01*
X1125708D01*
Y556978D01*
G02X1123504I-1102J-1021D01*
G37*
G36*
G01X1106772Y556977D02*
Y564484D01*
X1108974D01*
Y556979D01*
G02X1106772Y556977I-1100J-1022D01*
G37*
G36*
G01X1100078D02*
Y564484D01*
X1102282D01*
Y556979D01*
G02X1100078Y556977I-1101J-1022D01*
G37*
G36*
G01X949490Y556979D02*
Y564484D01*
X951692D01*
Y556977D01*
G02X949490Y556979I-1102J-1020D01*
G37*
G36*
G01X942796Y556978D02*
Y564484D01*
X944998D01*
Y556978D01*
G02X942796I-1101J-1021D01*
G37*
G36*
G01X926064D02*
Y564484D01*
X928266D01*
Y556978D01*
G02X926064I-1101J-1021D01*
G37*
G36*
G01X919370D02*
Y564484D01*
X921574D01*
Y556978D01*
G02X919370I-1102J-1021D01*
G37*
G36*
G01X912678D02*
Y564484D01*
X914880D01*
Y556978D01*
G02X912678I-1101J-1021D01*
G37*
G36*
G01X905984D02*
Y564484D01*
X908188D01*
Y556978D01*
G02X905984I-1102J-1021D01*
G37*
G36*
G01X889252D02*
Y564484D01*
X891456D01*
Y556978D01*
G02X889252I-1102J-1021D01*
G37*
G36*
G01X882560D02*
Y564484D01*
X884762D01*
Y556978D01*
G02X882560I-1101J-1021D01*
G37*
G36*
G01X875866D02*
Y564484D01*
X878070D01*
Y556978D01*
G02X875866I-1102J-1021D01*
G37*
G36*
G01X852442D02*
Y564484D01*
X854644D01*
Y556978D01*
G02X852442I-1101J-1021D01*
G37*
G36*
G01X845748D02*
Y564484D01*
X847952D01*
Y556978D01*
G02X845748I-1102J-1021D01*
G37*
G36*
G01X839056D02*
Y564484D01*
X841258D01*
Y556978D01*
G02X839056I-1101J-1021D01*
G37*
G36*
G01X832362D02*
Y564484D01*
X834566D01*
Y556978D01*
G02X832362I-1102J-1021D01*
G37*
G36*
G01X815630D02*
Y564484D01*
X817834D01*
Y556978D01*
G02X815630I-1102J-1021D01*
G37*
G36*
G01X808938D02*
Y564484D01*
X811140D01*
Y556978D01*
G02X808938I-1101J-1021D01*
G37*
G36*
G01X802244D02*
Y564484D01*
X804448D01*
Y556978D01*
G02X802244I-1102J-1021D01*
G37*
G36*
G01X795552D02*
Y564484D01*
X797754D01*
Y556978D01*
G02X795552I-1101J-1021D01*
G37*
G36*
G01X778820D02*
Y564484D01*
X781022D01*
Y556978D01*
G02X778820I-1101J-1021D01*
G37*
G36*
G01X772126D02*
Y564484D01*
X774330D01*
Y556978D01*
G02X772126I-1102J-1021D01*
G37*
G36*
G01X591022D02*
Y564484D01*
X593226D01*
Y556978D01*
G02X591022I-1102J-1021D01*
G37*
G36*
G01X584330D02*
Y564484D01*
X586532D01*
Y556978D01*
G02X584330I-1101J-1021D01*
G37*
G36*
G01X567596Y556977D02*
Y564484D01*
X569800D01*
Y556979D01*
G02X567596Y556977I-1101J-1022D01*
G37*
G36*
G01X560904D02*
Y564484D01*
X563106D01*
Y556979D01*
G02X560904Y556977I-1100J-1022D01*
G37*
G36*
G01X554212Y556978D02*
Y564484D01*
X556414D01*
Y556978D01*
G02X554212I-1101J-1021D01*
G37*
G36*
G01X547518D02*
Y564484D01*
X549722D01*
Y556978D01*
G02X547518I-1102J-1021D01*
G37*
G36*
G01X530786Y556977D02*
Y564484D01*
X532988D01*
Y556979D01*
G02X530786Y556977I-1100J-1022D01*
G37*
G36*
G01X524092D02*
Y564484D01*
X526296D01*
Y556979D01*
G02X524092Y556977I-1101J-1022D01*
G37*
G36*
G01X517400Y556978D02*
Y564484D01*
X519604D01*
Y556978D01*
G02X517400I-1102J-1021D01*
G37*
G36*
G01X510708D02*
Y564484D01*
X512910D01*
Y556978D01*
G02X510708I-1101J-1021D01*
G37*
G36*
G01X493974Y556977D02*
Y564484D01*
X496178D01*
Y556979D01*
G02X493974Y556977I-1101J-1022D01*
G37*
G36*
G01X487282D02*
Y564484D01*
X489484D01*
Y556979D01*
G02X487282Y556977I-1100J-1022D01*
G37*
G36*
G01X480590Y556978D02*
Y564484D01*
X482792D01*
Y556978D01*
G02X480590I-1101J-1021D01*
G37*
G36*
G01X473896D02*
Y564484D01*
X476100D01*
Y556978D01*
G02X473896I-1102J-1021D01*
G37*
G36*
G01X457164Y556977D02*
Y564484D01*
X459366D01*
Y556979D01*
G02X457164Y556977I-1100J-1022D01*
G37*
G36*
G01X450470D02*
Y564484D01*
X452674D01*
Y556979D01*
G02X450470Y556977I-1101J-1022D01*
G37*
G36*
G01X299882Y556979D02*
Y564484D01*
X302084D01*
Y556977D01*
G02X299882Y556979I-1102J-1020D01*
G37*
G36*
G01X293188Y556978D02*
Y564484D01*
X295390D01*
Y556978D01*
G02X293188I-1101J-1021D01*
G37*
G36*
G01X276456D02*
Y564484D01*
X278658D01*
Y556978D01*
G02X276456I-1101J-1021D01*
G37*
G36*
G01X269762D02*
Y564484D01*
X271966D01*
Y556978D01*
G02X269762I-1102J-1021D01*
G37*
G36*
G01X263070D02*
Y564484D01*
X265272D01*
Y556978D01*
G02X263070I-1101J-1021D01*
G37*
G36*
G01X256376D02*
Y564484D01*
X258580D01*
Y556978D01*
G02X256376I-1102J-1021D01*
G37*
G36*
G01X239644D02*
Y564484D01*
X241848D01*
Y556978D01*
G02X239644I-1102J-1021D01*
G37*
G36*
G01X232952D02*
Y564484D01*
X235154D01*
Y556978D01*
G02X232952I-1101J-1021D01*
G37*
G36*
G01X226258D02*
Y564484D01*
X228462D01*
Y556978D01*
G02X226258I-1102J-1021D01*
G37*
G36*
G01X202834D02*
Y564484D01*
X205036D01*
Y556978D01*
G02X202834I-1101J-1021D01*
G37*
G36*
G01X196140D02*
Y564484D01*
X198344D01*
Y556978D01*
G02X196140I-1102J-1021D01*
G37*
G36*
G01X189448D02*
Y564484D01*
X191650D01*
Y556978D01*
G02X189448I-1101J-1021D01*
G37*
G36*
G01X182754D02*
Y564484D01*
X184958D01*
Y556978D01*
G02X182754I-1102J-1021D01*
G37*
G36*
G01X166022D02*
Y564484D01*
X168226D01*
Y556978D01*
G02X166022I-1102J-1021D01*
G37*
G36*
G01X159330D02*
Y564484D01*
X161532D01*
Y556978D01*
G02X159330I-1101J-1021D01*
G37*
G36*
G01X152636D02*
Y564484D01*
X154840D01*
Y556978D01*
G02X152636I-1102J-1021D01*
G37*
G36*
G01X145944D02*
Y564484D01*
X148146D01*
Y556978D01*
G02X145944I-1101J-1021D01*
G37*
G36*
G01X129212D02*
Y564484D01*
X131414D01*
Y556978D01*
G02X129212I-1101J-1021D01*
G37*
G36*
G01X122518D02*
Y564484D01*
X124722D01*
Y556978D01*
G02X122518I-1102J-1021D01*
G37*
G36*
G01X1626606Y559210D02*
Y555115D01*
X1626596Y555031D01*
G02X1623582Y555200I-1502J169D01*
G01Y559200D01*
G02X1626606Y559210I1512J0D01*
G37*
G36*
G01X2393Y555510D02*
G03X2416Y554924I283J-282D01*
G02X430Y554895I-977J-1141D01*
G03X436Y555482I-269J296D01*
G02X389Y555529I968J1015D01*
G03X-189I-289J-277D01*
G02Y557471I-1011J971D01*
G03X389I289J277D01*
G02X2393Y555510I1012J-971D01*
G37*
G36*
G01X652611Y551617D02*
G03X651989I-311J-252D01*
G02Y553383I-1089J883D01*
G03X652611I311J252D01*
G02Y551617I1089J-883D01*
G37*
G36*
G01X1663754Y549588D02*
X1658753D01*
G02X1658754Y552412I1J1412D01*
G01X1663754D01*
G02X1665166Y551010I0J-1412D01*
G01Y550916D01*
X1665155Y550832D01*
G02X1663754Y549588I-1401J167D01*
G37*
G36*
G01X1230970Y552287D02*
G03Y551741I292J-273D01*
G02X1228778I-1096J-1027D01*
G03Y552287I-292J273D01*
G02X1230970I1096J1027D01*
G37*
G36*
G01X1194159D02*
G03Y551741I292J-273D01*
G02X1191967I-1096J-1027D01*
G03Y552287I-292J273D01*
G02X1194159I1096J1027D01*
G37*
G36*
G01X1157348D02*
G03Y551741I292J-273D01*
G02X1155156I-1096J-1027D01*
G03Y552287I-292J273D01*
G02X1157348I1096J1027D01*
G37*
G36*
G01X1120536D02*
G03Y551741I292J-273D01*
G02X1118344I-1096J-1027D01*
G03Y552287I-292J273D01*
G02X1120536I1096J1027D01*
G37*
G36*
G01X939828D02*
G03Y551741I292J-273D01*
G02X937636I-1096J-1027D01*
G03Y552287I-292J273D01*
G02X939828I1096J1027D01*
G37*
G36*
G01X903017D02*
G03Y551741I292J-273D01*
G02X900825I-1096J-1027D01*
G03Y552287I-292J273D01*
G02X903017I1096J1027D01*
G37*
G36*
G01X866206D02*
G03Y551741I292J-273D01*
G02X864014I-1096J-1027D01*
G03Y552287I-292J273D01*
G02X866206I1096J1027D01*
G37*
G36*
G01X829395D02*
G03Y551741I292J-273D01*
G02X827203I-1096J-1027D01*
G03Y552287I-292J273D01*
G02X829395I1096J1027D01*
G37*
G36*
G01X792584D02*
G03Y551741I292J-273D01*
G02X790392I-1096J-1027D01*
G03Y552287I-292J273D01*
G02X792584I1096J1027D01*
G37*
G36*
G01X581362D02*
G03Y551741I292J-273D01*
G02X579170I-1096J-1027D01*
G03Y552287I-292J273D01*
G02X581362I1096J1027D01*
G37*
G36*
G01X544551D02*
G03Y551741I292J-273D01*
G02X542359I-1096J-1027D01*
G03Y552287I-292J273D01*
G02X544551I1096J1027D01*
G37*
G36*
G01X507740D02*
G03Y551741I292J-273D01*
G02X505548I-1096J-1027D01*
G03Y552287I-292J273D01*
G02X507740I1096J1027D01*
G37*
G36*
G01X470928D02*
G03Y551741I292J-273D01*
G02X468736I-1096J-1027D01*
G03Y552287I-292J273D01*
G02X470928I1096J1027D01*
G37*
G36*
G01X290220D02*
G03Y551741I292J-273D01*
G02X288028I-1096J-1027D01*
G03Y552287I-292J273D01*
G02X290220I1096J1027D01*
G37*
G36*
G01X253409D02*
G03Y551741I292J-273D01*
G02X251217I-1096J-1027D01*
G03Y552287I-292J273D01*
G02X253409I1096J1027D01*
G37*
G36*
G01X216598D02*
G03Y551741I292J-273D01*
G02X214406I-1096J-1027D01*
G03Y552287I-292J273D01*
G02X216598I1096J1027D01*
G37*
G36*
G01X179787D02*
G03Y551741I292J-273D01*
G02X177595I-1096J-1027D01*
G03Y552287I-292J273D01*
G02X179787I1096J1027D01*
G37*
G36*
G01X142976D02*
G03Y551741I292J-273D01*
G02X140784I-1096J-1027D01*
G03Y552287I-292J273D01*
G02X142976I1096J1027D01*
G37*
G36*
G01X1685000Y549032D02*
X1679999D01*
G02X1680000Y552056I1J1512D01*
G01X1685000D01*
G02X1686512Y550554I0J-1512D01*
G01Y550459D01*
X1686502Y550375D01*
G02X1685000Y549032I-1502J168D01*
G37*
G36*
G01X1225870Y552073D02*
G03Y551527I292J-273D01*
G02X1223678I-1096J-1027D01*
G03Y552073I-292J273D01*
G02X1225870I1096J1027D01*
G37*
G36*
G01X1189059D02*
G03Y551527I292J-273D01*
G02X1186867I-1096J-1027D01*
G03Y552073I-292J273D01*
G02X1189059I1096J1027D01*
G37*
G36*
G01X1152248D02*
G03Y551527I292J-273D01*
G02X1150056I-1096J-1027D01*
G03Y552073I-292J273D01*
G02X1152248I1096J1027D01*
G37*
G36*
G01X1115436D02*
G03Y551527I292J-273D01*
G02X1113244I-1096J-1027D01*
G03Y552073I-292J273D01*
G02X1115436I1096J1027D01*
G37*
G36*
G01X934728D02*
G03Y551527I292J-273D01*
G02X932536I-1096J-1027D01*
G03Y552073I-292J273D01*
G02X934728I1096J1027D01*
G37*
G36*
G01X897917D02*
G03Y551527I292J-273D01*
G02X895725I-1096J-1027D01*
G03Y552073I-292J273D01*
G02X897917I1096J1027D01*
G37*
G36*
G01X861106D02*
G03Y551527I292J-273D01*
G02X858914I-1096J-1027D01*
G03Y552073I-292J273D01*
G02X861106I1096J1027D01*
G37*
G36*
G01X824295D02*
G03Y551527I292J-273D01*
G02X822103I-1096J-1027D01*
G03Y552073I-292J273D01*
G02X824295I1096J1027D01*
G37*
G36*
G01X787484D02*
G03Y551527I292J-273D01*
G02X785292I-1096J-1027D01*
G03Y552073I-292J273D01*
G02X787484I1096J1027D01*
G37*
G36*
G01X576262D02*
G03Y551527I292J-273D01*
G02X574070I-1096J-1027D01*
G03Y552073I-292J273D01*
G02X576262I1096J1027D01*
G37*
G36*
G01X539451D02*
G03Y551527I292J-273D01*
G02X537259I-1096J-1027D01*
G03Y552073I-292J273D01*
G02X539451I1096J1027D01*
G37*
G36*
G01X502640D02*
G03Y551527I292J-273D01*
G02X500448I-1096J-1027D01*
G03Y552073I-292J273D01*
G02X502640I1096J1027D01*
G37*
G36*
G01X465828D02*
G03Y551527I292J-273D01*
G02X463636I-1096J-1027D01*
G03Y552073I-292J273D01*
G02X465828I1096J1027D01*
G37*
G36*
G01X285120D02*
G03Y551527I292J-273D01*
G02X282928I-1096J-1027D01*
G03Y552073I-292J273D01*
G02X285120I1096J1027D01*
G37*
G36*
G01X248309D02*
G03Y551527I292J-273D01*
G02X246117I-1096J-1027D01*
G03Y552073I-292J273D01*
G02X248309I1096J1027D01*
G37*
G36*
G01X211498D02*
G03Y551527I292J-273D01*
G02X209306I-1096J-1027D01*
G03Y552073I-292J273D01*
G02X211498I1096J1027D01*
G37*
G36*
G01X174687D02*
G03Y551527I292J-273D01*
G02X172495I-1096J-1027D01*
G03Y552073I-292J273D01*
G02X174687I1096J1027D01*
G37*
G36*
G01X137876D02*
G03Y551527I292J-273D01*
G02X135684I-1096J-1027D01*
G03Y552073I-292J273D01*
G02X137876I1096J1027D01*
G37*
G36*
G01X1794888Y551715D02*
G03X1794866Y551116I254J-309D01*
G02X1793012Y551185I-966J-1016D01*
G03X1793034Y551784I-254J309D01*
G02X1794888Y551715I966J1016D01*
G37*
G36*
G01X1936731Y551240D02*
G03X1937264Y550995I380J125D01*
G02X1936469Y549260I536J-1295D01*
G03X1935936Y549505I-380J-125D01*
G02X1936731Y551240I-536J1295D01*
G37*
G36*
G01X1739037Y549968D02*
G03X1739065Y549355I270J-295D01*
G02X1737267Y549271I-849J-1116D01*
G03X1737239Y549884I-270J295D01*
G02X1739037Y549968I849J1116D01*
G37*
G36*
G01X1364055Y546944D02*
G03X1363501I-277J-288D01*
G02Y548964I-973J1010D01*
G03X1364055I277J288D01*
G02Y546944I973J-1010D01*
G37*
G36*
G01X1705348Y545122D02*
X1700348D01*
G02Y548144I0J1511D01*
G01X1705348D01*
G02X1706860Y546643I0J-1512D01*
G01Y546548D01*
X1706850Y546464D01*
G02X1705348Y545122I-1502J169D01*
G37*
G36*
G01X1496273Y547033D02*
G03X1496820Y547010I286J280D01*
G02X1496723Y544674I1046J-1213D01*
G03X1496176Y544697I-286J-280D01*
G02X1493930Y544849I-1046J1213D01*
G03X1493330I-300J-265D01*
G02X1490874Y544916I-1200J1061D01*
G03X1490298Y544970I-314J-248D01*
G02X1490387Y547006I-918J1060D01*
G03X1490965Y547010I287J278D01*
G02X1493330Y546971I1165J-1100D01*
G03X1493930I300J265D01*
G02X1496273Y547033I1200J-1061D01*
G37*
G36*
G01X1439987Y544190D02*
G03X1439915Y543633I247J-315D01*
G02X1437935Y543889I-1116J-848D01*
G03X1438007Y544446I-247J315D01*
G02X1439987Y544190I1116J848D01*
G37*
G36*
G01X1676020Y550027D02*
G03X1676280Y549508I376J-136D01*
G02X1671633Y548350I-1359J-4449D01*
G03X1671350Y549032I-283J282D01*
G01X1669599D01*
G02X1669600Y552056I1J1512D01*
G01X1674600D01*
G02X1676112Y550554I0J-1512D01*
G01Y550459D01*
X1676102Y550375D01*
G02X1676020Y550027I-1502J170D01*
G37*
G36*
G01X1043835Y552650D02*
X1055611D01*
X1057211Y551050D01*
X1058911D01*
X1060250Y549711D01*
Y549685D01*
G03X1060733Y549293I400J-1D01*
G02X1060298Y546722I291J-1372D01*
G01X1060164Y546803D01*
X1058411Y545050D01*
X1055432D01*
Y539272D01*
X1053228D01*
Y545050D01*
X1052086D01*
Y539272D01*
X1049882D01*
Y545050D01*
X1045392D01*
Y539272D01*
X1043190D01*
Y545550D01*
X1041850Y546889D01*
Y551011D01*
X1043242Y552403D01*
G02X1043835Y552650I558J-504D01*
G37*
G36*
G01X392570Y551330D02*
X393342Y552103D01*
X393345Y552106D01*
G02X393935Y552350I555J-507D01*
G01X406211D01*
X407511Y551050D01*
X409311D01*
X410750Y549611D01*
Y549254D01*
X410980D01*
X411008Y549263D01*
G02X410868Y546630I407J-1342D01*
G01X410744Y546683D01*
X408911Y544850D01*
X405824D01*
Y539272D01*
X403620D01*
Y544850D01*
X402478D01*
Y539272D01*
X400274D01*
Y544850D01*
X395784D01*
Y539272D01*
X393582D01*
Y544958D01*
X392350Y546189D01*
Y550800D01*
G02X392570Y551330I750J-1D01*
G37*
G36*
G01X1391434Y540655D02*
G03X1391428Y540051I259J-305D01*
G02X1389543Y540025I-928J-1051D01*
G03X1389521Y540629I-273J292D01*
G02X1391434Y540655I941J1171D01*
G37*
G36*
G01X1743894Y534951D02*
G03X1743351I-271J-294D01*
G02Y538631I-1697J1840D01*
G03X1743894I272J294D01*
G02X1747288I1697J-1840D01*
G03X1747831I272J294D01*
G02X1751225I1697J-1840D01*
G03X1751768I271J294D01*
G02X1755162I1697J-1840D01*
G03X1755705I271J294D01*
G02X1759099I1697J-1840D01*
G03X1759642I272J294D01*
G02Y534951I1697J-1840D01*
G03X1759099I-271J-294D01*
G02X1755705I-1697J1840D01*
G03X1755162I-272J-294D01*
G02X1751768I-1697J1840D01*
G03X1751225I-272J-294D01*
G02X1747831I-1697J1840D01*
G03X1747288I-271J-294D01*
G02X1743894I-1697J1840D01*
G37*
G36*
G01X735027Y534190D02*
G03X734473I-277J-288D01*
G02X732490Y536173I-973J1010D01*
G03Y536727I-288J277D01*
G02X734473Y538710I1010J973D01*
G03X735027I277J288D01*
G02X737010Y536727I973J-1010D01*
G03Y536173I288J-277D01*
G02X735027Y534190I-1010J-973D01*
G37*
G36*
G01X1712206Y533780D02*
X1707204D01*
G02X1704820Y534952I0J3011D01*
G03X1704207Y534977I-317J-244D01*
G02X1700203Y534976I-2002J1814D01*
G03X1699590Y534952I-296J-268D01*
G02X1697206Y533780I-2384J1839D01*
G01X1692204D01*
G02X1689820Y534952I0J3011D01*
G03X1689207Y534977I-317J-244D01*
G02Y538605I-2002J1814D01*
G03X1689820Y538630I296J269D01*
G02X1692204Y539802I2384J-1839D01*
G01X1697206D01*
G02X1699590Y538630I0J-3011D01*
G03X1700203Y538606I317J244D01*
G02X1704207Y538605I2002J-1815D01*
G03X1704820Y538630I296J269D01*
G02X1707204Y539802I2384J-1839D01*
G01X1712206D01*
G02X1714590Y538630I0J-3011D01*
G03X1715203Y538606I317J244D01*
G02Y534976I2002J-1815D01*
G03X1714590Y534952I-296J-268D01*
G02X1712206Y533780I-2384J1839D01*
G37*
G36*
G01X1225862Y533364D02*
G03X1225868Y532807I290J-275D01*
G02X1223712Y532785I-1067J-1057D01*
G03X1223706Y533342I-290J275D01*
G02X1225862Y533364I1067J1057D01*
G37*
G36*
G01X1189051D02*
G03X1189057Y532807I290J-275D01*
G02X1186901Y532785I-1067J-1057D01*
G03X1186895Y533342I-290J275D01*
G02X1189051Y533364I1067J1057D01*
G37*
G36*
G01X1152240D02*
G03X1152246Y532807I290J-275D01*
G02X1150090Y532785I-1067J-1057D01*
G03X1150084Y533342I-290J275D01*
G02X1152240Y533364I1067J1057D01*
G37*
G36*
G01X1115428D02*
G03X1115434Y532807I290J-275D01*
G02X1113278Y532785I-1067J-1057D01*
G03X1113272Y533342I-290J275D01*
G02X1115428Y533364I1067J1057D01*
G37*
G36*
G01X934720D02*
G03X934726Y532807I290J-275D01*
G02X932570Y532785I-1067J-1057D01*
G03X932564Y533342I-290J275D01*
G02X934720Y533364I1067J1057D01*
G37*
G36*
G01X897909D02*
G03X897915Y532807I290J-275D01*
G02X895759Y532785I-1067J-1057D01*
G03X895753Y533342I-290J275D01*
G02X897909Y533364I1067J1057D01*
G37*
G36*
G01X861098D02*
G03X861104Y532807I290J-275D01*
G02X858948Y532785I-1067J-1057D01*
G03X858942Y533342I-290J275D01*
G02X861098Y533364I1067J1057D01*
G37*
G36*
G01X824287D02*
G03X824293Y532807I290J-275D01*
G02X822137Y532785I-1067J-1057D01*
G03X822131Y533342I-290J275D01*
G02X824287Y533364I1067J1057D01*
G37*
G36*
G01X787476D02*
G03X787482Y532807I290J-275D01*
G02X785326Y532785I-1067J-1057D01*
G03X785320Y533342I-290J275D01*
G02X787476Y533364I1067J1057D01*
G37*
G36*
G01X576254D02*
G03X576260Y532807I290J-275D01*
G02X574104Y532785I-1067J-1057D01*
G03X574098Y533342I-290J275D01*
G02X576254Y533364I1067J1057D01*
G37*
G36*
G01X539443D02*
G03X539449Y532807I290J-275D01*
G02X537293Y532785I-1067J-1057D01*
G03X537287Y533342I-290J275D01*
G02X539443Y533364I1067J1057D01*
G37*
G36*
G01X502632D02*
G03X502638Y532807I290J-275D01*
G02X500482Y532785I-1067J-1057D01*
G03X500476Y533342I-290J275D01*
G02X502632Y533364I1067J1057D01*
G37*
G36*
G01X465820D02*
G03X465826Y532807I290J-275D01*
G02X463670Y532785I-1067J-1057D01*
G03X463664Y533342I-290J275D01*
G02X465820Y533364I1067J1057D01*
G37*
G36*
G01X285112D02*
G03X285118Y532807I290J-275D01*
G02X282962Y532785I-1067J-1057D01*
G03X282956Y533342I-290J275D01*
G02X285112Y533364I1067J1057D01*
G37*
G36*
G01X248301D02*
G03X248307Y532807I290J-275D01*
G02X246151Y532785I-1067J-1057D01*
G03X246145Y533342I-290J275D01*
G02X248301Y533364I1067J1057D01*
G37*
G36*
G01X211490D02*
G03X211496Y532807I290J-275D01*
G02X209340Y532785I-1067J-1057D01*
G03X209334Y533342I-290J275D01*
G02X211490Y533364I1067J1057D01*
G37*
G36*
G01X174679D02*
G03X174685Y532807I290J-275D01*
G02X172529Y532785I-1067J-1057D01*
G03X172523Y533342I-290J275D01*
G02X174679Y533364I1067J1057D01*
G37*
G36*
G01X135718Y532785D02*
G03X135712Y533342I-290J275D01*
G02X137868Y533364I1067J1057D01*
G03X137874Y532807I290J-275D01*
G02X135718Y532785I-1067J-1057D01*
G37*
G36*
G01X1230967Y533119D02*
G03Y532570I291J-274D01*
G02X1228781I-1093J-1030D01*
G03Y533119I-291J274D01*
G02X1230967I1093J1030D01*
G37*
G36*
G01X1194156D02*
G03Y532570I291J-274D01*
G02X1191970I-1093J-1030D01*
G03Y533119I-291J274D01*
G02X1194156I1093J1030D01*
G37*
G36*
G01X1157345D02*
G03Y532570I291J-274D01*
G02X1155159I-1093J-1030D01*
G03Y533119I-291J274D01*
G02X1157345I1093J1030D01*
G37*
G36*
G01X1120533D02*
G03Y532570I291J-274D01*
G02X1118347I-1093J-1030D01*
G03Y533119I-291J274D01*
G02X1120533I1093J1030D01*
G37*
G36*
G01X939825D02*
G03Y532570I291J-274D01*
G02X937639I-1093J-1030D01*
G03Y533119I-291J274D01*
G02X939825I1093J1030D01*
G37*
G36*
G01X903014D02*
G03Y532570I291J-274D01*
G02X900828I-1093J-1030D01*
G03Y533119I-291J274D01*
G02X903014I1093J1030D01*
G37*
G36*
G01X866203D02*
G03Y532570I291J-274D01*
G02X864017I-1093J-1030D01*
G03Y533119I-291J274D01*
G02X866203I1093J1030D01*
G37*
G36*
G01X829392D02*
G03Y532570I291J-274D01*
G02X827206I-1093J-1030D01*
G03Y533119I-291J274D01*
G02X829392I1093J1030D01*
G37*
G36*
G01X792581D02*
G03Y532570I291J-274D01*
G02X790395I-1093J-1030D01*
G03Y533119I-291J274D01*
G02X792581I1093J1030D01*
G37*
G36*
G01X581359D02*
G03Y532570I291J-274D01*
G02X579173I-1093J-1030D01*
G03Y533119I-291J274D01*
G02X581359I1093J1030D01*
G37*
G36*
G01X544548D02*
G03Y532570I291J-274D01*
G02X542362I-1093J-1030D01*
G03Y533119I-291J274D01*
G02X544548I1093J1030D01*
G37*
G36*
G01X507737D02*
G03Y532570I291J-274D01*
G02X505551I-1093J-1030D01*
G03Y533119I-291J274D01*
G02X507737I1093J1030D01*
G37*
G36*
G01X470925D02*
G03Y532570I291J-274D01*
G02X468739I-1093J-1030D01*
G03Y533119I-291J274D01*
G02X470925I1093J1030D01*
G37*
G36*
G01X290217D02*
G03Y532570I291J-274D01*
G02X288031I-1093J-1030D01*
G03Y533119I-291J274D01*
G02X290217I1093J1030D01*
G37*
G36*
G01X253406D02*
G03Y532570I291J-274D01*
G02X251220I-1093J-1030D01*
G03Y533119I-291J274D01*
G02X253406I1093J1030D01*
G37*
G36*
G01X216595D02*
G03Y532570I291J-274D01*
G02X214409I-1093J-1030D01*
G03Y533119I-291J274D01*
G02X216595I1093J1030D01*
G37*
G36*
G01X179784D02*
G03Y532570I291J-274D01*
G02X177598I-1093J-1030D01*
G03Y533119I-291J274D01*
G02X179784I1093J1030D01*
G37*
G36*
G01X142973D02*
G03Y532570I291J-274D01*
G02X140787I-1093J-1030D01*
G03Y533119I-291J274D01*
G02X142973I1093J1030D01*
G37*
G36*
G01X4611Y532271D02*
G03X5189I289J277D01*
G02Y530329I1011J-971D01*
G03X4611I-289J-277D01*
G02Y532271I-1011J971D01*
G37*
G36*
G01X1482727Y530190D02*
G03X1482173I-277J-288D01*
G02Y532210I-973J1010D01*
G03X1482727I277J288D01*
G02Y530190I973J-1010D01*
G37*
G36*
G01X115539Y527414D02*
G03X115435Y526832I214J-338D01*
G02X113575Y527166I-1113J-852D01*
G03X113679Y527748I-214J338D01*
G02X115539Y527414I1113J852D01*
G37*
G36*
G01X1818548Y526492D02*
G03X1818168Y526005I11J-400D01*
G02X1816761Y527101I-1368J-305D01*
G03X1817141Y527588I-11J400D01*
G02X1818548Y526492I1368J305D01*
G37*
G36*
G01X1638728Y528723D02*
G03X1638940Y528154I350J-194D01*
G02X1636593Y527726I-810J-2208D01*
G03X1636591Y528333I-261J303D01*
G02X1638728Y528723I909J1067D01*
G37*
G36*
G01X1785026Y521592D02*
G03X1784449Y521570I-278J-288D01*
G02X1782379Y521539I-1049J930D01*
G03X1781811Y521552I-290J-275D01*
G02X1781859Y523523I-973J1010D01*
G03X1782427Y523510I290J275D01*
G02X1784374Y523508I972J-1010D01*
G03X1784951Y523530I278J288D01*
G02X1785026Y521592I1049J-930D01*
G37*
G36*
G01X1629183Y519602D02*
G03X1628572Y519538I-279J-287D01*
G02X1628383Y521324I-1165J780D01*
G03X1628994Y521388I279J287D01*
G02X1629183Y519602I1165J-780D01*
G37*
G36*
G01X1698850Y519221D02*
G03X1698272I-289J-277D01*
G02Y521163I-1011J971D01*
G03X1698850I289J277D01*
G02Y519221I1011J-971D01*
G37*
G36*
G01X1790804Y521062D02*
G03X1790594Y520541I159J-367D01*
G02X1788746Y521288I-1294J-541D01*
G03X1788956Y521809I-159J367D01*
G02X1790804Y521062I1294J541D01*
G37*
G36*
G01X1377636Y518921D02*
G03X1377082I-277J-288D01*
G02X1375031Y519035I-973J1010D01*
G03X1374417Y519037I-308J-256D01*
G02X1374423Y520836I-1072J903D01*
G03X1375037Y520834I308J256D01*
G02X1377082Y520941I1073J-903D01*
G03X1377636I277J288D01*
G02X1379572Y520950I973J-1010D01*
G03X1380124Y520952I275J290D01*
G02X1382173Y520836I970J-1012D01*
G03X1382787Y520834I308J256D01*
G02X1384832Y520941I1073J-903D01*
G03X1385386I277J288D01*
G02Y518921I973J-1010D01*
G03X1384832I-277J-288D01*
G02X1382781Y519035I-973J1010D01*
G03X1382167Y519037I-308J-256D01*
G02X1380132Y518921I-1072J903D01*
G03X1379580Y518919I-275J-290D01*
G02X1377636Y518921I-971J1012D01*
G37*
G36*
G01X1490100Y521502D02*
X1492664D01*
G02Y518498I36J-1502D01*
G01X1490099D01*
G02X1490100Y521502I1J1502D01*
G37*
G36*
G01X753910Y520148D02*
G03Y519594I288J-277D01*
G02X751890I-1010J-973D01*
G03Y520148I-288J277D01*
G02X753910I1010J973D01*
G37*
G36*
G01X869174Y519182D02*
Y526684D01*
X871376D01*
Y519182D01*
G02X869174I-1101J-1021D01*
G37*
G36*
G01X219566D02*
Y526684D01*
X221768D01*
Y519182D01*
G02X219566I-1101J-1021D01*
G37*
G36*
G01X1240630Y519178D02*
Y526684D01*
X1242834D01*
Y519178D01*
G02X1240630I-1102J-1021D01*
G37*
G36*
G01X1233938D02*
Y526684D01*
X1236140D01*
Y519178D01*
G02X1233938I-1101J-1021D01*
G37*
G36*
G01X1217204Y519177D02*
Y526684D01*
X1219408D01*
Y519179D01*
G02X1217204Y519177I-1101J-1022D01*
G37*
G36*
G01X1210512D02*
Y526684D01*
X1212714D01*
Y519179D01*
G02X1210512Y519177I-1100J-1022D01*
G37*
G36*
G01X1203820Y519178D02*
Y526684D01*
X1206022D01*
Y519178D01*
G02X1203820I-1101J-1021D01*
G37*
G36*
G01X1197126D02*
Y526684D01*
X1199330D01*
Y519178D01*
G02X1197126I-1102J-1021D01*
G37*
G36*
G01X1180394Y519177D02*
Y526684D01*
X1182596D01*
Y519179D01*
G02X1180394Y519177I-1100J-1022D01*
G37*
G36*
G01X1173700D02*
Y526684D01*
X1175904D01*
Y519179D01*
G02X1173700Y519177I-1101J-1022D01*
G37*
G36*
G01X1167008Y519178D02*
Y526684D01*
X1169212D01*
Y519178D01*
G02X1167008I-1102J-1021D01*
G37*
G36*
G01X1160316D02*
Y526684D01*
X1162518D01*
Y519178D01*
G02X1160316I-1101J-1021D01*
G37*
G36*
G01X1143582Y519177D02*
Y526684D01*
X1145786D01*
Y519179D01*
G02X1143582Y519177I-1101J-1022D01*
G37*
G36*
G01X1136890D02*
Y526684D01*
X1139092D01*
Y519179D01*
G02X1136890Y519177I-1100J-1022D01*
G37*
G36*
G01X1130198Y519178D02*
Y526684D01*
X1132400D01*
Y519178D01*
G02X1130198I-1101J-1021D01*
G37*
G36*
G01X1123504D02*
Y526684D01*
X1125708D01*
Y519178D01*
G02X1123504I-1102J-1021D01*
G37*
G36*
G01X1106772Y519177D02*
Y526684D01*
X1108974D01*
Y519179D01*
G02X1106772Y519177I-1100J-1022D01*
G37*
G36*
G01X1100078D02*
Y526684D01*
X1102282D01*
Y519179D01*
G02X1100078Y519177I-1101J-1022D01*
G37*
G36*
G01X949490Y519179D02*
Y526684D01*
X951692D01*
Y519177D01*
G02X949490Y519179I-1102J-1020D01*
G37*
G36*
G01X942796Y519178D02*
Y526684D01*
X944998D01*
Y519178D01*
G02X942796I-1101J-1021D01*
G37*
G36*
G01X926064D02*
Y526684D01*
X928266D01*
Y519178D01*
G02X926064I-1101J-1021D01*
G37*
G36*
G01X919370D02*
Y526684D01*
X921574D01*
Y519178D01*
G02X919370I-1102J-1021D01*
G37*
G36*
G01X912678D02*
Y526684D01*
X914880D01*
Y519178D01*
G02X912678I-1101J-1021D01*
G37*
G36*
G01X905984D02*
Y526684D01*
X908188D01*
Y519178D01*
G02X905984I-1102J-1021D01*
G37*
G36*
G01X889252D02*
Y526684D01*
X891456D01*
Y519178D01*
G02X889252I-1102J-1021D01*
G37*
G36*
G01X882560D02*
Y526684D01*
X884762D01*
Y519178D01*
G02X882560I-1101J-1021D01*
G37*
G36*
G01X875866D02*
Y526684D01*
X878070D01*
Y519178D01*
G02X875866I-1102J-1021D01*
G37*
G36*
G01X852442D02*
Y526684D01*
X854644D01*
Y519178D01*
G02X852442I-1101J-1021D01*
G37*
G36*
G01X845748D02*
Y526684D01*
X847952D01*
Y519178D01*
G02X845748I-1102J-1021D01*
G37*
G36*
G01X839056D02*
Y526684D01*
X841258D01*
Y519178D01*
G02X839056I-1101J-1021D01*
G37*
G36*
G01X832362D02*
Y526684D01*
X834566D01*
Y519178D01*
G02X832362I-1102J-1021D01*
G37*
G36*
G01X815630D02*
Y526684D01*
X817834D01*
Y519178D01*
G02X815630I-1102J-1021D01*
G37*
G36*
G01X808938D02*
Y526684D01*
X811140D01*
Y519178D01*
G02X808938I-1101J-1021D01*
G37*
G36*
G01X802244D02*
Y526684D01*
X804448D01*
Y519178D01*
G02X802244I-1102J-1021D01*
G37*
G36*
G01X795552D02*
Y526684D01*
X797754D01*
Y519178D01*
G02X795552I-1101J-1021D01*
G37*
G36*
G01X778820D02*
Y526684D01*
X781022D01*
Y519178D01*
G02X778820I-1101J-1021D01*
G37*
G36*
G01X772126D02*
Y526684D01*
X774330D01*
Y519178D01*
G02X772126I-1102J-1021D01*
G37*
G36*
G01X591022D02*
Y526684D01*
X593226D01*
Y519178D01*
G02X591022I-1102J-1021D01*
G37*
G36*
G01X584330D02*
Y526684D01*
X586532D01*
Y519178D01*
G02X584330I-1101J-1021D01*
G37*
G36*
G01X567596Y519177D02*
Y526684D01*
X569800D01*
Y519179D01*
G02X567596Y519177I-1101J-1022D01*
G37*
G36*
G01X560904D02*
Y526684D01*
X563106D01*
Y519179D01*
G02X560904Y519177I-1100J-1022D01*
G37*
G36*
G01X554212Y519178D02*
Y526684D01*
X556414D01*
Y519178D01*
G02X554212I-1101J-1021D01*
G37*
G36*
G01X547518D02*
Y526684D01*
X549722D01*
Y519178D01*
G02X547518I-1102J-1021D01*
G37*
G36*
G01X530786Y519177D02*
Y526684D01*
X532988D01*
Y519179D01*
G02X530786Y519177I-1100J-1022D01*
G37*
G36*
G01X524092D02*
Y526684D01*
X526296D01*
Y519179D01*
G02X524092Y519177I-1101J-1022D01*
G37*
G36*
G01X517400Y519178D02*
Y526684D01*
X519604D01*
Y519178D01*
G02X517400I-1102J-1021D01*
G37*
G36*
G01X510708D02*
Y526684D01*
X512910D01*
Y519178D01*
G02X510708I-1101J-1021D01*
G37*
G36*
G01X493974Y519177D02*
Y526684D01*
X496178D01*
Y519179D01*
G02X493974Y519177I-1101J-1022D01*
G37*
G36*
G01X487282D02*
Y526684D01*
X489484D01*
Y519179D01*
G02X487282Y519177I-1100J-1022D01*
G37*
G36*
G01X480590Y519178D02*
Y526684D01*
X482792D01*
Y519178D01*
G02X480590I-1101J-1021D01*
G37*
G36*
G01X473896D02*
Y526684D01*
X476100D01*
Y519178D01*
G02X473896I-1102J-1021D01*
G37*
G36*
G01X457164Y519177D02*
Y526684D01*
X459366D01*
Y519179D01*
G02X457164Y519177I-1100J-1022D01*
G37*
G36*
G01X450470D02*
Y526684D01*
X452674D01*
Y519179D01*
G02X450470Y519177I-1101J-1022D01*
G37*
G36*
G01X299882Y519179D02*
Y526684D01*
X302084D01*
Y519177D01*
G02X299882Y519179I-1102J-1020D01*
G37*
G36*
G01X293188Y519178D02*
Y526684D01*
X295390D01*
Y519178D01*
G02X293188I-1101J-1021D01*
G37*
G36*
G01X276456D02*
Y526684D01*
X278658D01*
Y519178D01*
G02X276456I-1101J-1021D01*
G37*
G36*
G01X269762D02*
Y526684D01*
X271966D01*
Y519178D01*
G02X269762I-1102J-1021D01*
G37*
G36*
G01X263070D02*
Y526684D01*
X265272D01*
Y519178D01*
G02X263070I-1101J-1021D01*
G37*
G36*
G01X256376D02*
Y526684D01*
X258580D01*
Y519178D01*
G02X256376I-1102J-1021D01*
G37*
G36*
G01X239644D02*
Y526684D01*
X241848D01*
Y519178D01*
G02X239644I-1102J-1021D01*
G37*
G36*
G01X232952D02*
Y526684D01*
X235154D01*
Y519178D01*
G02X232952I-1101J-1021D01*
G37*
G36*
G01X226258D02*
Y526684D01*
X228462D01*
Y519178D01*
G02X226258I-1102J-1021D01*
G37*
G36*
G01X202834D02*
Y526684D01*
X205036D01*
Y519178D01*
G02X202834I-1101J-1021D01*
G37*
G36*
G01X196140D02*
Y526684D01*
X198344D01*
Y519178D01*
G02X196140I-1102J-1021D01*
G37*
G36*
G01X189448D02*
Y526684D01*
X191650D01*
Y519178D01*
G02X189448I-1101J-1021D01*
G37*
G36*
G01X182754D02*
Y526684D01*
X184958D01*
Y519178D01*
G02X182754I-1102J-1021D01*
G37*
G36*
G01X166022D02*
Y526684D01*
X168226D01*
Y519178D01*
G02X166022I-1102J-1021D01*
G37*
G36*
G01X159330D02*
Y526684D01*
X161532D01*
Y519178D01*
G02X159330I-1101J-1021D01*
G37*
G36*
G01X152636D02*
Y526684D01*
X154840D01*
Y519178D01*
G02X152636I-1102J-1021D01*
G37*
G36*
G01X145944D02*
Y526684D01*
X148146D01*
Y519178D01*
G02X145944I-1101J-1021D01*
G37*
G36*
G01X129212D02*
Y526684D01*
X131414D01*
Y519178D01*
G02X129212I-1101J-1021D01*
G37*
G36*
G01X122518D02*
Y526684D01*
X124722D01*
Y519178D01*
G02X122518I-1102J-1021D01*
G37*
G36*
G01X1510005Y516654D02*
X1507444D01*
X1507441Y516653D01*
G02Y519657I-36J1502D01*
G01X1507444Y519656D01*
X1510005D01*
G02X1511506Y518165I0J-1501D01*
G01Y518070D01*
X1511497Y517986D01*
G02X1510005Y516654I-1492J169D01*
G37*
G36*
G01X53987Y525432D02*
G03X54513I263J302D01*
G02X56487I987J-1132D01*
G03X57013I263J302D01*
G02X59132Y523313I987J-1132D01*
G03Y522787I302J-263D01*
G02X59075Y520751I-1132J-987D01*
G03X59061Y520207I286J-280D01*
G02X56933Y518094I-1125J-995D01*
G03X56420Y518113I-268J-297D01*
G02X54397Y518281I-920J1187D01*
G03X54103I-147J-136D01*
G02X54037Y518214I-1102J1020D01*
G03X54036Y517925I138J-145D01*
G02X51848Y517819I-1044J-1079D01*
G03X51849Y518335I-305J259D01*
G02X51868Y520287I1151J965D01*
G03Y520813I-302J263D01*
G02Y522787I1132J987D01*
G03Y523313I-302J263D01*
G02X53987Y525432I1132J987D01*
G37*
G36*
G01X1025810Y517883D02*
G03Y517329I288J-277D01*
G02X1023790I-1010J-973D01*
G03Y517883I-288J277D01*
G02X1025810I1010J973D01*
G37*
G36*
G01X376202D02*
G03Y517329I288J-277D01*
G02X374182I-1010J-973D01*
G03Y517883I-288J277D01*
G02X376202I1010J973D01*
G37*
G36*
G01X1500655Y514620D02*
X1498091D01*
G02Y517624I-36J1502D01*
G01X1500655D01*
G02X1502156Y516132I-1J-1502D01*
G01Y516037D01*
X1502147Y515953D01*
G02X1500655Y514620I-1492J169D01*
G37*
G36*
G01X1483227Y514690D02*
G03X1482673I-277J-288D01*
G02Y516710I-973J1010D01*
G03X1483227I277J288D01*
G02Y514690I973J-1010D01*
G37*
G36*
G01X63468Y516587D02*
G03Y517113I-302J263D01*
G02X63617Y519235I1132J987D01*
G03X63596Y519857I-262J303D01*
G02X63343Y522008I907J1197D01*
G03X63317Y522545I-309J254D01*
G02X63282Y524631I1063J1061D01*
G03Y525177I-292J273D01*
G02X65087Y527527I1098J1025D01*
G03X65604Y527653I188J353D01*
G02X67972Y525813I1237J-852D01*
G03Y525287I302J-263D01*
G02X67864Y523201I-1132J-987D01*
G03X67853Y522919I136J-147D01*
G02X67882Y520913I-1103J-1019D01*
G03Y520387I302J-263D01*
G02Y518413I-1132J-987D01*
G03Y517887I302J-263D01*
G02X66485Y515422I-1132J-987D01*
G03X66032Y515148I-71J-394D01*
G02X63468Y516587I-1432J452D01*
G37*
G36*
G01X1314671Y516789D02*
G03Y516211I277J-289D01*
G02X1312729I-971J-1011D01*
G03Y516789I-277J289D01*
G02X1314671I971J1011D01*
G37*
G36*
G01X1230970Y514487D02*
G03Y513941I292J-273D01*
G02X1228778I-1096J-1027D01*
G03Y514487I-292J273D01*
G02X1230970I1096J1027D01*
G37*
G36*
G01X1194159D02*
G03Y513941I292J-273D01*
G02X1191967I-1096J-1027D01*
G03Y514487I-292J273D01*
G02X1194159I1096J1027D01*
G37*
G36*
G01X1157348D02*
G03Y513941I292J-273D01*
G02X1155156I-1096J-1027D01*
G03Y514487I-292J273D01*
G02X1157348I1096J1027D01*
G37*
G36*
G01X1120536D02*
G03Y513941I292J-273D01*
G02X1118344I-1096J-1027D01*
G03Y514487I-292J273D01*
G02X1120536I1096J1027D01*
G37*
G36*
G01X939828D02*
G03Y513941I292J-273D01*
G02X937636I-1096J-1027D01*
G03Y514487I-292J273D01*
G02X939828I1096J1027D01*
G37*
G36*
G01X903017D02*
G03Y513941I292J-273D01*
G02X900825I-1096J-1027D01*
G03Y514487I-292J273D01*
G02X903017I1096J1027D01*
G37*
G36*
G01X866206D02*
G03Y513941I292J-273D01*
G02X864014I-1096J-1027D01*
G03Y514487I-292J273D01*
G02X866206I1096J1027D01*
G37*
G36*
G01X829395D02*
G03Y513941I292J-273D01*
G02X827203I-1096J-1027D01*
G03Y514487I-292J273D01*
G02X829395I1096J1027D01*
G37*
G36*
G01X792584D02*
G03Y513941I292J-273D01*
G02X790392I-1096J-1027D01*
G03Y514487I-292J273D01*
G02X792584I1096J1027D01*
G37*
G36*
G01X581362D02*
G03Y513941I292J-273D01*
G02X579170I-1096J-1027D01*
G03Y514487I-292J273D01*
G02X581362I1096J1027D01*
G37*
G36*
G01X544551D02*
G03Y513941I292J-273D01*
G02X542359I-1096J-1027D01*
G03Y514487I-292J273D01*
G02X544551I1096J1027D01*
G37*
G36*
G01X507740D02*
G03Y513941I292J-273D01*
G02X505548I-1096J-1027D01*
G03Y514487I-292J273D01*
G02X507740I1096J1027D01*
G37*
G36*
G01X470928D02*
G03Y513941I292J-273D01*
G02X468736I-1096J-1027D01*
G03Y514487I-292J273D01*
G02X470928I1096J1027D01*
G37*
G36*
G01X290220D02*
G03Y513941I292J-273D01*
G02X288028I-1096J-1027D01*
G03Y514487I-292J273D01*
G02X290220I1096J1027D01*
G37*
G36*
G01X253409D02*
G03Y513941I292J-273D01*
G02X251217I-1096J-1027D01*
G03Y514487I-292J273D01*
G02X253409I1096J1027D01*
G37*
G36*
G01X216598D02*
G03Y513941I292J-273D01*
G02X214406I-1096J-1027D01*
G03Y514487I-292J273D01*
G02X216598I1096J1027D01*
G37*
G36*
G01X179787D02*
G03Y513941I292J-273D01*
G02X177595I-1096J-1027D01*
G03Y514487I-292J273D01*
G02X179787I1096J1027D01*
G37*
G36*
G01X142976D02*
G03Y513941I292J-273D01*
G02X140784I-1096J-1027D01*
G03Y514487I-292J273D01*
G02X142976I1096J1027D01*
G37*
G36*
G01X1775235Y513745D02*
G03X1775789Y513710I295J270D01*
G02X1775660Y511695I906J-1070D01*
G03X1775106Y511730I-295J-270D01*
G02X1775235Y513745I-906J1070D01*
G37*
G36*
G01X1225870Y514273D02*
G03Y513727I292J-273D01*
G02X1223678I-1096J-1027D01*
G03Y514273I-292J273D01*
G02X1225870I1096J1027D01*
G37*
G36*
G01X1189059D02*
G03Y513727I292J-273D01*
G02X1186867I-1096J-1027D01*
G03Y514273I-292J273D01*
G02X1189059I1096J1027D01*
G37*
G36*
G01X1152248D02*
G03Y513727I292J-273D01*
G02X1150056I-1096J-1027D01*
G03Y514273I-292J273D01*
G02X1152248I1096J1027D01*
G37*
G36*
G01X1115436D02*
G03Y513727I292J-273D01*
G02X1113244I-1096J-1027D01*
G03Y514273I-292J273D01*
G02X1115436I1096J1027D01*
G37*
G36*
G01X934728D02*
G03Y513727I292J-273D01*
G02X932536I-1096J-1027D01*
G03Y514273I-292J273D01*
G02X934728I1096J1027D01*
G37*
G36*
G01X897917D02*
G03Y513727I292J-273D01*
G02X895725I-1096J-1027D01*
G03Y514273I-292J273D01*
G02X897917I1096J1027D01*
G37*
G36*
G01X861106D02*
G03Y513727I292J-273D01*
G02X858914I-1096J-1027D01*
G03Y514273I-292J273D01*
G02X861106I1096J1027D01*
G37*
G36*
G01X824295D02*
G03Y513727I292J-273D01*
G02X822103I-1096J-1027D01*
G03Y514273I-292J273D01*
G02X824295I1096J1027D01*
G37*
G36*
G01X787484D02*
G03Y513727I292J-273D01*
G02X785292I-1096J-1027D01*
G03Y514273I-292J273D01*
G02X787484I1096J1027D01*
G37*
G36*
G01X576262D02*
G03Y513727I292J-273D01*
G02X574070I-1096J-1027D01*
G03Y514273I-292J273D01*
G02X576262I1096J1027D01*
G37*
G36*
G01X539451D02*
G03Y513727I292J-273D01*
G02X537259I-1096J-1027D01*
G03Y514273I-292J273D01*
G02X539451I1096J1027D01*
G37*
G36*
G01X502640D02*
G03Y513727I292J-273D01*
G02X500448I-1096J-1027D01*
G03Y514273I-292J273D01*
G02X502640I1096J1027D01*
G37*
G36*
G01X465828D02*
G03Y513727I292J-273D01*
G02X463636I-1096J-1027D01*
G03Y514273I-292J273D01*
G02X465828I1096J1027D01*
G37*
G36*
G01X285120D02*
G03Y513727I292J-273D01*
G02X282928I-1096J-1027D01*
G03Y514273I-292J273D01*
G02X285120I1096J1027D01*
G37*
G36*
G01X248309D02*
G03Y513727I292J-273D01*
G02X246117I-1096J-1027D01*
G03Y514273I-292J273D01*
G02X248309I1096J1027D01*
G37*
G36*
G01X211498D02*
G03Y513727I292J-273D01*
G02X209306I-1096J-1027D01*
G03Y514273I-292J273D01*
G02X211498I1096J1027D01*
G37*
G36*
G01X174687D02*
G03Y513727I292J-273D01*
G02X172495I-1096J-1027D01*
G03Y514273I-292J273D01*
G02X174687I1096J1027D01*
G37*
G36*
G01X137876D02*
G03Y513727I292J-273D01*
G02X135684I-1096J-1027D01*
G03Y514273I-292J273D01*
G02X137876I1096J1027D01*
G37*
G36*
G01X1460011Y514043D02*
G03X1459949Y513438I227J-329D01*
G02X1458137Y513623I-1014J-968D01*
G03X1458199Y514228I-227J329D01*
G02X1460186Y516206I1014J968D01*
G03X1460740I277J288D01*
G02Y514186I973J-1010D01*
G03X1460186I-277J-288D01*
G02X1460011Y514043I-972J1011D01*
G37*
G36*
G01X730626Y510592D02*
G03X730049Y510570I-278J-288D01*
G02X729974Y512508I-1049J930D01*
G03X730551Y512530I278J288D01*
G02X730626Y510592I1049J-930D01*
G37*
G36*
G01X1506985Y512146D02*
X1509546D01*
X1509549Y512147D01*
G02Y509143I36J-1502D01*
G01X1509546Y509144D01*
X1506984D01*
G02X1506985Y512146I1J1501D01*
G37*
G36*
G01X1614027Y509290D02*
G03X1613473I-277J-288D01*
G02Y511310I-973J1010D01*
G03X1614027I277J288D01*
G02Y509290I973J-1010D01*
G37*
G36*
G01X683958Y531151D02*
G03X683803Y531684I-354J186D01*
G02X685742Y532249I697J1216D01*
G03X685897Y531716I354J-186D01*
G02X686577Y530763I-697J-1216D01*
G01X686608Y530600D01*
X700414D01*
X704000Y527014D01*
Y519586D01*
X703400Y518986D01*
Y510186D01*
X702014Y508800D01*
X679814D01*
X678914Y507900D01*
X674486D01*
X673300Y509086D01*
Y517086D01*
X673286Y517100D01*
X671586D01*
X670000Y518686D01*
Y526914D01*
X673686Y530600D01*
X683792D01*
X683823Y530763D01*
G02X683958Y531151I1377J-262D01*
G37*
G36*
G01X1549341Y510717D02*
G03X1549325Y510156I277J-289D01*
G02X1547275I-1025J-956D01*
G03X1547259Y510717I-293J272D01*
G02X1549341I1041J1083D01*
G37*
G36*
G01X721845Y510766D02*
G03X722033Y510244I365J-163D01*
G02X720134Y509558I-619J-1258D01*
G03X719946Y510080I-365J163D01*
G02X721845Y510766I619J1258D01*
G37*
G36*
G01X1498277Y509740D02*
X1500838D01*
X1500841Y509741D01*
G02Y506737I36J-1502D01*
G01X1500838Y506738D01*
X1498276D01*
G02X1498277Y509740I1J1501D01*
G37*
G36*
G01X1485692Y509502D02*
X1488293D01*
G02X1489794Y508010I0J-1501D01*
G01Y507915D01*
X1489785Y507831D01*
G02X1488293Y506498I-1492J168D01*
G01X1485692D01*
G02Y509502I0J1502D01*
G37*
G36*
G01X1481975Y506474D02*
X1479374D01*
G02X1479375Y509476I1J1501D01*
G01X1481975D01*
G02X1483476Y507985I0J-1501D01*
G01Y507890D01*
X1483467Y507806D01*
G02X1481975Y506474I-1492J169D01*
G37*
G36*
G01X115452Y509327D02*
G03Y508773I288J-277D01*
G02X113432I-1010J-973D01*
G03Y509327I-288J277D01*
G02X115452I1010J973D01*
G37*
G36*
G01X1844304Y507840D02*
G03X1843851Y507461I-54J-396D01*
G02X1842636Y508910I-1401J59D01*
G03X1843089Y509289I54J396D01*
G02X1844304Y507840I1401J-59D01*
G37*
G36*
G01X34223Y509289D02*
G03X34058Y509518I-197J32D01*
G02X33490Y509735I241J1482D01*
G03X32964Y509651I-216J-337D01*
G02X32610Y511865I-1164J949D01*
G03X33136Y511949I216J337D01*
G02X35288Y512131I1164J-949D01*
G03X35856Y512173I263J301D01*
G02X38495Y511340I1144J-973D01*
G03X38958Y510982I399J37D01*
G02X39428Y508015I241J-1483D01*
G03X39092Y507574I61J-395D01*
G02X36111Y507205I-1492J-174D01*
G03X35713Y507553I-397J-52D01*
G02X34223Y509289I-6J1502D01*
G37*
G36*
G01X1556448Y508744D02*
G03Y508190I288J-277D01*
G02X1554428I-1010J-973D01*
G03Y508744I-288J277D01*
G02X1556448I1010J973D01*
G37*
G36*
G01X1543516Y508517D02*
G03X1543500Y507956I277J-289D01*
G02X1541450I-1025J-956D01*
G03X1541434Y508517I-293J272D01*
G02X1543516I1041J1083D01*
G37*
G36*
G01X764960Y507567D02*
G03Y507013I288J-277D01*
G02X762940I-1010J-973D01*
G03Y507567I-288J277D01*
G02Y509513I1010J973D01*
G03Y510067I-288J277D01*
G02X764960I1010J973D01*
G03Y509513I288J-277D01*
G02Y507567I-1010J-973D01*
G37*
G36*
G01X703409Y505754D02*
G03X702898Y505399I-112J-384D01*
G02X701891Y506846I-1398J101D01*
G03X702402Y507201I112J384D01*
G02X703409Y505754I1398J-101D01*
G37*
G36*
G01X712207Y504510D02*
G03X711639I-284J-282D01*
G02X709492Y504695I-997J986D01*
G03X708872Y504741I-329J-228D01*
G02X709001Y506501I-1022J960D01*
G03X709621Y506455I329J228D01*
G02X711636Y506486I1022J-959D01*
G03X712204I284J282D01*
G02X714199Y506484I997J-986D01*
G03X714798Y506517I285J280D01*
G02X714901Y504666I1102J-867D01*
G03X714302Y504633I-285J-280D01*
G02X712207Y504510I-1102J867D01*
G37*
G36*
G01X1650037Y503846D02*
G03X1649482Y503744I-226J-330D01*
G02X1648998Y505777I-1152J800D01*
G03X1649539Y505936I191J351D01*
G02X1650037Y503846I1405J-770D01*
G37*
G36*
G01X1568662Y504677D02*
G03X1569135Y505096I74J393D01*
G02X1570261Y502751I3463J220D01*
G03X1569638Y502643I-270J-296D01*
G02X1568662Y504677I-1238J657D01*
G37*
G36*
G01X1508625Y504540D02*
X1511126D01*
G02X1512628Y503048I0J-1502D01*
G01Y503038D01*
G02X1511126Y501536I-1502J0D01*
G01X1508625D01*
G02Y504540I0J1502D01*
G37*
G36*
G01X1049882Y501472D02*
Y507050D01*
X1045392D01*
Y501472D01*
X1043190D01*
Y507450D01*
X1041950Y508689D01*
Y515011D01*
X1046536Y519596D01*
Y526684D01*
X1048738D01*
Y521150D01*
X1053228D01*
Y526684D01*
X1055432D01*
Y521150D01*
X1056576D01*
Y526684D01*
X1058778D01*
Y521150D01*
X1063268D01*
Y526684D01*
X1065472D01*
Y521150D01*
X1069962D01*
Y526684D01*
X1072164D01*
Y521150D01*
X1073308D01*
Y526684D01*
X1075510D01*
Y521150D01*
X1080000D01*
Y526684D01*
X1082204D01*
Y521150D01*
X1086694D01*
Y526684D01*
X1088896D01*
Y521150D01*
X1093386D01*
Y526684D01*
X1095590D01*
Y521172D01*
X1097450Y519311D01*
Y514189D01*
X1096550Y513289D01*
Y512211D01*
X1097250Y511511D01*
Y508889D01*
X1095590Y507228D01*
Y501472D01*
X1093386D01*
Y507050D01*
X1088896D01*
Y501472D01*
X1086694D01*
Y507050D01*
X1085550D01*
Y501472D01*
X1083346D01*
Y507050D01*
X1078856D01*
Y501472D01*
X1076654D01*
Y507050D01*
X1065472D01*
Y501472D01*
X1063268D01*
Y507050D01*
X1055432D01*
Y501472D01*
X1053228D01*
Y507050D01*
X1052086D01*
Y501472D01*
X1049882D01*
G37*
G36*
G01X392797Y515558D02*
X394850Y517611D01*
Y519511D01*
X396389Y521050D01*
X396928D01*
Y526684D01*
X399130D01*
Y521050D01*
X403620D01*
Y526684D01*
X405824D01*
Y521050D01*
X406968D01*
Y526684D01*
X409170D01*
Y521050D01*
X413660D01*
Y526684D01*
X415864D01*
Y521050D01*
X420354D01*
Y526684D01*
X422556D01*
Y521050D01*
X423700D01*
Y526684D01*
X425902D01*
Y521050D01*
X430392D01*
Y526684D01*
X432596D01*
Y521050D01*
X437086D01*
Y526684D01*
X439288D01*
Y521050D01*
X443778D01*
Y526684D01*
X445982D01*
Y521080D01*
X447850Y519211D01*
Y514189D01*
X446850Y513189D01*
Y512211D01*
X447650Y511411D01*
Y508689D01*
X445982Y507020D01*
Y501472D01*
X443778D01*
Y507050D01*
X439288D01*
Y501472D01*
X437086D01*
Y507050D01*
X435942D01*
Y501472D01*
X433738D01*
Y507050D01*
X429248D01*
Y501472D01*
X427046D01*
Y507050D01*
X415864D01*
Y501472D01*
X413660D01*
Y507050D01*
X405824D01*
Y501472D01*
X403620D01*
Y507050D01*
X402478D01*
Y501472D01*
X400274D01*
Y507050D01*
X395784D01*
Y501472D01*
X393582D01*
Y507558D01*
X392550Y508589D01*
Y514965D01*
G02X392797Y515558I751J35D01*
G37*
G36*
G01X1549310Y503027D02*
G03Y502473I288J-277D01*
G02X1547290I-1010J-973D01*
G03Y503027I-288J277D01*
G02X1549310I1010J973D01*
G37*
G36*
G01X1528002Y503810D02*
Y501300D01*
G02X1524998I-1502J0D01*
G01Y503801D01*
G02X1528002Y503810I1502J-1D01*
G37*
G36*
G01X675626Y500292D02*
G03X675049Y500270I-278J-288D01*
G02X672987Y500231I-1049J930D01*
G03X672432Y500253I-289J-277D01*
G02X672513Y502269I-932J1047D01*
G03X673068Y502247I289J277D01*
G02X674974Y502208I932J-1047D01*
G03X675551Y502230I278J288D01*
G02X675626Y500292I1049J-930D01*
G37*
G36*
G01X1738703Y502186D02*
G03X1738508Y501612I149J-371D01*
G02X1736777Y502201I-1208J-712D01*
G03X1736972Y502775I-149J371D01*
G02X1738703Y502186I1208J712D01*
G37*
G36*
G01X1874950Y501383D02*
G03X1875469Y501146I376J136D01*
G02X1874655Y499359I504J-1308D01*
G03X1874136Y499596I-376J-136D01*
G02X1874950Y501383I-504J1308D01*
G37*
G36*
G01X648006Y500173D02*
G03X647601Y499757I-5J-400D01*
G02X646219Y501102I-1401J-57D01*
G03X646624Y501518I5J400D01*
G02X648006Y500173I1401J57D01*
G37*
G36*
G01X1269329Y500380D02*
G03X1268968Y499918I34J-398D01*
G02X1267464Y501091I-1384J-224D01*
G03X1267825Y501553I-34J398D01*
G02X1269329Y500380I1384J224D01*
G37*
G36*
G01X745051Y498664D02*
G03X744497I-277J-288D01*
G02X742514Y500647I-973J1010D01*
G03Y501201I-288J277D01*
G02X744497Y503184I1010J973D01*
G03X745051I277J288D01*
G02X746997I973J-1010D01*
G03X747551I277J288D01*
G02X749401Y501080I973J-1010D01*
G03Y500768I125J-156D01*
G02X749485Y500695I-877J-1094D01*
G03X749786Y500725I138J145D01*
G02X750099Y498788I1145J-809D01*
G03X749564Y498734I-238J-322D01*
G02X747551Y498664I-1040J940D01*
G03X746997I-277J-288D01*
G02X745051I-973J1010D01*
G37*
G36*
G01X1532695Y501067D02*
G03Y500513I288J-277D01*
G02X1530675I-1010J-973D01*
G03Y501067I-288J277D01*
G02X1532695I1010J973D01*
G37*
G36*
G01X1556520Y501002D02*
G03Y500448I288J-277D01*
G02X1554500I-1010J-973D01*
G03Y501002I-288J277D01*
G02X1556520I1010J973D01*
G37*
G36*
G01X1543485Y500927D02*
G03Y500373I288J-277D01*
G02X1541465I-1010J-973D01*
G03Y500927I-288J277D01*
G02X1543485I1010J973D01*
G37*
G36*
G01X710341Y498494D02*
G03X709755Y498476I-285J-281D01*
G02X709698Y500384I-1055J923D01*
G03X710284Y500402I285J281D01*
G02X710341Y498494I1055J-923D01*
G37*
G36*
G01X1336011Y498417D02*
G03X1335389I-311J-252D01*
G02Y500183I-1089J883D01*
G03X1336011I311J252D01*
G02Y498417I1089J-883D01*
G37*
G36*
G01X1705728Y500548D02*
G03X1705739Y499999I296J-269D01*
G02X1703425Y497782I-1143J-1123D01*
G03X1702908Y497840I-292J-273D01*
G02X1700748Y500156I-903J1323D01*
G03X1700722Y500682I-314J248D01*
G02X1703017Y502917I1152J1113D01*
G03X1703551Y502884I285J280D01*
G02X1705728Y500548I993J-1257D01*
G37*
G36*
G01X1084646Y498007D02*
G03X1084202Y497618I-44J-398D01*
G02X1082954Y499043I-1402J31D01*
G03X1083398Y499432I44J398D01*
G02X1084646Y498007I1402J-31D01*
G37*
G36*
G01X435038D02*
G03X434594Y497618I-44J-398D01*
G02X433346Y499043I-1402J31D01*
G03X433790Y499432I44J398D01*
G02X435038Y498007I1402J-31D01*
G37*
G36*
G01X-17651Y498430D02*
G03X-17666Y499031I-271J294D01*
G02X-15815Y499076I900J1075D01*
G03X-15800Y498475I271J-294D01*
G02X-17651Y498430I-900J-1075D01*
G37*
G36*
G01X1673481Y498725D02*
G03X1673416Y498165I250J-313D01*
G02X1671438Y498395I-1103J-865D01*
G03X1671503Y498955I-250J313D01*
G02X1673481Y498725I1103J865D01*
G37*
G36*
G01X113060Y499007D02*
G03X113164Y498418I314J-248D01*
G02X111328Y498095I-737J-1193D01*
G03X111224Y498684I-314J248D01*
G02X113060Y499007I737J1193D01*
G37*
G36*
G01X1758575Y494894D02*
X1753575D01*
G02Y497918I0J1512D01*
G01X1758575D01*
G02X1760086Y496416I-1J-1512D01*
G01Y496321D01*
X1760077Y496237D01*
G02X1758575Y494894I-1502J169D01*
G37*
G36*
G01X1748125Y494888D02*
X1743124D01*
G02X1743125Y497912I1J1512D01*
G01X1748125D01*
G02X1749636Y496410I-1J-1512D01*
G01Y496315D01*
X1749627Y496231D01*
G02X1748125Y494888I-1502J168D01*
G37*
G36*
G01X1419542Y495324D02*
X1428842D01*
Y493322D01*
X1419840D01*
Y493523D01*
X1419547D01*
X1419487Y493452D01*
G02X1419542Y495324I-1146J970D01*
G37*
G36*
G01X1157348Y495140D02*
G03Y494594I292J-273D01*
G02X1155156I-1096J-1027D01*
G03Y495140I-292J273D01*
G02X1157348I1096J1027D01*
G37*
G36*
G01X507740D02*
G03Y494594I292J-273D01*
G02X505548I-1096J-1027D01*
G03Y495140I-292J273D01*
G02X507740I1096J1027D01*
G37*
G36*
G01X1194121Y495143D02*
G03Y494575I282J-284D01*
G02X1192005I-1058J-1066D01*
G03Y495143I-282J284D01*
G02X1194121I1058J1066D01*
G37*
G36*
G01X544513D02*
G03Y494575I282J-284D01*
G02X542397I-1058J-1066D01*
G03Y495143I-282J284D01*
G02X544513I1058J1066D01*
G37*
G36*
G01X1152226Y495101D02*
G03Y494533I282J-284D01*
G02X1150110I-1058J-1066D01*
G03Y495101I-282J284D01*
G02X1152226I1058J1066D01*
G37*
G36*
G01X502618D02*
G03Y494533I282J-284D01*
G02X500502I-1058J-1066D01*
G03Y495101I-282J284D01*
G02X502618I1058J1066D01*
G37*
G36*
G01X939828Y494917D02*
G03Y494371I292J-273D01*
G02X937636I-1096J-1027D01*
G03Y494917I-292J273D01*
G02X939828I1096J1027D01*
G37*
G36*
G01X934743D02*
G03Y494371I292J-273D01*
G02X932551I-1096J-1027D01*
G03Y494917I-292J273D01*
G02X934743I1096J1027D01*
G37*
G36*
G01X290220D02*
G03Y494371I292J-273D01*
G02X288028I-1096J-1027D01*
G03Y494917I-292J273D01*
G02X290220I1096J1027D01*
G37*
G36*
G01X285135D02*
G03Y494371I292J-273D01*
G02X282943I-1096J-1027D01*
G03Y494917I-292J273D01*
G02X285135I1096J1027D01*
G37*
G36*
G01X1296341Y494226D02*
G03X1296927Y494180I314J248D01*
G02X1296777Y492283I951J-1030D01*
G03X1296191Y492329I-314J-248D01*
G02X1296341Y494226I-951J1030D01*
G37*
G36*
G01X903017Y494787D02*
G03Y494241I292J-273D01*
G02X900825I-1096J-1027D01*
G03Y494787I-292J273D01*
G02X903017I1096J1027D01*
G37*
G36*
G01X253409D02*
G03Y494241I292J-273D01*
G02X251217I-1096J-1027D01*
G03Y494787I-292J273D01*
G02X253409I1096J1027D01*
G37*
G36*
G01X1189036Y494843D02*
G03Y494275I282J-284D01*
G02X1186920I-1058J-1066D01*
G03Y494843I-282J284D01*
G02X1189036I1058J1066D01*
G37*
G36*
G01X897894D02*
G03Y494275I282J-284D01*
G02X895778I-1058J-1066D01*
G03Y494843I-282J284D01*
G02X897894I1058J1066D01*
G37*
G36*
G01X539428D02*
G03Y494275I282J-284D01*
G02X537312I-1058J-1066D01*
G03Y494843I-282J284D01*
G02X539428I1058J1066D01*
G37*
G36*
G01X248286D02*
G03Y494275I282J-284D01*
G02X246170I-1058J-1066D01*
G03Y494843I-282J284D01*
G02X248286I1058J1066D01*
G37*
G36*
G01X694614Y493330D02*
G03Y492776I288J-277D01*
G02X692594I-1010J-973D01*
G03Y493330I-288J277D01*
G02X694614I1010J973D01*
G37*
G36*
G01X690835Y493282D02*
G03Y492728I288J-277D01*
G02X688815I-1010J-973D01*
G03Y493282I-288J277D01*
G02X690835I1010J973D01*
G37*
G36*
G01X1842089Y490529D02*
G03X1841511I-289J-277D01*
G02X1839529Y492511I-1011J971D01*
G03Y493089I-277J289D01*
G02X1841511Y495071I971J1011D01*
G03X1842089I289J277D01*
G02X1844071Y493089I1011J-971D01*
G03Y492511I277J-289D01*
G02X1842089Y490529I-971J-1011D01*
G37*
G36*
G01X89350Y490392D02*
G03X88830I-260J-304D01*
G02X86572Y492650I-1040J1218D01*
G03Y493170I-304J260D01*
G02X86592Y495274I1218J1041D01*
G03X86602Y495793I-299J265D01*
G02X86622Y497850I1238J1017D01*
G03Y498370I-304J260D01*
G02X88880Y500628I1218J1040D01*
G03X89400I260J304D01*
G02X91480I1040J-1218D01*
G03X92000I260J304D01*
G02X94080I1040J-1218D01*
G03X94600I260J304D01*
G02X96680I1040J-1218D01*
G03X97200I260J304D01*
G02X99458Y498370I1040J-1218D01*
G03Y497850I304J-260D01*
G02X97776Y495277I-1218J-1040D01*
G03X97283Y494758I-117J-383D01*
G02X94663Y493062I-1506J-545D01*
G03X94106Y493061I-278J-288D01*
G02X91834Y493101I-1116J1149D01*
G03X91546I-144J-139D01*
G02X91499Y493054I-1156J1109D01*
G03Y492766I139J-144D01*
G02X89350Y490392I-1109J-1156D01*
G37*
G36*
G01X1249880Y490086D02*
G03X1249721Y489554I196J-348D01*
G02X1247787Y490135I-1247J-641D01*
G03X1247946Y490667I-196J348D01*
G02X1249880Y490086I1247J641D01*
G37*
G36*
G01X1819124Y490442D02*
X1824125D01*
G02X1825636Y488940I-1J-1512D01*
G01Y488845D01*
X1825627Y488761D01*
G02X1824125Y487418I-1502J169D01*
G01X1819124D01*
G02Y490442I0J1512D01*
G37*
G36*
G01X1796124D02*
X1801125D01*
G02X1802636Y488940I-1J-1512D01*
G01Y488845D01*
X1802627Y488761D01*
G02X1801125Y487418I-1502J169D01*
G01X1796124D01*
G02Y490442I0J1512D01*
G37*
G36*
G01X1784524D02*
X1789525D01*
G02X1791036Y488940I-1J-1512D01*
G01Y488845D01*
X1791027Y488761D01*
G02X1789525Y487418I-1502J169D01*
G01X1784524D01*
G02Y490442I0J1512D01*
G37*
G36*
G01X1811975Y487218D02*
X1806975D01*
G02Y490242I0J1512D01*
G01X1811975D01*
G02X1813486Y488740I-1J-1512D01*
G01Y488645D01*
X1813477Y488561D01*
G02X1811975Y487218I-1502J169D01*
G37*
G36*
G01X1754300Y486344D02*
X1749299D01*
G02X1749300Y489366I1J1511D01*
G01X1754300D01*
G02X1755812Y487865I0J-1512D01*
G01Y487770D01*
X1755802Y487686D01*
G02X1754300Y486344I-1502J170D01*
G37*
G36*
G01X1741900Y486244D02*
X1736899D01*
G02X1736900Y489266I1J1511D01*
G01X1741900D01*
G02X1743412Y487765I0J-1512D01*
G01Y487670D01*
X1743402Y487586D01*
G02X1741900Y486244I-1502J170D01*
G37*
G36*
G01X1770325Y485844D02*
X1765324D01*
G02X1765325Y488866I1J1511D01*
G01X1770325D01*
G02X1771836Y487365I0J-1511D01*
G01Y487270D01*
X1771827Y487186D01*
G02X1770325Y485844I-1502J169D01*
G37*
G36*
G01X721807Y486893D02*
G03X721585Y486360I145J-373D01*
G02X719794Y487107I-1285J-560D01*
G03X720016Y487640I-145J373D01*
G02X721934Y489451I1285J560D01*
G03X722487Y489661I181J357D01*
G02X723159Y487897I1305J-513D01*
G03X722606Y487687I-181J-357D01*
G02X721807Y486893I-1304J514D01*
G37*
G36*
G01X676752Y484669D02*
G03X676148Y484662I-299J-266D01*
G02X676128Y486501I-1068J908D01*
G03X676732Y486508I299J266D01*
G02X678732Y486647I1068J-908D01*
G03X679287Y486669I266J299D01*
G02X679368Y484653I1013J-969D01*
G03X678813Y484631I-266J-299D01*
G02X676752Y484669I-1013J969D01*
G37*
G36*
G01X1841471Y486239D02*
G03Y485661I277J-289D01*
G02X1839529I-971J-1011D01*
G03Y486239I-277J289D01*
G02X1841471I971J1011D01*
G37*
G36*
G01X610478Y485035D02*
G03X611039Y485021I288J278D01*
G02X610992Y483025I961J-1021D01*
G03X610431Y483039I-288J-278D01*
G02X610478Y485035I-961J1021D01*
G37*
G36*
G01X709168Y482570D02*
G03X708585Y482538I-277J-289D01*
G02X708480Y484452I-1074J901D01*
G03X709063Y484484I277J289D01*
G02X709168Y482570I1074J-901D01*
G37*
G36*
G01X1652882Y483774D02*
G03X1652896Y483210I290J-275D01*
G02X1650911Y483164I-970J-1013D01*
G03X1650897Y483728I-290J275D01*
G02X1652882Y483774I970J1013D01*
G37*
G36*
G01X1616627Y480390D02*
G03X1616073I-277J-288D01*
G02Y482410I-973J1010D01*
G03X1616627I277J288D01*
G02Y480390I973J-1010D01*
G37*
G36*
G01X1672021Y482589D02*
G03Y482011I277J-289D01*
G02X1670079I-971J-1011D01*
G03Y482589I-277J289D01*
G02X1672021I971J1011D01*
G37*
G36*
G01X606268Y482376D02*
G03X606278Y481843I303J-261D01*
G02X604187Y481806I-1029J-952D01*
G03X604177Y482339I-303J261D01*
G02X606268Y482376I1029J952D01*
G37*
G36*
G01X1291510Y481727D02*
G03Y481173I288J-277D01*
G02X1289490I-1010J-973D01*
G03Y481727I-288J277D01*
G02X1291510I1010J973D01*
G37*
G36*
G01X1794975Y477788D02*
X1789974D01*
G02X1789975Y480812I1J1512D01*
G01X1794975D01*
G02X1796486Y479310I-1J-1512D01*
G01Y479215D01*
X1796477Y479131D01*
G02X1794975Y477788I-1502J168D01*
G37*
G36*
G01X658794Y478143D02*
G03X658229Y478136I-279J-287D01*
G02X658203Y480122I-1002J980D01*
G03X658768Y480129I279J287D01*
G02X660708Y480191I1002J-980D01*
G03X661243I267J297D01*
G02Y478107I938J-1042D01*
G03X660708I-268J-297D01*
G02X658794Y478143I-938J1042D01*
G37*
G36*
G01X1817375Y476808D02*
X1812375D01*
G02Y479832I0J1512D01*
G01X1817375D01*
G02X1818886Y478330I-1J-1512D01*
G01Y478235D01*
X1818877Y478151D01*
G02X1817375Y476808I-1502J169D01*
G37*
G36*
G01X1442987Y478864D02*
G03X1443606Y479124I225J330D01*
G01X1452616D01*
Y477122D01*
X1443563D01*
X1443509Y477004D01*
G02X1442987Y478864I-1368J619D01*
G37*
G36*
G01X1829967Y475416D02*
X1825297D01*
G02Y478438I0J1511D01*
G01X1829967D01*
G02X1831478Y476937I0J-1511D01*
G01Y476842D01*
X1831469Y476758D01*
G02X1829967Y475416I-1502J169D01*
G37*
G36*
G01X1766700Y474144D02*
X1761699D01*
G02X1761700Y477166I1J1511D01*
G01X1766700D01*
G02X1768212Y475665I0J-1512D01*
G01Y475570D01*
X1768202Y475486D01*
G02X1766700Y474144I-1502J170D01*
G37*
G36*
G01X15473Y476510D02*
G03X16027I277J288D01*
G02Y474490I973J-1010D01*
G03X15473I-277J-288D01*
G02X13549Y474470I-973J1010D01*
G03X12988Y474451I-271J-294D01*
G02X12923Y476447I-1016J966D01*
G03X13484Y476466I271J294D01*
G02X15473Y476510I1016J-966D01*
G37*
G36*
G01X1779300Y473544D02*
X1774299D01*
G02X1774300Y476566I1J1511D01*
G01X1779300D01*
G02X1780812Y475065I0J-1512D01*
G01Y474970D01*
X1780802Y474886D01*
G02X1779300Y473544I-1502J170D01*
G37*
G36*
G01X1806525Y472444D02*
X1801524D01*
G02X1801525Y475466I1J1511D01*
G01X1806525D01*
G02X1808036Y473965I0J-1511D01*
G01Y473870D01*
X1808027Y473786D01*
G02X1806525Y472444I-1502J169D01*
G37*
G36*
G01X-13140Y474769D02*
G03X-12540I300J265D01*
G02Y472911I1050J-929D01*
G03X-13140I-300J-265D01*
G02Y474769I-1050J929D01*
G37*
G36*
G01X1679576Y472270D02*
G03X1679022Y472244I-263J-301D01*
G02X1678925Y474260I-1021J961D01*
G03X1679479Y474286I263J301D01*
G02X1679576Y472270I1021J-961D01*
G37*
G36*
G01X1895789Y469229D02*
G03X1895211I-289J-277D01*
G02X1893117Y471090I-1011J971D01*
G03X1893095Y471623I-309J254D01*
G02X1895111Y473571I1005J977D01*
G03X1895689I289J277D01*
G02X1897634Y473646I1011J-971D01*
G03X1898166I266J298D01*
G02X1900111Y473571I934J-1046D01*
G03X1900689I289J277D01*
G02X1902632Y473647I1011J-971D01*
G03X1903187Y473669I266J299D01*
G02X1905283Y471810I1013J-969D01*
G03X1905305Y471277I309J-254D01*
G02X1903368Y469253I-1005J-977D01*
G03X1902813Y469231I-266J-299D01*
G02X1900789Y469229I-1013J969D01*
G03X1900211I-289J-277D01*
G02X1898266Y469154I-1011J971D01*
G03X1897734I-266J-298D01*
G02X1895789Y469229I-934J1046D01*
G37*
G36*
G01X1634422Y471660D02*
G03X1634365Y471124I265J-299D01*
G02X1632012Y471373I-1290J-950D01*
G03X1632069Y471909I-265J299D01*
G02X1634422Y471660I1290J950D01*
G37*
G36*
G01X1915424Y468001D02*
G03X1916048I312J250D01*
G02X1916047Y465998I1250J-1002D01*
G03X1915423I-312J-250D01*
G02X1912903Y466023I-1250J1002D01*
G03X1912269I-317J-243D01*
G02Y467977I-1270J977D01*
G03X1912903I317J243D01*
G02X1915424Y468001I1270J-977D01*
G37*
G36*
G01X1463389Y464529D02*
G03X1462811I-289J-277D01*
G02Y466471I-1011J971D01*
G03X1463389I289J277D01*
G02Y464529I1011J-971D01*
G37*
G36*
G01X1455589D02*
G03X1455011I-289J-277D01*
G02Y466471I-1011J971D01*
G03X1455589I289J277D01*
G02Y464529I1011J-971D01*
G37*
G36*
G01X1667496Y465448D02*
G03X1667236Y465939I-384J111D01*
G02X1666657Y466306I438J1332D01*
G03X1666074Y466303I-290J-276D01*
G02X1666064Y468222I-1027J954D01*
G03X1666647Y468225I290J276D01*
G02X1669021Y466883I1027J-954D01*
G03X1669281Y466392I384J-111D01*
G02X1667496Y465448I-438J-1332D01*
G37*
G36*
G01X1322493Y464943D02*
G03X1323080Y464737I377J134D01*
G02X1322494Y463074I735J-1194D01*
G03X1321907Y463280I-377J-134D01*
G02X1322493Y464943I-735J1194D01*
G37*
G36*
G01X1343133Y462606D02*
G03X1342564Y462583I-273J-292D01*
G02X1342485Y464552I-1036J945D01*
G03X1343054Y464575I273J292D01*
G02X1345126I1036J-945D01*
G03X1345714Y464571I296J269D01*
G02X1345703Y462670I1025J-956D01*
G03X1345115Y462674I-296J-269D01*
G02X1343133Y462606I-1025J956D01*
G37*
G36*
G01X1624247Y462902D02*
G03X1624014Y462389I142J-374D01*
G02X1622202Y463211I-1314J-489D01*
G03X1622435Y463724I-142J374D01*
G02X1624247Y462902I1314J489D01*
G37*
G36*
G01X1586502Y459200D02*
G03X1585948I-277J-288D01*
G02X1583863Y459356I-973J1010D01*
G03X1583247Y459378I-317J-244D01*
G02X1580798Y460293I-1047J932D01*
G03X1580392Y460688I-400J-5D01*
G02X1581772Y462107I-22J1402D01*
G03X1582178Y461712I400J5D01*
G02X1582413Y461696I23J-1402D01*
G03X1582857Y462206I61J395D01*
G02X1585455Y461984I1343J404D01*
G03X1585627Y461451I358J-179D01*
G02X1585948Y461220I-650J-1242D01*
G03X1586502I277J288D01*
G02Y459200I973J-1010D01*
G37*
G36*
G01X1463389Y458829D02*
G03X1462811I-289J-277D01*
G02Y460771I-1011J971D01*
G03X1463389I289J277D01*
G02Y458829I1011J-971D01*
G37*
G36*
G01X1455589D02*
G03X1455011I-289J-277D01*
G02Y460771I-1011J971D01*
G03X1455589I289J277D01*
G02Y458829I1011J-971D01*
G37*
G36*
G01X1640942Y458579D02*
G03X1640920Y457958I241J-319D01*
G02X1639158Y458021I-920J-1058D01*
G03X1639180Y458642I-241J319D01*
G02X1640942Y458579I920J1058D01*
G37*
G36*
G01X1685410Y458414D02*
G03Y457839I279J-288D01*
G02X1683460I-975J-1007D01*
G03Y458414I-279J287D01*
G02X1685410I975J1007D01*
G37*
G36*
G01X1676848Y457738D02*
G03X1676782Y457142I230J-327D01*
G02X1674937Y457346I-1038J-942D01*
G03X1675003Y457942I-230J327D01*
G02X1676848Y457738I1038J942D01*
G37*
G36*
G01X1529333Y455957D02*
G03X1529260Y455398I245J-316D01*
G02X1527289Y455655I-1113J-852D01*
G03X1527362Y456214I-245J316D01*
G02X1529333Y455957I1113J852D01*
G37*
G36*
G01X1463389Y453129D02*
G03X1462811I-289J-277D01*
G02Y455071I-1011J971D01*
G03X1463389I289J277D01*
G02Y453129I1011J-971D01*
G37*
G36*
G01X1455589D02*
G03X1455011I-289J-277D01*
G02Y455071I-1011J971D01*
G03X1455589I289J277D01*
G02Y453129I1011J-971D01*
G37*
G36*
G01X1411986Y457571D02*
Y453476D01*
X1411977Y453392D01*
G02X1408964Y453561I-1502J169D01*
G01Y457561D01*
G02X1411986Y457571I1511J0D01*
G37*
G36*
G01X1404286D02*
Y453476D01*
X1404277Y453392D01*
G02X1401264Y453561I-1502J169D01*
G01Y457561D01*
G02X1404286Y457571I1511J0D01*
G37*
G36*
G01X1396886D02*
Y453476D01*
X1396877Y453392D01*
G02X1393864Y453561I-1502J169D01*
G01Y457562D01*
G02X1396886Y457571I1511J-1D01*
G37*
G36*
G01X1589693Y453068D02*
G03X1590295Y453064I303J261D01*
G02X1590283Y451217I1049J-930D01*
G03X1589681Y451221I-303J-261D01*
G02X1587504Y451319I-1049J930D01*
G03X1586902Y451367I-322J-238D01*
G02X1584927Y451378I-982J1001D01*
G03X1584325Y451338I-284J-282D01*
G02X1584201Y453175I-1117J847D01*
G03X1584803Y453215I284J282D01*
G02X1587048Y453200I1117J-847D01*
G03X1587650Y453152I322J238D01*
G02X1589693Y453068I982J-1001D01*
G37*
G36*
G01X1620175Y453672D02*
G03X1620664Y453361I393J77D01*
G02X1619625Y451728I336J-1361D01*
G03X1619136Y452039I-393J-77D01*
G02X1620175Y453672I-336J1361D01*
G37*
G36*
G01X1662542Y452789D02*
G03X1662548Y452234I291J-274D01*
G02X1660529Y452213I-999J-983D01*
G03X1660523Y452768I-291J274D01*
G02X1660492Y454703I999J984D01*
G03X1660481Y455257I-294J271D01*
G02X1662500Y455299I989J994D01*
G03X1662511Y454745I294J-271D01*
G02X1662542Y452789I-989J-994D01*
G37*
G36*
G01X1867886Y451591D02*
G03X1867450Y451172I-36J-398D01*
G02X1866179Y452496I-1400J-72D01*
G03X1866615Y452915I36J398D01*
G02X1869093Y453883I1400J72D01*
G03X1869715Y453891I308J256D01*
G02X1869737Y452126I1100J-869D01*
G03X1869115Y452118I-308J-256D01*
G02X1867886Y451591I-1100J869D01*
G37*
G36*
G01X1836495Y449088D02*
X1831494D01*
G02X1831495Y452112I1J1512D01*
G01X1836495D01*
G02X1838006Y450610I-1J-1512D01*
G01Y450515D01*
X1837997Y450431D01*
G02X1836495Y449088I-1502J168D01*
G37*
G36*
G01X1818760Y451920D02*
X1823760D01*
G02X1825272Y450418I0J-1512D01*
G01Y450323D01*
X1825262Y450239D01*
G02X1823760Y448896I-1502J169D01*
G01X1818760D01*
G02Y451920I0J1512D01*
G37*
G36*
G01X1811161Y448896D02*
X1806161D01*
G02Y451920I0J1512D01*
G01X1811161D01*
G02X1812672Y450418I-1J-1512D01*
G01Y450323D01*
X1812663Y450239D01*
G02X1811161Y448896I-1502J169D01*
G37*
G36*
G01X1793562Y451920D02*
X1798563D01*
G02X1800074Y450418I-1J-1512D01*
G01Y450323D01*
X1800065Y450239D01*
G02X1798563Y448896I-1502J169D01*
G01X1793562D01*
G02Y451920I1J1512D01*
G37*
G36*
G01X1780963D02*
X1785964D01*
G02X1787476Y450418I0J-1512D01*
G01Y450323D01*
X1787466Y450239D01*
G02X1785964Y448896I-1502J168D01*
G01X1780963D01*
G02Y451920I0J1512D01*
G37*
G36*
G01X1768366D02*
X1773366D01*
G02X1774878Y450418I0J-1512D01*
G01Y450323D01*
X1774868Y450239D01*
G02X1773366Y448896I-1502J169D01*
G01X1768366D01*
G02Y451920I0J1512D01*
G37*
G36*
G01X1760767Y448896D02*
X1755767D01*
G02Y451920I0J1512D01*
G01X1760767D01*
G02X1762278Y450418I-1J-1512D01*
G01Y450323D01*
X1762269Y450239D01*
G02X1760767Y448896I-1502J169D01*
G37*
G36*
G01X1748169D02*
X1743169D01*
G02Y451920I0J1512D01*
G01X1748169D01*
G02X1749680Y450418I-1J-1512D01*
G01Y450323D01*
X1749671Y450239D01*
G02X1748169Y448896I-1502J169D01*
G37*
G36*
G01X1470989Y449026D02*
G03X1470411I-289J-277D01*
G02Y450968I-1011J971D01*
G03X1470989I289J277D01*
G02Y449026I1011J-971D01*
G37*
G36*
G01X1463189D02*
G03X1462611I-289J-277D01*
G02Y450968I-1011J971D01*
G03X1463189I289J277D01*
G02Y449026I1011J-971D01*
G37*
G36*
G01X1631268Y451086D02*
G03X1631263Y450513I277J-289D01*
G02X1629308Y450531I-987J-996D01*
G03X1629313Y451104I-277J289D01*
G02X1629282Y453064I987J996D01*
G03X1629260Y453635I-291J275D01*
G02X1629190Y455648I940J1040D01*
G03Y456202I-288J277D01*
G02X1631210I1010J973D01*
G03Y455648I288J-277D01*
G02X1631218Y453711I-1010J-973D01*
G03X1631240Y453140I291J-275D01*
G02X1631268Y451086I-940J-1040D01*
G37*
G36*
G01X1682201Y450789D02*
G03X1682187Y450234I281J-285D01*
G02X1680168Y450283I-1033J-948D01*
G03X1680182Y450838I-281J285D01*
G02X1682201Y450789I1033J948D01*
G37*
G36*
G01X1873831Y449539D02*
G03Y448961I277J-289D01*
G02X1871889I-971J-1011D01*
G03Y449539I-277J289D01*
G02X1873831I971J1011D01*
G37*
G36*
G01X1887937Y446834D02*
G03X1887409Y446826I-259J-304D01*
G02X1887369Y449230I-1079J1184D01*
G03X1887897Y449238I259J304D01*
G02X1890236Y449043I1079J-1184D01*
G03X1890866I315J247D01*
G02X1893386I1260J-989D01*
G03X1894015I315J247D01*
G02Y447065I1260J-989D01*
G03X1893386I-314J-247D01*
G02X1890866I-1260J989D01*
G03X1890236I-315J-247D01*
G02X1887937Y446834I-1260J989D01*
G37*
G36*
G01X1647500Y449140D02*
G03X1647513Y448585I294J-271D01*
G02X1645494Y448540I-988J-995D01*
G03X1645481Y449095I-294J271D01*
G02X1645452Y451055I988J995D01*
G03X1645448Y451610I-290J275D01*
G02X1647468Y451625I1003J980D01*
G03X1647472Y451070I290J-275D01*
G02X1647500Y449140I-1003J-980D01*
G37*
G36*
G01X1677288Y448795D02*
G03X1677284Y448229I281J-285D01*
G02X1675303Y448243I-998J-985D01*
G03X1675307Y448809I-281J285D01*
G02X1677288Y448795I998J985D01*
G37*
G36*
G01X1674076Y447548D02*
G03X1674075Y446993I288J-278D01*
G02X1672056Y446996I-1011J-971D01*
G03X1672057Y447551I-288J278D01*
G02X1674076Y447548I1011J971D01*
G37*
G36*
G01X-719Y455008D02*
G03X-446Y455489I-115J383D01*
G02X2653Y455455I1554J390D01*
G03X2899Y454974I386J-106D01*
G02X3557Y452433I-560J-1501D01*
G03Y451913I304J-260D01*
G02Y449833I-1218J-1040D01*
G03Y449313I304J-260D01*
G02Y447233I-1218J-1040D01*
G03Y446713I304J-260D01*
G02X1299Y444455I-1218J-1040D01*
G03X779I-260J-304D01*
G02X-1479Y446713I-1040J1218D01*
G03Y447233I-304J260D01*
G02Y449313I1218J1040D01*
G03Y449833I-304J260D01*
G02Y451913I1218J1040D01*
G03Y452433I-304J260D01*
G02X-719Y455008I1218J1040D01*
G37*
G36*
G01X6783Y448093D02*
G03X7303I260J304D01*
G02X9791Y447561I1040J-1218D01*
G03X10362Y447392I361J171D01*
G02X9895Y445483I738J-1192D01*
G03X9310Y445598I-344J-204D01*
G02X7187Y445766I-967J1277D01*
G03X6899I-144J-139D01*
G02X6852Y445719I-1156J1109D01*
G03Y445431I139J-144D01*
G02X4525Y445315I-1109J-1156D01*
G03Y445835I-304J260D01*
G02X6783Y448093I1218J1040D01*
G37*
G36*
G01X1670826Y445480D02*
G03Y444926I288J-277D01*
G02X1668806I-1010J-973D01*
G03Y445480I-288J277D01*
G02Y447426I1010J973D01*
G03Y447980I-288J277D01*
G02X1670826I1010J973D01*
G03Y447426I288J-277D01*
G02Y445480I-1010J-973D01*
G37*
G36*
G01X1718140Y442709D02*
G03X1717978Y443287I-335J218D01*
G02X1717595Y443559I609J1263D01*
G03X1717029I-283J-282D01*
G02Y445541I-992J991D01*
G03X1717595I283J282D01*
G02X1719764Y443788I992J-991D01*
G03X1719926Y443210I335J-218D01*
G02X1718140Y442709I-609J-1263D01*
G37*
G36*
G01X10786Y443296D02*
X15787D01*
G02X17298Y441795I0J-1512D01*
G01Y441700D01*
X17288Y441616D01*
G02X15786Y440274I-1502J170D01*
G01X10786D01*
G02Y443296I0J1511D01*
G37*
G36*
G01X1413300Y442491D02*
G03X1413324Y441870I264J-301D01*
G02X1411559Y441802I-841J-1122D01*
G03X1411535Y442423I-264J301D01*
G02X1413300Y442491I841J1122D01*
G37*
G36*
G01X1589900Y441497D02*
G03X1590472Y441480I294J271D01*
G02X1590416Y439521I974J-1008D01*
G03X1589844Y439538I-294J-271D01*
G02X1589900Y441497I-974J1008D01*
G37*
G36*
G01X1613207Y441666D02*
G03X1613223Y441103I292J-273D01*
G02X1611232Y441045I-967J-1015D01*
G03X1611216Y441608I-292J273D01*
G02X1613207Y441666I967J1015D01*
G37*
G36*
G01X22936Y444354D02*
G02X25958Y444364I1511J0D01*
G01Y439354D01*
X25959D01*
X25958Y439269D01*
X25949Y439185D01*
G02X22936Y439354I-1502J169D01*
G01Y444354D01*
G37*
G36*
G01X750525Y439327D02*
G03X749900Y438975I-226J-330D01*
G02X747401Y439770I-1400J-75D01*
G03X747278Y440369I-314J248D01*
G02X748440Y442914I672J1231D01*
G03X748971Y443205I140J375D01*
G02X750525Y439327I3670J-780D01*
G37*
G36*
G01X1409123Y439924D02*
G03Y439309I257J-307D01*
G02X1407327I-898J-1076D01*
G03Y439924I-257J307D01*
G02X1409123I898J1076D01*
G37*
G36*
G01X1506427Y436187D02*
G03X1506443Y435632I296J-269D01*
G02X1504427Y435576I-981J-1002D01*
G03X1504411Y436131I-296J269D01*
G02X1506427Y436187I981J1002D01*
G37*
G36*
G01X1640510Y434727D02*
G03Y434173I288J-277D01*
G02X1638490I-1010J-973D01*
G03Y434727I-288J277D01*
G02X1640510I1010J973D01*
G37*
G36*
G01X1461099Y431902D02*
G03X1460510I-294J-271D01*
G02Y433800I-1032J949D01*
G03X1461099I295J271D01*
G02Y431902I1032J-949D01*
G37*
G36*
G01X1468386Y433869D02*
G03X1468958Y433852I294J271D01*
G02X1468900Y431892I973J-1010D01*
G03X1468328Y431909I-294J-271D01*
G02X1468386Y433869I-973J1010D01*
G37*
G36*
G01X1588351Y433445D02*
G03X1588973Y433428I318J243D01*
G02X1588924Y431663I1064J-913D01*
G03X1588302Y431680I-318J-243D01*
G02X1588351Y433445I-1064J913D01*
G37*
G36*
G01X1410812Y434785D02*
Y429690D01*
X1410802Y429606D01*
G02X1407788Y429775I-1502J169D01*
G01Y434776D01*
G02X1410812Y434785I1512J-1D01*
G37*
G36*
G01X1402910D02*
Y429690D01*
X1402900Y429606D01*
G02X1399886Y429775I-1502J169D01*
G01Y434776D01*
G02X1402910Y434785I1512J-1D01*
G37*
G36*
G01X1468885Y427046D02*
G03X1468305I-290J-276D01*
G02Y428980I-1015J967D01*
G03X1468885I290J276D01*
G02Y427046I1015J-967D01*
G37*
G36*
G01X1548776Y429391D02*
G03Y428844I292J-274D01*
G02X1546732I-1022J-960D01*
G03Y429391I-292J274D01*
G02X1548097Y431710I1022J960D01*
G03X1548579Y431986I98J388D01*
G02X1549582Y430235I1346J-392D01*
G03X1549100Y429959I-98J-388D01*
G02X1548776Y429391I-1346J392D01*
G37*
G36*
G01X1583820Y426607D02*
G03X1583311Y426307I-118J-382D01*
G02X1582352Y427934I-1372J287D01*
G03X1582861Y428234I118J382D01*
G02X1583820Y426607I1372J-287D01*
G37*
G36*
G01X17025Y423338D02*
X12024D01*
G02X12025Y426362I1J1512D01*
G01X17025D01*
G02X18536Y424860I-1J-1512D01*
G01Y424765D01*
X18527Y424681D01*
G02X17025Y423338I-1502J168D01*
G37*
G36*
G01X7025D02*
X2024D01*
G02X2025Y426362I1J1512D01*
G01X7025D01*
G02X8536Y424860I-1J-1512D01*
G01Y424765D01*
X8527Y424681D01*
G02X7025Y423338I-1502J168D01*
G37*
G36*
G01X62516Y424220D02*
X62507Y424136D01*
G02X59494Y424305I-1502J169D01*
G01Y429306D01*
G02X62516Y429315I1511J-1D01*
G01Y424220D01*
G37*
G36*
G01X1589368Y424272D02*
G03X1588961Y423864I-7J-400D01*
G02X1587587Y425237I-1402J-29D01*
G03X1587994Y425645I7J400D01*
G02X1589368Y424272I1402J29D01*
G37*
G36*
G01X1559675Y420042D02*
X1555775D01*
G02Y422866I0J1412D01*
G01X1559676D01*
G02X1561086Y421464I-1J-1412D01*
G01Y421370D01*
X1561076Y421286D01*
G02X1559675Y420042I-1401J167D01*
G37*
G36*
G01X1548790Y422624D02*
G03Y422084I295J-270D01*
G02X1546720I-1035J-946D01*
G03Y422624I-295J270D01*
G02X1548139Y424918I1035J946D01*
G03X1548629Y425181I109J385D01*
G02X1549580Y423405I1335J-428D01*
G03X1549090Y423142I-109J-385D01*
G02X1548790Y422624I-1335J427D01*
G37*
G36*
G01X1504996Y419784D02*
G03X1504478Y419514I-133J-377D01*
G02X1501738Y419711I-1350J378D01*
G03X1501304Y420058I-397J-51D01*
G02X1502565Y421635I-129J1396D01*
G03X1502999Y421288I397J51D01*
G02X1503591Y421215I128J-1396D01*
G03X1504109Y421485I133J377D01*
G02X1504508Y422137I1350J-378D01*
G03X1504541Y422692I-271J295D01*
G02X1506556Y422574I1064J912D01*
G03X1506523Y422019I271J-295D01*
G02X1504996Y419784I-1065J-912D01*
G37*
G36*
G01X50776Y424005D02*
Y418910D01*
X50767Y418826D01*
G02X47754Y418995I-1502J169D01*
G01Y423996D01*
G02X50776Y424005I1511J-1D01*
G37*
G36*
G01X1557725Y416662D02*
X1553824D01*
G02X1553825Y419486I1J1412D01*
G01X1554448D01*
G02X1554998Y418963I0J-551D01*
G03X1555016Y418813I777J17D01*
G02X1555159Y418507I-1189J-742D01*
G03X1556391I616J472D01*
G02X1556534Y418813I1332J-436D01*
G03X1556550Y419022I-759J163D01*
G02X1557050Y419486I500J-37D01*
G01X1557725D01*
G02X1559136Y418084I0J-1411D01*
G01Y417990D01*
X1559126Y417906D01*
G02X1557725Y416662I-1401J167D01*
G37*
G36*
G01X1413476Y416907D02*
X1413461Y417081D01*
X1413626Y421997D01*
X1413634Y422005D01*
X1413640Y422078D01*
G02X1416647Y422124I1506J-131D01*
G01X1416668Y421948D01*
X1416504Y417042D01*
X1416505D01*
X1416502Y416988D01*
X1416477Y416817D01*
G02X1413476Y416907I-1495J222D01*
G37*
G36*
G01X1405646Y421576D02*
G02X1408670Y421585I1512J-1D01*
G01Y416490D01*
X1408660Y416406D01*
G02X1405646Y416572I-1502J167D01*
G01Y421576D01*
G37*
G36*
G01X1567475Y413282D02*
X1563574D01*
G02X1563575Y416106I1J1412D01*
G01X1564198D01*
G02X1564748Y415583I0J-551D01*
G03X1564766Y415433I777J17D01*
G02X1564909Y415127I-1189J-742D01*
G03X1566141I616J472D01*
G02X1566284Y415433I1332J-436D01*
G03X1566300Y415642I-759J163D01*
G02X1566800Y416106I500J-37D01*
G01X1567475D01*
G02X1568886Y414704I0J-1411D01*
G01Y414610D01*
X1568876Y414526D01*
G02X1567475Y413282I-1401J167D01*
G37*
G36*
G01X767237Y416062D02*
G03X767281Y415483I296J-269D01*
G02X765357Y415340I-887J-1086D01*
G03X765313Y415919I-296J269D01*
G02X766261Y418406I887J1086D01*
G03X766678Y418800I17J399D01*
G02X768019Y417379I1402J-20D01*
G03X767602Y416985I-17J-399D01*
G02X767237Y416062I-1402J21D01*
G37*
G36*
G01X47006Y415201D02*
G03Y414590I258J-306D01*
G02X45194I-906J-1070D01*
G03Y415201I-258J305D01*
G02X47006I906J1070D01*
G37*
G36*
G01X1471147Y413091D02*
G03X1471720Y413069I297J268D01*
G02X1471647Y411116I968J-1014D01*
G03X1471074Y411138I-297J-268D01*
G02X1471147Y413091I-968J1014D01*
G37*
G36*
G01X1588551Y411003D02*
G03X1587996Y410990I-271J-295D01*
G02X1587949Y413008I-996J986D01*
G03X1588504Y413021I271J295D01*
G02X1588551Y411003I996J-986D01*
G37*
G36*
G01X120018Y413220D02*
G03X120037Y412643I286J-279D01*
G02X118098Y412581I-937J-1043D01*
G03X118079Y413158I-286J279D01*
G02X120018Y413220I937J1043D01*
G37*
G36*
G01X20473Y414391D02*
G03X21740Y414794I-2J2199D01*
G02X21756Y410156I1488J-2314D01*
G03X20502Y410569I-1283J-1786D01*
G01X20471D01*
G03X19204Y410166I2J-2199D01*
G02X19188Y414804I-1488J2314D01*
G03X20442Y414391I1283J1786D01*
G01X20473D01*
G37*
G36*
G01X3938D02*
G03X5205Y414794I-2J2199D01*
G02X5221Y410156I1488J-2314D01*
G03X3967Y410569I-1283J-1786D01*
G01X3936D01*
G03X2669Y410166I2J-2199D01*
G02X2653Y414804I-1488J2314D01*
G03X3907Y414391I1283J1786D01*
G01X3938D01*
G37*
G36*
G01X-12598D02*
G03X-11331Y414794I-2J2199D01*
G02X-11315Y410156I1488J-2314D01*
G03X-12569Y410569I-1283J-1786D01*
G01X-12599D01*
G03X-13866Y410166I2J-2199D01*
G02X-13882Y414804I-1488J2314D01*
G03X-12628Y414391I1283J1786D01*
G01X-12598D01*
G37*
G36*
G01X749612Y408828D02*
G03X749058I-277J-288D01*
G02X747075Y410811I-973J1010D01*
G03Y411365I-288J277D01*
G02X749058Y413348I1010J973D01*
G03X749612I277J288D01*
G02X751558I973J-1010D01*
G03X752112I277J288D01*
G02X753991Y413408I973J-1010D01*
G03X754524Y413422I259J305D01*
G02X755905Y413741I963J-1019D01*
G03X756424Y414133I119J382D01*
G02X758799Y415177I1402J34D01*
G03X759353I277J288D01*
G02X761303Y415172I972J-1010D01*
G03X761912Y415233I279J287D01*
G02X763960Y413358I1157J-793D01*
G03X763942Y412756I254J-309D01*
G02X761975Y410760I-953J-1028D01*
G03X761384Y410747I-290J-276D01*
G02X759353Y410657I-1058J920D01*
G03X758799I-277J-288D01*
G02X757408Y410329I-972J1010D01*
G03X756889Y409937I-119J-382D01*
G02X754581Y408833I-1402J-34D01*
G03X754048Y408819I-259J-305D01*
G02X752112Y408828I-963J1019D01*
G03X751558I-277J-288D01*
G02X749612I-973J1010D01*
G37*
G36*
G01X1403912Y408281D02*
Y413282D01*
G02X1406934Y413291I1511J-1D01*
G01Y408281D01*
X1406935D01*
X1406934Y408196D01*
X1406925Y408112D01*
G02X1403912Y408281I-1502J169D01*
G37*
G36*
G01X1571375Y406522D02*
X1567474D01*
G02X1567475Y409346I1J1412D01*
G01X1568098D01*
G02X1568648Y408823I0J-551D01*
G03X1568666Y408673I777J17D01*
G02X1568809Y408367I-1189J-742D01*
G03X1570041I616J472D01*
G02X1570184Y408673I1332J-436D01*
G03X1570200Y408882I-759J163D01*
G02X1570700Y409346I500J-37D01*
G01X1571375D01*
G02X1572786Y407944I0J-1411D01*
G01Y407850D01*
X1572776Y407766D01*
G02X1571375Y406522I-1401J167D01*
G37*
G36*
G01X1444049Y407876D02*
G03X1443955Y407308I227J-329D01*
G02X1442033Y407625I-1125J-836D01*
G03X1442127Y408193I-227J329D01*
G02X1444049Y407876I1125J836D01*
G37*
G36*
G01X106158Y407656D02*
G03X105910Y407071I100J-387D01*
G02X104120Y407831I-1393J-792D01*
G03X104368Y408416I-100J387D01*
G02X105975Y410796I1393J792D01*
G03X106425Y411249I54J396D01*
G02X107796Y409891I1585J230D01*
G03X107346Y409438I-54J-396D01*
G02X106158Y407656I-1585J-230D01*
G37*
G36*
G01X120709Y404984D02*
G03X120136Y405156I-363J-168D01*
G02X120670Y406937I-738J1192D01*
G03X121243Y406765I363J168D01*
G02X120709Y404984I738J-1192D01*
G37*
G36*
G01X47828Y404422D02*
X52509D01*
G03X52872Y404989I0J400D01*
G02X53088Y406598I1372J635D01*
G01X55227Y409137D01*
G02X57894Y408173I1156J-974D01*
G01Y408078D01*
X57885Y407994D01*
G02X57539Y407189I-1503J169D01*
G01X56228Y405632D01*
X56227D01*
X55422Y404678D01*
X55421Y404676D01*
G02X53839Y404168I-1177J948D01*
G03X53332Y403783I-107J-385D01*
G01Y402418D01*
X47828D01*
Y404422D01*
G37*
G36*
G01X1589833Y402984D02*
G03X1589253Y402806I-214J-338D01*
G02X1588716Y404554I-1285J562D01*
G03X1589296Y404732I214J338D01*
G02X1589833Y402984I1285J-562D01*
G37*
G36*
G01X25591Y406517D02*
G03X26858Y406920I-2J2199D01*
G02X26874Y402282I1488J-2314D01*
G03X25620Y402695I-1283J-1786D01*
G01X25590D01*
G03X24323Y402292I2J-2199D01*
G02X24307Y406930I-1488J2314D01*
G03X25561Y406517I1283J1786D01*
G01X25591D01*
G37*
G36*
G01X9056D02*
G03X10323Y406920I-2J2199D01*
G02X10339Y402282I1488J-2314D01*
G03X9085Y402695I-1283J-1786D01*
G01X9054D01*
G03X7787Y402292I2J-2199D01*
G02X7771Y406930I-1488J2314D01*
G03X9025Y406517I1283J1786D01*
G01X9056D01*
G37*
G36*
G01X-7480D02*
G03X-6213Y406920I-2J2199D01*
G02X-6197Y402282I1488J-2314D01*
G03X-7451Y402695I-1283J-1786D01*
G01X-7481D01*
G03X-8748Y402292I2J-2199D01*
G02X-8764Y406930I-1488J2314D01*
G03X-7510Y406517I1283J1786D01*
G01X-7480D01*
G37*
G36*
G01X66896Y403268D02*
Y403173D01*
X66886Y403089D01*
G02X64311Y402193I-1502J169D01*
G01X61973Y404550D01*
X61972Y404551D01*
G02X64097Y406701I1052J1085D01*
G01X65153Y405638D01*
X66457Y404323D01*
G02X66896Y403268I-1073J-1065D01*
G37*
G36*
G01X1383327Y397890D02*
G03X1382773I-277J-288D01*
G02X1380751Y399830I-973J1010D01*
G03X1380740Y400372I-299J265D01*
G02X1380658Y400466I1015J968D01*
G03X1380346I-156J-125D01*
G02X1378023Y400669I-1094J877D01*
G03X1377479Y400826I-350J-193D01*
G02X1375827Y401043I-679J1227D01*
G03X1375273I-277J-288D01*
G02Y403063I-973J1010D01*
G03X1375827I277J288D01*
G02X1378029Y402727I973J-1010D01*
G03X1378573Y402570I350J193D01*
G02X1380225Y402353I679J-1227D01*
G03X1380779I277J288D01*
G02X1382725I973J-1010D01*
G03X1383279I277J288D01*
G02X1385225I973J-1010D01*
G03X1385779I277J288D01*
G02X1387801Y400413I973J-1010D01*
G03X1387812Y399871I299J-265D01*
G02X1385827Y397890I-1012J-971D01*
G03X1385273I-277J-288D01*
G02X1383327I-973J1010D01*
G37*
G36*
G01X1586703Y396411D02*
G03X1586141Y396408I-279J-286D01*
G02X1586130Y398403I-991J992D01*
G03X1586692Y398406I279J286D01*
G02X1586703Y396411I991J-992D01*
G37*
G36*
G01X102620Y396017D02*
G03X102080I-270J-295D01*
G02X99817Y398280I-1080J1183D01*
G03Y398820I-295J270D01*
G02X102080Y401083I1183J1080D01*
G03X102620I270J295D01*
G02X104780I1080J-1183D01*
G03X105320I270J295D01*
G02X107480I1080J-1183D01*
G03X108020I270J295D01*
G02X110562Y400555I1080J-1183D01*
G03X111054Y400339I365J163D01*
G02X111173Y397265I507J-1520D01*
G03X110681Y396941I-97J-388D01*
G02X108020Y396017I-1581J259D01*
G03X107480I-270J-295D01*
G02X105320I-1080J1183D01*
G03X104780I-270J-295D01*
G02X102620I-1080J1183D01*
G37*
G36*
G01X1370996Y395697D02*
G03X1370418I-289J-277D01*
G02Y397639I-1011J971D01*
G03X1370996I289J277D01*
G02Y395697I1011J-971D01*
G37*
G36*
G01X1655811Y398206D02*
G03X1655831Y397649I297J-268D01*
G02X1653820Y397576I-970J-1012D01*
G03X1653800Y398133I-297J268D01*
G02X1653776Y400133I970J1012D01*
G03X1653784Y400688I-284J282D01*
G02X1655803Y400657I1024J957D01*
G03X1655795Y400102I284J-282D01*
G02X1655811Y398206I-1025J-957D01*
G37*
G36*
G01X3938Y398643D02*
G03X5205Y399046I-2J2199D01*
G02X5221Y394408I1488J-2314D01*
G03X3967Y394821I-1283J-1786D01*
G01X3936D01*
G03X2669Y394418I2J-2199D01*
G02X2653Y399056I-1488J2314D01*
G03X3907Y398643I1283J1786D01*
G01X3938D01*
G37*
G36*
G01X-12598D02*
G03X-11331Y399046I-2J2199D01*
G02X-11315Y394408I1488J-2314D01*
G03X-12569Y394821I-1283J-1786D01*
G01X-12599D01*
G03X-13866Y394418I2J-2199D01*
G02X-13882Y399056I-1488J2314D01*
G03X-12628Y398643I1283J1786D01*
G01X-12598D01*
G37*
G36*
G01X776372Y395822D02*
G03X776297Y395251I238J-322D01*
G02X774170Y395478I-1175J-935D01*
G03X774217Y396052I-253J310D01*
G02X774190Y396084I1211J1049D01*
G03X773893Y396095I-153J-128D01*
G02X771901Y395846I-1151J1114D01*
G03X771307Y395618I-210J-340D01*
G02X768542Y395042I-1537J452D01*
G03X767960Y395076I-307J-257D01*
G02X768088Y397268I-1100J1164D01*
G03X768670Y397234I307J257D01*
G02X770611Y397433I1100J-1164D01*
G03X771205Y397661I210J340D01*
G02X773857Y398359I1537J-452D01*
G03X774392Y398339I279J287D01*
G02X776372Y395822I1028J-1228D01*
G37*
G36*
G01X188611Y394532D02*
G03X189210Y394332I377J133D01*
G02X188589Y392468I890J-1332D01*
G03X187990Y392668I-377J-133D01*
G02X188611Y394532I-890J1332D01*
G37*
G36*
G01X66236Y391560D02*
X66227Y391476D01*
G02X63214Y391645I-1502J169D01*
G01Y396645D01*
G02X66236Y396655I1511J0D01*
G01Y391560D01*
G37*
G36*
G01X1662125Y389274D02*
G03X1662056Y388723I251J-311D01*
G02X1660052Y388973I-1122J-840D01*
G03X1660121Y389524I-251J311D01*
G02X1660264Y391367I1122J840D01*
G03Y391940I-280J286D01*
G02X1662222I979J1003D01*
G03Y391367I280J-286D01*
G02X1662125Y389274I-979J-1003D01*
G37*
G36*
G01X25591Y390769D02*
G03X26858Y391172I-2J2199D01*
G02X26874Y386534I1488J-2314D01*
G03X25620Y386947I-1283J-1786D01*
G01X25590D01*
G03X24323Y386544I2J-2199D01*
G02X24307Y391182I-1488J2314D01*
G03X25561Y390769I1283J1786D01*
G01X25591D01*
G37*
G36*
G01X702030Y383117D02*
G03X701477Y383037I-236J-323D01*
G02X698986Y385050I-1273J972D01*
G03Y385570I-304J260D01*
G02X699283Y387921I1218J1040D01*
G03X699320Y388545I-230J327D01*
G02X699248Y390859I1071J1191D01*
G03X699228Y391439I-285J281D01*
G02X699243Y393849I1063J1198D01*
G03X699276Y394421I-262J302D01*
G02X701339Y396841I1181J1082D01*
G03X701880Y396938I219J334D01*
G02X704312Y397109I1289J-952D01*
G03X704910Y397140I285J280D01*
G02X707276Y397296I1254J-997D01*
G03X707838Y397302I278J288D01*
G02X710027Y397383I1138J-1128D01*
G03X710546Y397378I262J302D01*
G02X712636Y394950I1028J-1229D01*
G03Y394350I265J-300D01*
G02Y391950I-1061J-1200D01*
G03Y391350I265J-300D01*
G02X712388Y388770I-1061J-1200D01*
G03X712308Y388143I203J-345D01*
G02X712356Y385932I-1135J-1131D01*
G03Y385392I295J-270D01*
G02X710012Y383208I-1184J-1079D01*
G03X709452Y383228I-290J-275D01*
G02X707293Y383229I-1079J1184D01*
G03X706753I-270J-295D01*
G02X704593I-1080J1183D01*
G03X704053I-270J-295D01*
G02X702030Y383117I-1080J1183D01*
G37*
G36*
G01X175811Y385108D02*
G03Y384508I265J-300D01*
G02X173689I-1061J-1200D01*
G03Y385108I-265J300D01*
G02Y387508I1061J1200D01*
G03Y388108I-265J300D01*
G02X175811I1061J1200D01*
G03Y387508I265J-300D01*
G02Y385108I-1061J-1200D01*
G37*
G36*
G01X822018Y381889D02*
G03X821418I-300J-265D01*
G02X819157Y384150I-1200J1061D01*
G03Y384750I-265J300D01*
G02X821418Y387011I1061J1200D01*
G03X822018I300J265D01*
G02X824380Y387052I1200J-1061D01*
G03X824956Y387047I290J275D01*
G02X827282Y384845I1141J-1124D01*
G03X827306Y384282I296J-269D01*
G02X825072Y381986I-1090J-1174D01*
G03X824473Y381955I-286J-280D01*
G02X822018Y381889I-1255J995D01*
G37*
G36*
G01X1465365Y384296D02*
G03X1465373Y383729I286J-280D01*
G02X1463396Y383699I-973J-1009D01*
G03X1463388Y384266I-286J280D01*
G02X1465365Y384296I973J1009D01*
G37*
G36*
G01X172219Y384568D02*
G03Y383968I265J-300D01*
G02X170097I-1061J-1200D01*
G03Y384568I-265J300D01*
G02Y386968I1061J1200D01*
G03Y387568I-265J300D01*
G02X172219I1061J1200D01*
G03Y386968I265J-300D01*
G02Y384568I-1061J-1200D01*
G37*
G36*
G01X1571657Y384060D02*
G03X1571944Y383585I390J-89D01*
G02X1570217Y382538I-359J-1355D01*
G03X1569930Y383013I-390J89D01*
G02X1571657Y384060I359J1355D01*
G37*
G36*
G01X3938Y382895D02*
G03X5205Y383298I-2J2199D01*
G02X5221Y378660I1488J-2314D01*
G03X3967Y379073I-1283J-1786D01*
G01X3936D01*
G03X2669Y378670I2J-2199D01*
G02X2653Y383308I-1488J2314D01*
G03X3907Y382895I1283J1786D01*
G01X3938D01*
G37*
G36*
G01X-12598D02*
G03X-11331Y383298I-2J2199D01*
G02X-11315Y378660I1488J-2314D01*
G03X-12569Y379073I-1283J-1786D01*
G01X-12599D01*
G03X-13866Y378670I2J-2199D01*
G02X-13882Y383308I-1488J2314D01*
G03X-12628Y382895I1283J1786D01*
G01X-12598D01*
G37*
G36*
G01X1665868Y378253D02*
G03X1665885Y377698I296J-269D01*
G02X1663866Y377636I-980J-1003D01*
G03X1663849Y378191I-296J269D01*
G02X1665868Y378253I980J1003D01*
G37*
G36*
G01X1600490Y380354D02*
Y376261D01*
X1600480Y376176D01*
G02X1597266Y376346I-1603J170D01*
G01Y380344D01*
G02X1600490Y380354I1612J0D01*
G37*
G36*
G01X1609758Y380332D02*
Y376086D01*
X1609748Y376001D01*
G02X1606534Y376171I-1603J170D01*
G01Y380322D01*
G02X1609758Y380332I1612J0D01*
G37*
G36*
G01X852495Y375114D02*
G03X852599Y374541I322J-238D01*
G02X850584Y372074I-873J-1344D01*
G03X850026Y372086I-285J-280D01*
G02X847676Y374252I-1094J1171D01*
G03X847612Y374814I-313J249D01*
G02X847568Y374850I992J1257D01*
G03X847048I-260J-304D01*
G02X844790Y377108I-1040J1218D01*
G03Y377628I-304J260D01*
G02X847048Y379886I1218J1040D01*
G03X847568I260J304D01*
G02X849648I1040J-1218D01*
G03X850168I260J304D01*
G02X852426Y377628I1040J-1218D01*
G03Y377108I304J-260D01*
G02X852495Y375114I-1218J-1040D01*
G37*
G36*
G01X778810Y371129D02*
G03X778193Y371122I-306J-258D01*
G02X778172Y372904I-1093J878D01*
G03X778789Y372911I306J258D01*
G02X778810Y371129I1093J-878D01*
G37*
G36*
G01X25591Y375021D02*
G03X26858Y375424I-2J2199D01*
G02X26874Y370786I1488J-2314D01*
G03X25620Y371199I-1283J-1786D01*
G01X25590D01*
G03X24323Y370796I2J-2199D01*
G02X24307Y375434I-1488J2314D01*
G03X25561Y375021I1283J1786D01*
G01X25591D01*
G37*
G36*
G01X9056D02*
G03X10323Y375424I-2J2199D01*
G02X10339Y370786I1488J-2314D01*
G03X9085Y371199I-1283J-1786D01*
G01X9054D01*
G03X7787Y370796I2J-2199D01*
G02X7771Y375434I-1488J2314D01*
G03X9025Y375021I1283J1786D01*
G01X9056D01*
G37*
G36*
G01X197777Y376372D02*
G03X198245Y376627I91J389D01*
G02X200996Y375078I1509J-537D01*
G03X201025Y374541I310J-253D01*
G02X200961Y372200I-1125J-1141D01*
G03Y371600I265J-300D01*
G02X198839I-1061J-1200D01*
G03Y372200I-265J300D01*
G02X198351Y372990I1060J1201D01*
G03X197854Y373272I-386J-102D01*
G02X197777Y376372I-442J1540D01*
G37*
G36*
G01X102761Y370050D02*
G03X102792Y369428I266J-298D01*
G02X101032Y369342I-827J-1132D01*
G03X101001Y369964I-266J298D01*
G02X102761Y370050I827J1132D01*
G37*
G36*
G01X1598821Y368943D02*
G03X1598810Y368350I263J-301D01*
G02X1596929Y368386I-960J-1021D01*
G03X1596940Y368979I-263J301D01*
G02X1598821Y368943I960J1021D01*
G37*
G36*
G01X835874Y367906D02*
G03X836174Y367903I151J131D01*
G02X836266Y365662I1189J-1074D01*
G03X835725Y365668I-274J-292D01*
G02X833618Y365645I-1067J1195D01*
G03X833098I-260J-304D01*
G02X831018I-1040J1218D01*
G03X830498I-260J-304D01*
G02X828418I-1040J1218D01*
G03X827898I-260J-304D01*
G02X825818I-1040J1218D01*
G03X825298I-260J-304D01*
G02X823218I-1040J1218D01*
G03X822698I-260J-304D01*
G02X820440Y367903I-1040J1218D01*
G03Y368423I-304J260D01*
G02X822698Y370681I1218J1040D01*
G03X823218I260J304D01*
G02X825298I1040J-1218D01*
G03X825818I260J304D01*
G02X827898I1040J-1218D01*
G03X828418I260J304D01*
G02X830498I1040J-1218D01*
G03X831018I260J304D01*
G02X833098I1040J-1218D01*
G03X833618I260J304D01*
G02X835767Y368307I1040J-1218D01*
G03Y368019I139J-144D01*
G02X835874Y367906I-1108J-1157D01*
G37*
G36*
G01X20473Y367147D02*
G03X21740Y367550I-2J2199D01*
G02X21756Y362912I1488J-2314D01*
G03X20502Y363325I-1283J-1786D01*
G01X20471D01*
G03X19204Y362922I2J-2199D01*
G02X19188Y367560I-1488J2314D01*
G03X20442Y367147I1283J1786D01*
G01X20473D01*
G37*
G36*
G01X3938D02*
G03X5205Y367550I-2J2199D01*
G02X5221Y362912I1488J-2314D01*
G03X3967Y363325I-1283J-1786D01*
G01X3936D01*
G03X2669Y362922I2J-2199D01*
G02X2653Y367560I-1488J2314D01*
G03X3907Y367147I1283J1786D01*
G01X3938D01*
G37*
G36*
G01X-12598D02*
G03X-11331Y367550I-2J2199D01*
G02X-11315Y362912I1488J-2314D01*
G03X-12569Y363325I-1283J-1786D01*
G01X-12599D01*
G03X-13866Y362922I2J-2199D01*
G02X-13882Y367560I-1488J2314D01*
G03X-12628Y367147I1283J1786D01*
G01X-12598D01*
G37*
G36*
G01X746633Y362791D02*
G03X746113I-260J-304D01*
G02X743930Y365131I-1040J1218D01*
G03X743910Y365711I-285J281D01*
G02X746013Y368127I1063J1198D01*
G03X746533I260J304D01*
G02X748613I1040J-1218D01*
G03X749133I260J304D01*
G02X751316Y365787I1040J-1218D01*
G03X751336Y365207I285J-281D01*
G02X749233Y362791I-1063J-1198D01*
G03X748713I-260J-304D01*
G02X746633I-1040J1218D01*
G37*
G36*
G01X412516Y364647D02*
G03X412494Y364092I277J-289D01*
G02X410478Y364173I-1047J-932D01*
G03X410500Y364728I-277J289D01*
G02X410576Y366671I1047J932D01*
G03Y367249I-277J289D01*
G02X412518I971J1011D01*
G03Y366671I277J-289D01*
G02X412516Y364647I-971J-1011D01*
G37*
G36*
G01X776217Y363952D02*
G03X776224Y363388I287J-278D01*
G02X774043Y363308I-1053J-1072D01*
G03X774008Y363871I-301J264D01*
G02X773978Y363897I1034J1223D01*
G03X773423Y363887I-272J-293D01*
G02X771547Y363601I-1133J1133D01*
G03X770977Y363359I-186J-354D01*
G02X768209Y364835I-1537J451D01*
G03X768197Y365360I-308J256D01*
G02X770958Y366719I1183J1080D01*
G03X771539Y366435I394J69D01*
G02X773382Y366193I752J-1415D01*
G03X773937Y366203I272J293D01*
G02X776217Y363952I1133J-1132D01*
G37*
G36*
G01X126754Y363789D02*
G03X126731Y363260I288J-278D01*
G02X124229Y361625I-1168J-944D01*
G03X123566Y361696I-355J-184D01*
G02X121298Y363940I-1236J1019D01*
G03X121351Y364496I-258J305D01*
G02X124003Y366273I1249J1003D01*
G03X124602Y366153I350J193D01*
G02X126754Y363789I998J-1253D01*
G37*
G36*
G01X1544310Y362427D02*
G03Y361873I288J-277D01*
G02X1542290I-1010J-973D01*
G03Y362427I-288J277D01*
G02X1544310I1010J973D01*
G37*
G36*
G01X1653798Y365610D02*
Y360515D01*
X1653788Y360430D01*
G02X1650574Y360600I-1603J170D01*
G01Y365601D01*
G02X1653798Y365610I1612J-1D01*
G37*
G36*
G01X1641878Y365510D02*
Y360415D01*
X1641868Y360330D01*
G02X1638654Y360500I-1603J170D01*
G01Y365501D01*
G02X1641878Y365510I1612J-1D01*
G37*
G36*
G01X1534756Y361839D02*
G03X1534771Y361284I295J-270D01*
G02X1532753Y361227I-982J-1001D01*
G03X1532738Y361782I-295J270D01*
G02X1534756Y361839I982J1001D01*
G37*
G36*
G01X823910Y358757D02*
G03X823310Y358745I-295J-271D01*
G02X821028Y360982I-1221J1036D01*
G03Y361582I-265J300D01*
G02X823289Y363843I1061J1200D01*
G03X823889I300J265D01*
G02X826289I1200J-1061D01*
G03X826889I300J265D01*
G02X829289I1200J-1061D01*
G03X829889I300J265D01*
G02X832289I1200J-1061D01*
G03X832889I300J265D01*
G02X835176Y361605I1200J-1061D01*
G03Y361018I271J-294D01*
G02X832889Y358780I-1087J-1177D01*
G03X832289I-300J-265D01*
G02X829889I-1200J1061D01*
G03X829289I-300J-265D01*
G02X826889I-1200J1061D01*
G03X826289I-300J-265D01*
G02X823910Y358757I-1200J1061D01*
G37*
G36*
G01X175224Y358560D02*
G03X174624I-300J-265D01*
G02Y360682I-1200J1061D01*
G03X175224I300J265D01*
G02X177624I1200J-1061D01*
G03X178224I300J265D01*
G02X180624I1200J-1061D01*
G03X181224I300J265D01*
G02X183624I1200J-1061D01*
G03X184224I300J265D01*
G02X186624I1200J-1061D01*
G03X187224I300J265D01*
G02Y358560I1200J-1061D01*
G03X186624I-300J-265D01*
G02X184224I-1200J1061D01*
G03X183624I-300J-265D01*
G02X181224I-1200J1061D01*
G03X180624I-300J-265D01*
G02X178224I-1200J1061D01*
G03X177624I-300J-265D01*
G02X175224I-1200J1061D01*
G37*
G36*
G01X49402Y358381D02*
G03X48839Y358449I-315J-246D01*
G02X49078Y360409I-869J1101D01*
G03X49641Y360341I315J246D01*
G02X49402Y358381I869J-1101D01*
G37*
G36*
G01X1479586Y360661D02*
G03X1479585Y360087I278J-287D01*
G02X1477633Y360091I-978J-1005D01*
G03X1477634Y360665I-278J287D01*
G02X1479586Y360661I978J1005D01*
G37*
G36*
G01X1588089Y357429D02*
G03X1587511I-289J-277D01*
G02Y359371I-1011J971D01*
G03X1588089I289J277D01*
G02Y357429I1011J-971D01*
G37*
G36*
G01X1489450Y359356D02*
G03Y358778I277J-289D01*
G02X1487508I-971J-1011D01*
G03Y359356I-277J289D01*
G02Y361378I971J1011D01*
G03Y361956I-277J289D01*
G02X1489450I971J1011D01*
G03Y361378I277J-289D01*
G02Y359356I-971J-1011D01*
G37*
G36*
G01X1484671Y358502D02*
G03X1484699Y357881I266J-299D01*
G02X1482936Y357801I-832J-1128D01*
G03X1482908Y358422I-266J299D01*
G02X1484671Y358502I832J1128D01*
G37*
G36*
G01X25591Y359273D02*
G03X26858Y359676I-2J2199D01*
G02X26874Y355038I1488J-2314D01*
G03X25620Y355451I-1283J-1786D01*
G01X25590D01*
G03X24323Y355048I2J-2199D01*
G02X24307Y359686I-1488J2314D01*
G03X25561Y359273I1283J1786D01*
G01X25591D01*
G37*
G36*
G01X9056D02*
G03X10323Y359676I-2J2199D01*
G02X10339Y355038I1488J-2314D01*
G03X9085Y355451I-1283J-1786D01*
G01X9054D01*
G03X7787Y355048I2J-2199D01*
G02X7771Y359686I-1488J2314D01*
G03X9025Y359273I1283J1786D01*
G01X9056D01*
G37*
G36*
G01X-7480D02*
G03X-6213Y359676I-2J2199D01*
G02X-6197Y355038I1488J-2314D01*
G03X-7451Y355451I-1283J-1786D01*
G01X-7481D01*
G03X-8748Y355048I2J-2199D01*
G02X-8764Y359686I-1488J2314D01*
G03X-7510Y359273I1283J1786D01*
G01X-7480D01*
G37*
G36*
G01X1631382Y356595D02*
G03X1631410Y355995I278J-288D01*
G02X1629560Y355908I-876J-1095D01*
G03X1629532Y356508I-278J288D01*
G02X1629425Y358603I876J1095D01*
G03X1629440Y359158I-280J285D01*
G02X1629414Y361018I1036J945D01*
G03X1629383Y361573I-303J261D01*
G02X1629291Y363533I954J1027D01*
G03X1629269Y364088I-299J266D01*
G02X1629267Y366108I971J1011D01*
G03X1629258Y366692I-278J288D01*
G02X1631173Y366721I942J1038D01*
G03X1631182Y366137I278J-288D01*
G02X1631286Y364166I-942J-1038D01*
G03X1631308Y363611I299J-266D01*
G02X1631399Y361685I-971J-1011D01*
G03X1631430Y361130I303J-261D01*
G02X1631459Y359103I-954J-1027D01*
G03X1631444Y358548I280J-285D01*
G02X1631382Y356595I-1036J-945D01*
G37*
G36*
G01X1521289Y356063D02*
G03X1521315Y355466I279J-287D01*
G02X1519453Y355385I-885J-1087D01*
G03X1519427Y355982I-279J287D01*
G02X1521289Y356063I885J1087D01*
G37*
G36*
G01X1525756Y355744D02*
G03Y355190I288J-277D01*
G02X1523736I-1010J-973D01*
G03Y355744I-288J277D01*
G02Y357690I1010J973D01*
G03Y358244I-288J277D01*
G02X1525756I1010J973D01*
G03Y357690I288J-277D01*
G02Y355744I-1010J-973D01*
G37*
G36*
G01X1499217Y353894D02*
G03Y353316I277J-289D01*
G02X1497275I-971J-1011D01*
G03Y353894I-277J289D01*
G02Y355916I971J1011D01*
G03Y356494I-277J289D01*
G02X1497261Y358503I971J1011D01*
G03X1497275Y359058I-281J285D01*
G02X1497356Y361034I1034J947D01*
G03X1497342Y361633I-272J293D01*
G02X1497293Y363734I904J1072D01*
G03X1497279Y364333I-272J293D01*
G02X1499136Y364376I904J1072D01*
G03X1499150Y363777I272J-293D01*
G02X1499199Y361676I-904J-1072D01*
G03X1499213Y361077I272J-293D01*
G02X1499294Y359007I-904J-1072D01*
G03X1499280Y358452I281J-285D01*
G02X1499217Y356494I-1034J-947D01*
G03Y355916I277J-289D01*
G02Y353894I-971J-1011D01*
G37*
G36*
G01X1653157Y353689D02*
G03Y353111I277J-289D01*
G02X1651215I-971J-1011D01*
G03Y353689I-277J289D01*
G02X1653157I971J1011D01*
G37*
G36*
G01X767955Y352504D02*
G03X768121Y351953I349J-195D01*
G02X766254Y351393I-644J-1245D01*
G03X766088Y351944I-349J195D01*
G02X767955Y352504I644J1245D01*
G37*
G36*
G01X1539449Y352283D02*
G03Y351705I277J-289D01*
G02X1537507I-971J-1011D01*
G03Y352283I-277J289D01*
G02Y354305I971J1011D01*
G03Y354883I-277J289D01*
G02X1539449I971J1011D01*
G03Y354305I277J-289D01*
G02Y352283I-971J-1011D01*
G37*
G36*
G01X1416430Y352151D02*
G03X1416419Y351563I266J-299D01*
G02X1414520Y351599I-969J-1013D01*
G03X1414531Y352187I-266J299D01*
G02X1416430Y352151I969J1013D01*
G37*
G36*
G01X1447394Y350654D02*
G03X1446911Y350277I-83J-391D01*
G02X1445801Y351698I-1401J50D01*
G03X1446284Y352075I83J391D01*
G02X1447394Y350654I1401J-50D01*
G37*
G36*
G01X1490844Y351587D02*
G03X1490827Y351004I265J-299D01*
G02X1488909Y351061I-989J-993D01*
G03X1488926Y351644I-265J299D01*
G02X1490844Y351587I989J993D01*
G37*
G36*
G01X1544538Y351473D02*
G03Y350919I288J-277D01*
G02X1542518I-1010J-973D01*
G03Y351473I-288J277D01*
G02X1544538I1010J973D01*
G37*
G36*
G01X1331153Y351026D02*
G03X1331708Y350981I301J264D01*
G02X1331547Y348974I892J-1082D01*
G03X1330992Y349019I-301J-264D01*
G02X1331153Y351026I-892J1082D01*
G37*
G36*
G01X115528Y351963D02*
G03X115764Y352490I-135J377D01*
G02X117535Y351696I1299J526D01*
G03X117299Y351169I135J-377D01*
G02X117398Y350750I-1299J-528D01*
G03X117844Y350383I399J30D01*
G02X116610Y348884I164J-1392D01*
G03X116164Y349251I-399J-30D01*
G02X115528Y351963I-163J1392D01*
G37*
G36*
G01X746378Y343688D02*
G03X745818I-280J-286D01*
G02X743637Y346033I-1120J1145D01*
G03Y346633I-265J300D01*
G02X745818Y348978I1061J1200D01*
G03X746378I280J286D01*
G02X748618I1120J-1145D01*
G03X749178I280J286D01*
G02X751359Y346633I1120J-1145D01*
G03Y346033I265J-300D01*
G02X749178Y343688I-1061J-1200D01*
G03X748618I-280J-286D01*
G02X746378I-1120J1145D01*
G37*
G36*
G01X1643534Y343999D02*
G03X1643594Y343437I312J-251D01*
G02X1641621Y343227I-882J-1090D01*
G03X1641561Y343789I-312J251D01*
G02X1643534Y343999I882J1090D01*
G37*
G36*
G01X1556480Y340194D02*
G03X1555870I-305J-259D01*
G02Y342006I-1070J906D01*
G03X1556480I305J259D01*
G02Y340194I1070J-906D01*
G37*
G36*
G01X778862Y339127D02*
G03X778252I-305J-259D01*
G02Y340939I-1070J906D01*
G03X778862I305J259D01*
G02Y339127I1070J-906D01*
G37*
G36*
G01X700168Y337953D02*
G03X699613Y337931I-266J-299D01*
G02X699532Y339947I-1013J969D01*
G03X700087Y339969I266J299D01*
G02X700168Y337953I1013J-969D01*
G37*
G36*
G01X1582841Y337739D02*
G03X1582273Y337715I-272J-293D01*
G02X1579704Y339598I-1183J1080D01*
G03X1579581Y340130I-346J200D01*
G02X1581408Y342230I785J1162D01*
G03X1581962Y342189I298J267D01*
G02X1584152Y340570I897J-1077D01*
G03X1584360Y340050I369J-154D01*
G02X1582841Y337739I-566J-1283D01*
G37*
G36*
G01X1069992Y337612D02*
G03X1069392I-300J-265D01*
G02Y339734I-1200J1061D01*
G03X1069992I300J265D01*
G02Y337612I1200J-1061D01*
G37*
G36*
G01X1062792D02*
G03X1062192I-300J-265D01*
G02Y339734I-1200J1061D01*
G03X1062792I300J265D01*
G02Y337612I1200J-1061D01*
G37*
G36*
G01X1079082Y337472D02*
G03X1078482I-300J-265D01*
G02Y339594I-1200J1061D01*
G03X1079082I300J265D01*
G02X1081384Y339696I1200J-1061D01*
G03X1081987Y339757I275J290D01*
G02X1084465Y339942I1314J-916D01*
G03X1085029Y339925I291J275D01*
G02X1084962Y337657I1097J-1167D01*
G03X1084398Y337674I-291J-275D01*
G02X1082199Y337678I-1097J1167D01*
G03X1081596Y337617I-275J-290D01*
G02X1079082Y337472I-1314J916D01*
G37*
G36*
G01X824282Y335966D02*
G03X823682I-300J-265D01*
G02X821337Y338147I-1200J1061D01*
G03Y338707I-286J280D01*
G02X821421Y341027I1145J1120D01*
G03Y341627I-265J300D01*
G02X823682Y343888I1061J1200D01*
G03X824282I300J265D01*
G02X826682I1200J-1061D01*
G03X827282I300J265D01*
G02X829682I1200J-1061D01*
G03X830282I300J265D01*
G02X832682I1200J-1061D01*
G03X833282I300J265D01*
G02X835623Y343951I1200J-1061D01*
G03X836203Y343961I285J281D01*
G02X838483Y344041I1179J-1084D01*
G03X839058Y344068I274J291D01*
G02X841421Y341905I1204J-1057D01*
G03X841425Y341349I290J-276D01*
G02X841466Y339148I-1143J-1122D01*
G03X841486Y338588I295J-270D01*
G02X839304Y336242I-1103J-1162D01*
G03X838704Y336172I-270J-295D01*
G02X836241Y335953I-1322J905D01*
G03X835661Y335943I-285J-281D01*
G02X833282Y335966I-1179J1084D01*
G03X832682I-300J-265D01*
G02X830282I-1200J1061D01*
G03X829682I-300J-265D01*
G02X827282I-1200J1061D01*
G03X826682I-300J-265D01*
G02X824282I-1200J1061D01*
G37*
G36*
G01X1620907Y337663D02*
G03Y337109I288J-277D01*
G02X1618887I-1010J-973D01*
G03Y337663I-288J277D01*
G02Y339609I1010J973D01*
G03Y340163I-288J277D01*
G02X1620907I1010J973D01*
G03Y339609I288J-277D01*
G02Y337663I-1010J-973D01*
G37*
G36*
G01X746378Y334371D02*
G03X745818I-280J-286D01*
G02X743553Y336636I-1120J1145D01*
G03Y337196I-286J280D01*
G02X745818Y339461I1145J1120D01*
G03X746378I280J286D01*
G02X748618I1120J-1145D01*
G03X749178I280J286D01*
G02X751443Y337196I1120J-1145D01*
G03Y336636I286J-280D01*
G02X749178Y334371I-1145J-1120D01*
G03X748618I-280J-286D01*
G02X746378I-1120J1145D01*
G37*
G36*
G01X852875Y334344D02*
G03X852275I-300J-265D01*
G02X849944Y336539I-1200J1061D01*
G03X849925Y337123I-283J283D01*
G02X849782Y337266I1059J1202D01*
G03X849182I-300J-265D01*
G02X846921Y339527I-1200J1061D01*
G03Y340127I-265J300D01*
G02Y342527I1061J1200D01*
G03Y343127I-265J300D01*
G02X849182Y345388I1061J1200D01*
G03X849782I300J265D01*
G02X852182I1200J-1061D01*
G03X852782I300J265D01*
G02X855182I1200J-1061D01*
G03X855782I300J265D01*
G02X858043Y343127I1200J-1061D01*
G03Y342527I265J-300D01*
G02Y340127I-1061J-1200D01*
G03Y339527I265J-300D01*
G02X858113Y337193I-1061J-1200D01*
G03X858132Y336609I283J-283D01*
G02X855875Y334344I-1057J-1204D01*
G03X855275I-300J-265D01*
G02X852875I-1200J1061D01*
G37*
G36*
G01X81379Y334629D02*
G03X80813Y334496I-220J-334D01*
G02X80371Y336371I-1213J704D01*
G03X80937Y336504I220J334D01*
G02X81379Y334629I1213J-704D01*
G37*
G36*
G01X102187Y334221D02*
G03X101599Y334210I-289J-277D01*
G02X101563Y336109I-1049J930D01*
G03X102151Y336120I289J277D01*
G02X102187Y334221I1049J-930D01*
G37*
G36*
G01X1497795Y336516D02*
G03X1498283Y336166I398J40D01*
G02X1497205Y334660I317J-1366D01*
G03X1496717Y335010I-398J-40D01*
G02X1495105Y336914I-317J1366D01*
G03X1494893Y337435I-369J153D01*
G02X1494589Y339834I552J1289D01*
G03X1494670Y340384I-244J317D01*
G02X1496666Y340090I1140J816D01*
G03X1496585Y339540I244J-317D01*
G02X1496620Y339488I-1145J-808D01*
G03X1496939Y339466I168J109D01*
G02X1498126Y337150I1058J-920D01*
G03X1497771Y336668I36J-398D01*
G02X1497795Y336516I-1371J-294D01*
G37*
G36*
G01X1473398Y336467D02*
G03X1473409Y335868I270J-295D01*
G02X1471552Y335833I-909J-1068D01*
G03X1471541Y336432I-270J295D01*
G02X1473398Y336467I909J1068D01*
G37*
G36*
G01X1416971Y334489D02*
G03Y333911I277J-289D01*
G02X1415029I-971J-1011D01*
G03Y334489I-277J289D01*
G02Y336511I971J1011D01*
G03Y337089I-277J289D01*
G02X1416971I971J1011D01*
G03Y336511I277J-289D01*
G02Y334489I-971J-1011D01*
G37*
G36*
G01X1570182Y333131D02*
G03Y332553I277J-289D01*
G02X1568240I-971J-1011D01*
G03Y333131I-277J289D01*
G02X1570182I971J1011D01*
G37*
G36*
G01X1548600Y333102D02*
G03X1548734Y332556I343J-205D01*
G02X1546798Y332082I-733J-1195D01*
G03X1546664Y332628I-343J205D01*
G02X1548600Y333102I733J1195D01*
G37*
G36*
G01X200006Y337822D02*
G03X200004Y338371I-292J273D01*
G02X199866Y338536I1157J1108D01*
G03X199257Y338583I-324J-234D01*
G02X196987Y340843I-1138J1127D01*
G03X197007Y341387I-283J283D01*
G02X197154Y343623I1216J1043D01*
G03X197156Y344216I-267J297D01*
G02X197033Y344341I1079J1184D01*
G03X196433I-300J-265D01*
G02X194299Y346704I-1200J1061D01*
G03X194325Y347334I-233J325D01*
G02Y349470I908J1068D01*
G03X194299Y350100I-259J305D01*
G02X196433Y352463I934J1302D01*
G03X197033I300J265D01*
G02X199294Y350202I1200J-1061D01*
G03Y349602I265J-300D01*
G02X199339Y349561I-1056J-1204D01*
G03X199901Y349570I276J289D01*
G02X202106Y347249I1144J-1121D01*
G03Y346649I265J-300D01*
G02X202224Y346534I-1058J-1203D01*
G03X202826Y346549I294J270D01*
G02X205121Y344327I1234J-1022D01*
G03Y343727I265J-300D01*
G02X205137Y341341I-1061J-1200D01*
G03X205158Y340732I269J-296D01*
G02X205334Y338382I-995J-1256D01*
G03X205336Y337833I292J-273D01*
G02X202977Y335667I-1159J-1105D01*
G03X202377I-300J-265D01*
G02X202238Y335528I-1200J1061D01*
G03Y334928I265J-300D01*
G02Y332528I-1061J-1200D01*
G03Y331928I265J-300D01*
G02X200116I-1061J-1200D01*
G03Y332528I-265J300D01*
G02Y334928I1061J1200D01*
G03Y335528I-265J300D01*
G02X200006Y337822I1061J1201D01*
G37*
G36*
G01X776587Y331634D02*
G03X776458Y331090I214J-338D01*
G02X773785Y329738I-1286J-775D01*
G03X773079Y329800I-369J-154D01*
G02X770216Y331188I-1349J864D01*
G03X769926Y331709I-378J131D01*
G02X771463Y334350I352J1563D01*
G03X771997Y334297I296J269D01*
G02X774071Y334153I953J-1288D01*
G03X774627Y334149I280J285D01*
G02X776587Y331634I1105J-1160D01*
G37*
G36*
G01X1526765Y328878D02*
G03X1526213Y328768I-220J-334D01*
G02X1525823Y330723I-1162J785D01*
G03X1526375Y330833I220J334D01*
G02X1526765Y328878I1162J-785D01*
G37*
G36*
G01X1560995Y330789D02*
G03Y330211I277J-289D01*
G02X1559053I-971J-1011D01*
G03Y330789I-277J289D01*
G02X1560995I971J1011D01*
G37*
G36*
G01X1654016Y328102D02*
G03X1654038Y327534I292J-273D01*
G02X1652066Y327457I-947J-1034D01*
G03X1652044Y328025I-292J273D01*
G02X1654016Y328102I947J1034D01*
G37*
G36*
G01X645706Y326977D02*
G03X645589Y327576I-312J250D01*
G02X647366Y327923I683J1224D01*
G03X647483Y327324I312J-250D01*
G02X645706Y326977I-683J-1224D01*
G37*
G36*
G01X1493775Y327586D02*
G03X1493930Y327048I352J-190D01*
G02X1492005Y326492I-690J-1220D01*
G03X1491850Y327030I-352J190D01*
G02X1493775Y327586I690J1220D01*
G37*
G36*
G01X1017937Y325288D02*
G03X1017717Y324783I156J-368D01*
G02X1015855Y325596I-1318J-479D01*
G03X1016075Y326101I-156J368D01*
G02X1018366Y327590I1318J480D01*
G03X1018920I277J288D01*
G02X1020866I973J-1010D01*
G03X1021420I277J288D01*
G02X1023366I973J-1010D01*
G03X1023920I277J288D01*
G02X1024287Y327844I971J-1011D01*
G03X1024479Y328371I-172J361D01*
G02X1026567Y330094I1276J580D01*
G03X1027153Y330233I232J326D01*
G02X1028642Y328200I1240J-653D01*
G03X1028420Y327534I71J-394D01*
G02X1026420Y325570I-1027J-955D01*
G03X1025866I-277J-288D01*
G02X1023920I-973J1010D01*
G03X1023366I-277J-288D01*
G02X1021420I-973J1010D01*
G03X1020866I-277J-288D01*
G02X1018920I-973J1010D01*
G03X1018366I-277J-288D01*
G02X1017937Y325288I-972J1011D01*
G37*
G36*
G01X376998Y330627D02*
G03X377585Y330641I287J279D01*
G02X379464Y328129I1200J-1061D01*
G03X379286Y327569I170J-362D01*
G02X376816Y325592I-1392J-792D01*
G03X376282Y325596I-269J-296D01*
G02X374111Y325645I-1059J1202D01*
G03X373545Y325635I-278J-288D01*
G02X371263Y325609I-1154J1111D01*
G03X370735Y325640I-282J-284D01*
G02X368626Y325759I-987J1262D01*
G03X368101Y325790I-280J-286D01*
G02X368083Y325776I-992J1257D01*
G03X368050Y325488I120J-160D01*
G02X365736Y325637I-1228J-1029D01*
G03X365796Y326156I-271J294D01*
G02X368243Y328200I1325J901D01*
G03X368768Y328169I280J286D01*
G02X370876Y328039I980J-1267D01*
G03X371404Y328008I282J284D01*
G02X373503Y327899I987J-1262D01*
G03X374069Y327909I278J288D01*
G02X374351Y328142I1155J-1110D01*
G03X374476Y328684I-217J336D01*
G02X376998Y330627I1371J828D01*
G37*
G36*
G01X1543591Y324428D02*
G03X1543924Y323984I397J-49D01*
G02X1542309Y322772I-224J-1384D01*
G03X1541976Y323216I-397J49D01*
G02X1543591Y324428I224J1384D01*
G37*
G36*
G01X1590800Y323413D02*
G03X1591385Y323202I378J131D01*
G02X1590786Y321542I725J-1200D01*
G03X1590201Y321753I-378J-131D01*
G02X1590800Y323413I-725J1200D01*
G37*
G36*
G01X688320Y318775D02*
G03X688262Y318235I263J-301D01*
G02X686218Y318455I-1124J-838D01*
G03X686276Y318995I-263J301D01*
G02X688320Y318775I1124J838D01*
G37*
G36*
G01X647783Y319011D02*
G03Y318389I252J-311D01*
G02X646017I-883J-1089D01*
G03Y319011I-252J311D01*
G02X647783I883J1089D01*
G37*
G36*
G01X115528Y319963D02*
G03X115764Y320490I-135J377D01*
G02X117535Y319696I1299J526D01*
G03X117299Y319169I135J-377D01*
G02X117398Y318750I-1299J-528D01*
G03X117844Y318383I399J30D01*
G02X116610Y316884I164J-1392D01*
G03X116164Y317251I-399J-30D01*
G02X115528Y319963I-163J1392D01*
G37*
G36*
G01X1549195Y318450D02*
G03X1549443Y317930I374J-141D01*
G02X1547687Y317092I-443J-1330D01*
G03X1547439Y317612I-374J141D01*
G02X1549195Y318450I443J1330D01*
G37*
G36*
G01X82378Y317044D02*
G03X82972Y317036I301J264D01*
G02X82946Y315158I1028J-953D01*
G03X82352Y315166I-301J-264D01*
G02X82378Y317044I-1028J953D01*
G37*
G36*
G01X64971Y315489D02*
G03Y314911I277J-289D01*
G02X63029I-971J-1011D01*
G03Y315489I-277J289D01*
G02X64971I971J1011D01*
G37*
G36*
G01X1568271Y314778D02*
G03X1568629Y314283I388J-96D01*
G02X1567163Y313224I-105J-1398D01*
G03X1566805Y313719I-388J96D01*
G02X1565900Y314144I104J1398D01*
G03X1565346Y314165I-288J-277D01*
G02X1565421Y316183I-935J1045D01*
G03X1565975Y316162I288J277D01*
G02X1568271Y314778I935J-1045D01*
G37*
G36*
G01X1517245Y312208D02*
G03X1517209Y311654I269J-296D01*
G02X1515194Y311785I-1071J-905D01*
G03X1515230Y312339I-269J296D01*
G02X1517245Y312208I1071J905D01*
G37*
G36*
G01X1640423Y311762D02*
G03Y311208I288J-277D01*
G02X1638403I-1010J-973D01*
G03Y311762I-288J277D01*
G02X1640423I1010J973D01*
G37*
G36*
G01X1054857Y310895D02*
G03X1055487Y310894I315J246D01*
G02X1055484Y308919I1260J-989D01*
G03X1054854Y308920I-315J-246D01*
G02X1054857Y310895I-1260J989D01*
G37*
G36*
G01X1047789Y310997D02*
G03X1048375Y310996I293J272D01*
G02X1048370Y308817I1172J-1092D01*
G03X1047784Y308818I-293J-272D01*
G02X1047789Y310997I-1172J1092D01*
G37*
G36*
G01X1040571Y310985D02*
G03X1041163Y310983I297J268D01*
G02X1041159Y308829I1184J-1079D01*
G03X1040567Y308831I-297J-268D01*
G02X1040571Y310985I-1184J1079D01*
G37*
G36*
G01X1033286Y310919D02*
G03X1033907Y310918I311J252D01*
G02X1033903Y308895I1240J-1014D01*
G03X1033282Y308896I-311J-252D01*
G02X1033286Y310919I-1240J1014D01*
G37*
G36*
G01X405310Y310979D02*
G03X405905Y310978I298J267D01*
G02X405901Y308835I1189J-1074D01*
G03X405306Y308836I-298J-267D01*
G02X405310Y310979I-1189J1074D01*
G37*
G36*
G01X397985Y310878D02*
G03X398621Y310877I318J242D01*
G02X398618Y308936I1273J-972D01*
G03X397982Y308937I-318J-242D01*
G02X397985Y310878I-1273J972D01*
G37*
G36*
G01X390781Y310875D02*
G03X391419Y310874I319J241D01*
G02X391415Y308939I1275J-970D01*
G03X390777Y308940I-319J-241D01*
G02X390781Y310875I-1275J970D01*
G37*
G36*
G01X383698Y310970D02*
G03X384297Y310969I300J265D01*
G02X384293Y308844I1197J-1065D01*
G03X383694Y308845I-300J-265D01*
G02X383698Y310970I-1197J1065D01*
G37*
G36*
G01X1022960Y308827D02*
G03X1022346Y308796I-294J-271D01*
G02X1022245Y310842I-1281J962D01*
G03X1022859Y310873I294J271D01*
G02X1022960Y308827I1281J-962D01*
G37*
G36*
G01X1565345Y310023D02*
G03X1565339Y309424I262J-302D01*
G02X1563482Y309443I-939J-1041D01*
G03X1563488Y310042I-262J302D01*
G02X1565345Y310023I939J1041D01*
G37*
G36*
G01X714980Y309887D02*
G03Y309333I288J-277D01*
G02X712960I-1010J-973D01*
G03Y309887I-288J277D01*
G02X714980I1010J973D01*
G37*
G36*
G01X455158Y309368D02*
G03Y308814I288J-277D01*
G02X452981Y307064I-1010J-972D01*
G03X452426Y307175I-333J-222D01*
G02X450266Y308104I-778J1166D01*
G03X449789Y308428I-394J-67D01*
G02X448527Y308790I-289J1372D01*
G03X447973I-277J-288D01*
G02Y310810I-973J1010D01*
G03X448527I277J288D01*
G02X450882Y310037I973J-1010D01*
G03X451359Y309713I394J67D01*
G02X452218Y309622I289J-1372D01*
G03X452773Y310066I163J365D01*
G02X455158Y309368I1375J275D01*
G37*
G36*
G01X1561087Y309435D02*
G03X1561176Y308850I311J-252D01*
G02X1559310Y308565I-776J-1167D01*
G03X1559221Y309150I-311J252D01*
G02X1561087Y309435I776J1167D01*
G37*
G36*
G01X1306859Y308248D02*
G03X1306876Y307664I281J-284D01*
G02X1304964Y307608I-926J-1053D01*
G03X1304947Y308192I-281J284D01*
G02X1304824Y308315I928J1051D01*
G03X1304271Y308358I-299J-266D01*
G02X1304429Y310371I-891J1083D01*
G03X1304982Y310328I299J266D01*
G02X1306859Y308248I891J-1083D01*
G37*
G36*
G01X198917Y305660D02*
G03X198404Y305796I-333J-221D01*
G02X196532Y308340I-720J1431D01*
G03X196541Y308886I-288J278D01*
G02X198882Y308846I1189J1073D01*
G03X198873Y308300I288J-278D01*
G02X199018Y308115I-1185J-1078D01*
G03X199531Y307979I333J221D01*
G02X198917Y305660I720J-1431D01*
G37*
G36*
G01X1537386Y305392D02*
G03X1537870Y305102I388J98D01*
G02X1536847Y303397I336J-1361D01*
G03X1536363Y303687I-388J-98D01*
G02X1537386Y305392I-336J1361D01*
G37*
G36*
G01X1637893Y304142D02*
G03X1637906Y303586I294J-271D01*
G02X1635890Y303537I-984J-998D01*
G03X1635877Y304093I-294J271D01*
G02X1637893Y304142I984J998D01*
G37*
G36*
G01X1564358Y302020D02*
G03X1564356Y302642I-253J310D01*
G02X1566121Y302648I879J1092D01*
G03X1566123Y302026I253J-310D01*
G02X1564358Y302020I-879J-1092D01*
G37*
G36*
G01X1584487Y302124D02*
G03Y301556I281J-284D01*
G02X1582513I-987J-996D01*
G03Y302124I-281J284D01*
G02X1584487I987J996D01*
G37*
G36*
G01X1300631Y300220D02*
G03X1300624Y299612I256J-307D01*
G02X1298804Y299635I-923J-1055D01*
G03X1298811Y300243I-256J307D01*
G02X1300631Y300220I923J1055D01*
G37*
G36*
G01X776240Y299981D02*
G03X776220Y299391I260J-304D01*
G02X773762Y297796I-1049J-1075D01*
G03X773189Y298006I-376J-138D01*
G02X771445Y298114I-789J1394D01*
G03X770853Y297981I-239J-321D01*
G02X768107Y299624I-1414J754D01*
G03X767877Y300232I-333J222D01*
G02X769325Y303003I413J1548D01*
G03X769846Y303007I258J305D01*
G02X772461Y301440I1054J-1207D01*
G03X772761Y300961I390J-89D01*
G02X773039Y300869I-362J-1561D01*
G03X773598Y301229I159J367D01*
G02X776240Y299981I1602J-29D01*
G37*
G36*
G01X824482Y294466D02*
G03X823882I-300J-265D01*
G02X821621Y296727I-1200J1061D01*
G03Y297327I-265J300D01*
G02X821499Y299607I1061J1200D01*
G03Y300147I-295J270D01*
G02Y302307I1183J1080D01*
G03Y302847I-295J270D01*
G02X823882Y304988I1183J1080D01*
G03X824482I300J265D01*
G02X826882I1200J-1061D01*
G03X827482I300J265D01*
G02X829882I1200J-1061D01*
G03X830482I300J265D01*
G02X832882I1200J-1061D01*
G03X833482I300J265D01*
G02X835922Y304941I1200J-1061D01*
G03X836542I310J253D01*
G02X838887Y302767I1240J-1014D01*
G03Y302187I275J-290D01*
G02Y299867I-1105J-1160D01*
G03Y299287I275J-290D01*
G02X836414Y297294I-1105J-1160D01*
G03X835794Y297374I-342J-208D01*
G02X833482Y297466I-1112J1153D01*
G03X832882I-300J-265D01*
G02X830482I-1200J1061D01*
G03X829882I-300J-265D01*
G02X827482I-1200J1061D01*
G03X826882I-300J-265D01*
G02X826743Y297327I-1200J1061D01*
G03Y296727I265J-300D01*
G02X824482Y294466I-1061J-1200D01*
G37*
G36*
G01X189138Y307917D02*
G03X189444Y307915I154J127D01*
G02X189544Y308022I1219J-1039D01*
G03X189534Y308317I-140J143D01*
G02X191803Y308517I1036J1222D01*
G03X191822Y307985I308J-255D01*
G02X189549Y305728I-1157J-1108D01*
G03X188997Y305732I-278J-287D01*
G02X188963Y305702I-1077J1186D01*
G03X188943Y305122I265J-299D01*
G02X188905Y302840I-1143J-1122D01*
G03Y302260I275J-290D01*
G02X188983Y300020I-1105J-1160D01*
G03Y299480I295J-270D01*
G02X188997Y297336I-1183J-1080D01*
G03X189029Y296773I299J-265D01*
G02X189127Y296676I-1077J-1186D01*
G03X189695Y296660I292J273D01*
G02X192000Y296561I1105J-1160D01*
G03X192600I300J265D01*
G02X195037Y296518I1200J-1061D01*
G03X195667Y296535I308J254D01*
G02X195719Y294565I1289J-952D01*
G03X195089Y294548I-308J-254D01*
G02X192600Y294439I-1289J952D01*
G03X192000I-300J-265D01*
G02X189629Y294407I-1200J1061D01*
G03X189061Y294423I-292J-273D01*
G02X186719Y294565I-1105J1160D01*
G03X186089Y294548I-308J-254D01*
G02X183600Y294439I-1289J952D01*
G03X183000I-300J-265D01*
G02X180629Y294407I-1200J1061D01*
G03X180061Y294423I-292J-273D01*
G02X177719Y294565I-1105J1160D01*
G03X177089Y294548I-308J-254D01*
G02X174600Y294439I-1289J952D01*
G03X174000I-300J-265D01*
G02X171695Y296660I-1200J1061D01*
G03Y297240I-275J290D01*
G02X171617Y299480I1105J1160D01*
G03Y300020I-295J270D01*
G02X171695Y302260I1183J1080D01*
G03Y302840I-275J290D01*
G02X174000Y305061I1105J1160D01*
G03X174600I300J265D01*
G02X177000I1200J-1061D01*
G03X177600I300J265D01*
G02X180000I1200J-1061D01*
G03X180600I300J265D01*
G02X183000I1200J-1061D01*
G03X183600I300J265D01*
G02X186000I1200J-1061D01*
G03X186600I300J265D01*
G02X186737Y305198I1199J-1062D01*
G03X186757Y305778I-265J299D01*
G02X189138Y307917I1143J1123D01*
G37*
G36*
G01X657627Y294985D02*
G03X657426Y295549I-350J193D01*
G02X659176Y296170I524J1301D01*
G03X659377Y295606I350J-193D01*
G02X657627Y294985I-524J-1301D01*
G37*
G36*
G01X1054894Y293960D02*
G03X1055497Y293959I302J262D01*
G02X1055492Y291854I1205J-1055D01*
G03X1054889Y291855I-302J-262D01*
G02X1054894Y293960I-1205J1055D01*
G37*
G36*
G01X1040435Y293917D02*
G03X1041058Y293914I313J249D01*
G02X1041049Y291906I1244J-1010D01*
G03X1040426Y291909I-313J-249D01*
G02X1040435Y293917I-1244J1010D01*
G37*
G36*
G01X1033215Y293897D02*
G03X1033844Y293896I315J247D01*
G02X1033840Y291917I1258J-992D01*
G03X1033211Y291918I-315J-247D01*
G02X1033215Y293897I-1258J992D01*
G37*
G36*
G01X1026163Y294014D02*
G03X1026744Y294011I292J273D01*
G02X1026733Y291808I1158J-1107D01*
G03X1026152Y291811I-292J-273D01*
G02X1026163Y294014I-1158J1107D01*
G37*
G36*
G01X1018861Y293935D02*
G03X1019475Y293934I307J256D01*
G02X1019471Y291879I1227J-1030D01*
G03X1018857Y291880I-307J-256D01*
G02X1018861Y293935I-1227J1030D01*
G37*
G36*
G01X405448Y294111D02*
G03X406013Y294086I295J270D01*
G02X405912Y291823I1081J-1182D01*
G03X405347Y291848I-295J-270D01*
G02X405448Y294111I-1081J1182D01*
G37*
G36*
G01X398151Y294056D02*
G03X398749Y294025I313J249D01*
G02X398640Y291906I1145J-1121D01*
G03X398042Y291937I-313J-249D01*
G02X398151Y294056I-1145J1121D01*
G37*
G36*
G01X390797Y293888D02*
G03X391429Y293887I316J245D01*
G02X391425Y291926I1265J-983D01*
G03X390793Y291927I-316J-245D01*
G02X390797Y293888I-1265J983D01*
G37*
G36*
G01X383890Y294190D02*
G03X384463Y294130I315J246D01*
G02X384229Y291921I1031J-1226D01*
G03X383656Y291981I-315J-246D01*
G02X383890Y294190I-1031J1226D01*
G37*
G36*
G01X372753Y291803D02*
G03X372226Y291770I-245J-316D01*
G02X369837Y291911I-1132J1134D01*
G03X369242Y291947I-314J-248D01*
G02X369373Y294080I-1126J1140D01*
G03X369968Y294044I314J248D01*
G02X372077Y294169I1126J-1140D01*
G03X372604Y294202I245J316D01*
G02X372753Y291803I1132J-1134D01*
G37*
G36*
G01X1637832Y293973D02*
G03Y293419I288J-277D01*
G02X1635812I-1010J-973D01*
G03Y293973I-288J277D01*
G02X1635853Y295959I1010J973D01*
G03X1635876Y296514I-276J289D01*
G02X1637894Y296431I1049J930D01*
G03X1637871Y295876I276J-289D01*
G02X1637832Y293973I-1049J-930D01*
G37*
G36*
G01X1305637Y292913D02*
G03X1305262Y292476I23J-399D01*
G02X1303787Y293745I-1396J-131D01*
G03X1304162Y294182I-23J399D01*
G02X1305637Y292913I1396J131D01*
G37*
G36*
G01X1335501Y292918D02*
G03X1336123Y292909I315J247D01*
G02X1336099Y291144I1077J-897D01*
G03X1335477Y291153I-315J-247D01*
G02X1335501Y292918I-1077J897D01*
G37*
G36*
G01X49683Y291311D02*
G03Y290689I252J-311D01*
G02X47917I-883J-1089D01*
G03Y291311I-252J311D01*
G02X49683I883J1089D01*
G37*
G36*
G01X1534824Y287709D02*
G03X1534841Y287125I281J-284D01*
G02X1532928Y287070I-927J-1052D01*
G03X1532911Y287654I-281J284D01*
G02X1534824Y287709I927J1052D01*
G37*
G36*
G01X1548006Y287663D02*
G03X1548358Y287223I398J-43D01*
G02X1546805Y285979I-159J-1393D01*
G03X1546453Y286419I-398J43D01*
G02X1548006Y287663I159J1393D01*
G37*
G36*
G01X637881Y287185D02*
G03X637839Y286610I255J-308D01*
G02X636064Y286864I-1040J-940D01*
G03X636087Y287187I-105J170D01*
G02X635967Y287300I900J1076D01*
G03X635645Y287257I-146J-137D01*
G02X635280Y289012I-1238J658D01*
G03X635852Y289090I249J313D01*
G02X637881Y287185I1133J-827D01*
G37*
G36*
G01X115528Y287963D02*
G03X115764Y288490I-135J377D01*
G02X117535Y287696I1299J526D01*
G03X117299Y287169I135J-377D01*
G02X117398Y286750I-1299J-528D01*
G03X117844Y286383I399J30D01*
G02X116610Y284884I164J-1392D01*
G03X116164Y285251I-399J-30D01*
G02X115528Y287963I-163J1392D01*
G37*
G36*
G01X663911Y283917D02*
G03X663289I-311J-252D01*
G02X660957Y285448I-1089J883D01*
G03X660742Y286007I-355J184D01*
G02X662475Y286673I490J1314D01*
G03X662690Y286114I355J-184D01*
G02X663289Y285683I-491J-1314D01*
G03X663911I311J252D01*
G02Y283917I1089J-883D01*
G37*
G36*
G01X1580115Y283805D02*
G03X1579560Y283799I-274J-291D01*
G02X1579539Y285819I-983J1000D01*
G03X1580094Y285825I274J291D01*
G02X1580115Y283805I983J-1000D01*
G37*
G36*
G01X1570790Y286064D02*
G03X1571021Y286576I-144J373D01*
G02X1573704Y286758I1315J487D01*
G03X1574027Y286277I391J-87D01*
G02X1572875Y283833I-237J-1382D01*
G03X1572321Y283802I-261J-303D01*
G02X1570790Y286064I-1028J953D01*
G37*
G36*
G01X560979Y284997D02*
G03X560608Y284565I28J-399D01*
G02X559116Y285846I-1397J-118D01*
G03X559487Y286278I-28J399D01*
G02X560979Y284997I1397J118D01*
G37*
G36*
G01X1315646Y285315D02*
G03X1315579Y284745I243J-318D01*
G02X1313636Y284974I-1089J-883D01*
G03X1313703Y285544I-243J318D01*
G02X1315646Y285315I1089J883D01*
G37*
G36*
G01X69311Y282571D02*
G03X69889I289J277D01*
G02Y280629I1011J-971D01*
G03X69311I-289J-277D01*
G02Y282571I-1011J971D01*
G37*
G36*
G01X1399552Y283306D02*
G03X1399680Y282764I343J-205D01*
G02X1397721Y282299I-754J-1182D01*
G03X1397593Y282841I-343J205D01*
G02X1399552Y283306I754J1182D01*
G37*
G36*
G01X1097703Y279975D02*
G03X1098242I269J295D01*
G02X1098239Y277904I944J-1037D01*
G03X1097700I-269J-295D01*
G02X1097703Y279975I-944J1037D01*
G37*
G36*
G01X448798Y277912D02*
G03X448198I-300J-265D01*
G02Y279770I-1050J929D01*
G03X448798I300J265D01*
G02Y277912I1050J-929D01*
G37*
G36*
G01X1434372Y279771D02*
G03Y279217I288J-277D01*
G02X1432352I-1010J-973D01*
G03Y279771I-288J277D01*
G02X1434372I1010J973D01*
G37*
G36*
G01X662303Y279878D02*
G03X662721Y279485I400J6D01*
G02X661384Y278062I65J-1401D01*
G03X660966Y278455I-400J-6D01*
G02X662303Y279878I-65J1401D01*
G37*
G36*
G01X60473Y279010D02*
G03X61027I277J288D01*
G02Y276990I973J-1010D01*
G03X60473I-277J-288D01*
G02Y279010I-973J1010D01*
G37*
G36*
G01X648422Y279263D02*
G03X648418Y278671I267J-298D01*
G02X646534Y278684I-949J-1032D01*
G03X646538Y279276I-267J298D01*
G02X648422Y279263I949J1032D01*
G37*
G36*
G01X1333680Y274524D02*
X1330171D01*
G02Y277546I0J1511D01*
G01X1333681D01*
G02X1335192Y276045I0J-1512D01*
G01Y275950D01*
X1335182Y275866D01*
G02X1333680Y274524I-1502J169D01*
G37*
G36*
G01X452389Y274629D02*
G03X451811I-289J-277D01*
G02Y276571I-1011J971D01*
G03X452389I289J277D01*
G02Y274629I1011J-971D01*
G37*
G36*
G01X778572Y275068D02*
G03X777973Y274913I-236J-323D01*
G02X777528Y276632I-1273J588D01*
G03X778127Y276787I236J323D01*
G02X778572Y275068I1273J-588D01*
G37*
G36*
G01X1637694Y276342D02*
G03Y275788I288J-277D01*
G02X1635674I-1010J-973D01*
G03Y276342I-288J277D01*
G02Y278288I1010J973D01*
G03Y278842I-288J277D01*
G02X1637694I1010J973D01*
G03Y278288I288J-277D01*
G02Y276342I-1010J-973D01*
G37*
G36*
G01X199827Y276169D02*
G03X199847Y276768I-254J308D01*
G02X199776Y276839I1097J1168D01*
G03X199204Y276852I-292J-273D01*
G02X197062Y279231I-1122J1144D01*
G03X197082Y279830I-254J308D01*
G02X199314Y282128I1100J1165D01*
G03X199867Y282116I283J283D01*
G02X202249Y281867I1080J-1183D01*
G03X202879Y281841I325J233D01*
G02X204855Y279865I1068J-908D01*
G03X204881Y279235I259J-305D01*
G02X204967Y276697I-934J-1302D01*
G03X204947Y276098I254J-308D01*
G02X202647Y273872I-1100J-1165D01*
G03X202047I-300J-265D01*
G02X199827Y276169I-1200J1062D01*
G37*
G36*
G01X824264Y273849D02*
G03X823664I-300J-265D01*
G02X821246Y275950I-1200J1061D01*
G03Y276470I-304J260D01*
G02Y278550I1218J1040D01*
G03Y279070I-304J260D01*
G02X823664Y281171I1218J1040D01*
G03X824264I300J265D01*
G02X826664I1200J-1061D01*
G03X827264I300J265D01*
G02X829664I1200J-1061D01*
G03X830264I300J265D01*
G02X832664I1200J-1061D01*
G03X833264I300J265D01*
G02X835584Y281255I1200J-1061D01*
G03X836144I280J286D01*
G02X838384I1120J-1145D01*
G03X838944I280J286D01*
G02X841282Y279070I1120J-1145D01*
G03Y278550I304J-260D01*
G02X838944Y276365I-1218J-1040D01*
G03X838384I-280J-286D01*
G02X838373Y276354I-1138J1127D01*
G03Y276066I139J-144D01*
G02X836144Y273765I-1109J-1156D01*
G03X835584I-280J-286D01*
G02X833264Y273849I-1120J1145D01*
G03X832664I-300J-265D01*
G02X830264I-1200J1061D01*
G03X829664I-300J-265D01*
G02X827264I-1200J1061D01*
G03X826664I-300J-265D01*
G02X824264I-1200J1061D01*
G37*
G36*
G01X850182Y273366D02*
G03X849582I-300J-265D01*
G02X847164Y275467I-1200J1061D01*
G03Y275987I-304J260D01*
G02X847199Y278107I1218J1040D01*
G03Y278647I-295J270D01*
G02X847164Y280767I1183J1080D01*
G03Y281287I-304J260D01*
G02X849582Y283388I1218J1040D01*
G03X850182I300J265D01*
G02X852582I1200J-1061D01*
G03X853182I300J265D01*
G02X855582I1200J-1061D01*
G03X856182I300J265D01*
G02X858600Y281287I1200J-1061D01*
G03Y280767I304J-260D01*
G02X858565Y278647I-1218J-1040D01*
G03Y278107I295J-270D01*
G02X858600Y275987I-1183J-1080D01*
G03Y275467I304J-260D01*
G02X856182Y273366I-1218J-1040D01*
G03X855582I-300J-265D01*
G02X853182I-1200J1061D01*
G03X852582I-300J-265D01*
G02X850182I-1200J1061D01*
G37*
G36*
G01X1340248Y270244D02*
X1336448D01*
G02Y273266I0J1511D01*
G01X1340249D01*
G02X1341760Y271765I0J-1512D01*
G01Y271670D01*
X1341750Y271586D01*
G02X1340248Y270244I-1502J169D01*
G37*
G36*
G01X184648Y273848D02*
G03X184644Y274431I-276J290D01*
G02X184615Y274459I1098J1166D01*
G03X184055I-280J-286D01*
G02X181823Y274451I-1120J1145D01*
G03X181203Y274371I-278J-288D01*
G02X178635Y274143I-1368J833D01*
G03X178035I-300J-265D01*
G02X175635I-1200J1061D01*
G03X175035I-300J-265D01*
G02X172617Y276244I-1200J1061D01*
G03Y276764I-304J260D01*
G02X175035Y278865I1218J1040D01*
G03X175635I300J265D01*
G02X178035I1200J-1061D01*
G03X178635I300J265D01*
G02X180947Y278957I1200J-1061D01*
G03X181567Y279037I278J288D01*
G02X184055Y279349I1368J-833D01*
G03X184615I280J286D01*
G02X186844Y279360I1120J-1145D01*
G03X187416Y279379I277J289D01*
G02X189679Y279484I1184J-1079D01*
G03X190239Y279504I270J295D01*
G02X190321Y277216I1161J-1104D01*
G03X189761Y277196I-270J-295D01*
G02X189758Y277193I-1134J1131D01*
G03X189745Y276654I289J-277D01*
G02X189613Y274419I-1210J-1050D01*
G03X189608Y273832I269J-296D01*
G02X189714Y271609I-1098J-1166D01*
G03X189707Y271089I300J-264D01*
G02X187392Y268885I-1232J-1023D01*
G03X186851I-271J-295D01*
G02X184552Y271108I-1083J1181D01*
G03X184550Y271633I-303J261D01*
G02X184648Y273848I1204J1056D01*
G37*
G36*
G01X1412345Y270158D02*
G03X1412700Y269670I390J-90D01*
G02X1411213Y268588I-121J-1397D01*
G03X1410858Y269076I-390J90D01*
G02X1412345Y270158I121J1397D01*
G37*
G36*
G01X1010655Y269874D02*
G03X1011064Y269502I399J28D01*
G02X1009701Y268003I36J-1402D01*
G03X1009292Y268375I-399J-28D01*
G02X1007949Y269270I-36J1402D01*
G03X1007382Y269475I-373J-145D01*
G02X1005785Y271762I-682J1225D01*
G03X1005777Y272375I-261J303D01*
G02X1007580Y272398I888J1085D01*
G03X1007588Y271785I261J-303D01*
G02X1008007Y271207I-888J-1085D01*
G03X1008574Y271002I373J145D01*
G02X1010655Y269874I682J-1225D01*
G37*
G36*
G01X361047D02*
G03X361456Y269502I399J28D01*
G02X360093Y268003I36J-1402D01*
G03X359684Y268375I-399J-28D01*
G02X358341Y269270I-36J1402D01*
G03X357774Y269475I-373J-145D01*
G02X356177Y271762I-682J1225D01*
G03X356169Y272375I-261J303D01*
G02X357972Y272398I888J1085D01*
G03X357980Y271785I261J-303D01*
G02X358399Y271207I-888J-1085D01*
G03X358966Y271002I373J145D01*
G02X361047Y269874I682J-1225D01*
G37*
G36*
G01X1347468Y266584D02*
X1343668D01*
G02Y269606I0J1511D01*
G01X1347469D01*
G02X1348980Y268105I0J-1512D01*
G01Y268010D01*
X1348970Y267926D01*
G02X1347468Y266584I-1502J169D01*
G37*
G36*
G01X748148Y268571D02*
G03X748170Y269192I-241J319D01*
G02X749932Y269129I920J1058D01*
G03X749910Y268508I241J-319D01*
G02X748148Y268571I-920J-1058D01*
G37*
G36*
G01X773929Y267748D02*
G03X774446Y267632I324J234D01*
G02X774006Y265368I725J-1316D01*
G03X773483Y265454I-310J-253D01*
G02X771490Y265684I-853J1356D01*
G03X770892Y265652I-285J-281D01*
G02X768945Y268092I-1255J995D01*
G03X769114Y268660I-173J361D01*
G02X771987Y268933I1371J829D01*
G03X772416Y268398I375J-139D01*
G02X773929Y267748I214J-1588D01*
G37*
G36*
G01X1356268Y264184D02*
X1352468D01*
G02Y267206I0J1511D01*
G01X1356269D01*
G02X1357780Y265705I0J-1512D01*
G01Y265610D01*
X1357770Y265526D01*
G02X1356268Y264184I-1502J170D01*
G37*
G36*
G01X1217244Y267082D02*
G03Y266528I288J-277D01*
G02X1215224I-1010J-973D01*
G03Y267082I-288J277D01*
G02X1217244I1010J973D01*
G37*
G36*
G01X567936D02*
G03Y266528I288J-277D01*
G02X565916I-1010J-973D01*
G03Y267082I-288J277D01*
G02X567936I1010J973D01*
G37*
G36*
G01X1381031Y264088D02*
X1377522D01*
G02Y267112I0J1512D01*
G01X1381032D01*
G02X1382542Y265610I-1J-1512D01*
G01Y265515D01*
X1382533Y265431D01*
G02X1381031Y264088I-1502J168D01*
G37*
G36*
G01X1362803Y267036D02*
X1366313D01*
G02X1367824Y265535I0J-1512D01*
G01Y265440D01*
X1367814Y265356D01*
G02X1366312Y264014I-1502J169D01*
G01X1362803D01*
G02Y267036I1J1511D01*
G37*
G36*
G01X1074367Y266089D02*
G03X1074899Y266044I291J274D01*
G02X1074698Y263668I966J-1278D01*
G03X1074166Y263713I-291J-274D01*
G02X1072074Y263851I-966J1278D01*
G03X1071495Y263833I-281J-285D01*
G02X1071426Y266040I-1195J1067D01*
G03X1072005Y266058I281J285D01*
G02X1074367Y266089I1195J-1067D01*
G37*
G36*
G01X1064599Y265863D02*
G03X1065178Y265844I299J266D01*
G02X1065103Y263636I1122J-1143D01*
G03X1064524Y263655I-299J-266D01*
G02X1062202Y263738I-1122J1144D01*
G03X1061602I-300J-265D01*
G02X1059092Y263877I-1200J1061D01*
G03X1058452Y263897I-327J-230D01*
G02X1056002Y263838I-1250J1002D01*
G03X1055402I-300J-265D01*
G02Y265960I-1200J1061D01*
G03X1056002I300J265D01*
G02X1058512Y265821I1200J-1061D01*
G03X1059152Y265801I327J230D01*
G02X1061602Y265860I1250J-1002D01*
G03X1062202I300J265D01*
G02X1064599Y265863I1200J-1061D01*
G37*
G36*
G01X437620Y263877D02*
G03X437658Y263359I322J-237D01*
G02X435228Y263181I-1139J-1127D01*
G03X435190Y263699I-322J237D01*
G02X437620Y263877I1139J1127D01*
G37*
G36*
G01X1628763Y261318D02*
G03X1628481Y260782I90J-390D01*
G02X1626286Y261349I-1304J-515D01*
G03X1626299Y261955I-255J309D01*
G02X1628763Y261318I1843J2044D01*
G37*
G36*
G01X1884784Y261829D02*
G03Y261229I265J-300D01*
G02X1882460Y259043I-1061J-1200D01*
G03X1881843Y259059I-315J-246D01*
G02X1879572Y261309I-1210J1050D01*
G03Y261909I-265J300D01*
G02X1881896Y264095I1061J1200D01*
G03X1882513Y264079I315J246D01*
G02X1884784Y261829I1210J-1050D01*
G37*
G36*
G01X1160308Y261401D02*
G03X1160313Y260793I262J-302D01*
G02X1158492Y260779I-902J-1073D01*
G03X1158487Y261387I-262J302D01*
G02X1160308Y261401I902J1073D01*
G37*
G36*
G01X1455205Y261089D02*
G03X1455127Y260534I244J-317D01*
G02X1453298Y260914I-1127J-834D01*
G03X1453342Y261226I-100J173D01*
G02X1453256Y261323I1005J978D01*
G03X1452944I-156J-125D01*
G02X1452823Y263210I-1094J877D01*
G03X1453377I277J288D01*
G02X1455205Y261089I972J-1010D01*
G37*
G36*
G01X1226918Y260827D02*
G03Y260273I288J-277D01*
G02X1224898I-1010J-973D01*
G03Y260827I-288J277D01*
G02X1226918I1010J973D01*
G37*
G36*
G01X576610D02*
G03Y260273I288J-277D01*
G02X574590I-1010J-973D01*
G03Y260827I-288J277D01*
G02X576610I1010J973D01*
G37*
G36*
G01X510478Y259111D02*
G03X510102Y258672I22J-399D01*
G02X508630Y259932I-1395J-140D01*
G03X509006Y260371I-22J399D01*
G02X510478Y259111I1395J140D01*
G37*
G36*
G01X1494858Y254727D02*
G03X1494307Y254648I-235J-324D01*
G02X1494023Y256641I-1108J859D01*
G03X1494574Y256720I235J324D01*
G02X1494678Y256839I1106J-861D01*
G03X1494681Y257394I-287J279D01*
G02X1496700Y257383I1015J967D01*
G03X1496697Y256828I287J-279D01*
G02X1494858Y254727I-1015J-967D01*
G37*
G36*
G01X1465810Y255243D02*
G03X1465890Y254676I316J-244D01*
G02X1463781Y252976I-827J-1132D01*
G03X1463257Y253182I-366J-161D01*
G02X1462861Y255863I-553J1288D01*
G03X1463304Y256225I44J398D01*
G02X1465810Y255243I1396J-125D01*
G37*
G36*
G01X621974Y254930D02*
G03X621904Y254340I231J-327D01*
G02X620041Y254561I-1054J-924D01*
G03X620111Y255151I-231J327D01*
G02X621974Y254930I1054J924D01*
G37*
G36*
G01X1275468Y254991D02*
G03X1275795Y254508I390J-88D01*
G02X1274209Y253432I-218J-1385D01*
G03X1273882Y253915I-390J88D01*
G02X1275468Y254991I218J1385D01*
G37*
G36*
G01X116610Y252884D02*
G03X116164Y253251I-399J-30D01*
G02X115528Y255963I-163J1392D01*
G03X115764Y256490I-135J377D01*
G02X117535Y255696I1299J526D01*
G03X117299Y255169I135J-377D01*
G02X117398Y254750I-1299J-528D01*
G03X117844Y254383I399J30D01*
G02X116610Y252884I164J-1392D01*
G37*
G36*
G01X1469444Y253888D02*
G03X1469999Y253876I284J282D01*
G02X1469956Y251858I951J-1030D01*
G03X1469401Y251870I-284J-282D01*
G02X1469444Y253888I-951J1030D01*
G37*
G36*
G01X766693Y253259D02*
G03X766354Y252751I45J-397D01*
G02X764846Y253756I-1347J-388D01*
G03X765185Y254264I-45J397D01*
G02X765602Y255701I1347J388D01*
G03X765624Y256278I-266J299D01*
G02X767562Y256203I1008J974D01*
G03X767540Y255626I266J-299D01*
G02X766693Y253259I-1008J-974D01*
G37*
G36*
G01X1479777Y253333D02*
G03X1479666Y252778I222J-333D01*
G02X1477723Y253167I-1166J-778D01*
G03X1477834Y253722I-222J333D01*
G02X1477627Y254782I1166J778D01*
G03X1477271Y255261I-392J80D01*
G02X1478770Y256375I126J1396D01*
G03X1479126Y255896I392J-80D01*
G02X1479777Y253333I-126J-1396D01*
G37*
G36*
G01X1434852Y253400D02*
G03X1434985Y252823I328J-228D01*
G02X1433148Y252400I-686J-1223D01*
G03X1433015Y252977I-328J228D01*
G02X1434852Y253400I686J1223D01*
G37*
G36*
G01X1817282Y248886D02*
X1812281D01*
G02X1812282Y252110I1J1612D01*
G01X1817282D01*
G02X1818894Y250508I0J-1612D01*
G01Y250413D01*
X1818884Y250328D01*
G02X1817282Y248886I-1602J169D01*
G37*
G36*
G01X1798384D02*
X1793384D01*
G02Y252110I0J1612D01*
G01X1798385D01*
G02X1799996Y250508I-1J-1612D01*
G01Y250413D01*
X1799986Y250328D01*
G02X1798384Y248886I-1602J169D01*
G37*
G36*
G01X1825702Y251794D02*
G03X1826143Y251395I400J-1D01*
G02X1824885Y250006I144J-1395D01*
G03X1824444Y250405I-400J1D01*
G02X1825702Y251794I-144J1395D01*
G37*
G36*
G01X1736800Y248939D02*
G03X1736200I-300J-265D01*
G02Y251061I-1200J1061D01*
G03X1736800I300J265D01*
G02X1739200I1200J-1061D01*
G03X1739800I300J265D01*
G02Y248939I1200J-1061D01*
G03X1739200I-300J-265D01*
G02X1736800I-1200J1061D01*
G37*
G36*
G01X1690282Y249679D02*
G03X1689813Y249382I-80J-392D01*
G02X1687183Y249118I-1362J334D01*
G03X1686664Y249315I-362J-171D01*
G02X1685186Y249552I-551J1289D01*
G03X1684632Y249528I-265J-300D01*
G02X1684542Y251545I-1017J965D01*
G03X1685096Y251569I265J300D01*
G02X1687381Y251202I1017J-965D01*
G03X1687900Y251005I362J171D01*
G02X1688734Y251089I551J-1289D01*
G03X1689203Y251386I80J392D01*
G02X1690282Y249679I1362J-334D01*
G37*
G36*
G01X1597653Y247276D02*
G03X1598245Y247267I300J264D01*
G02X1598217Y245384I1025J-957D01*
G03X1597625Y245393I-300J-264D01*
G02X1597653Y247276I-1025J957D01*
G37*
G36*
G01X199940Y245395D02*
G03X199360I-290J-275D01*
G02X197139Y247700I-1160J1105D01*
G03Y248300I-265J300D01*
G02Y250700I1061J1200D01*
G03Y251300I-265J300D01*
G02X197118Y251319I1064J1197D01*
G03X196499Y251219I-270J-295D01*
G02X196182Y253181I-1399J781D01*
G03X196801Y253281I270J295D01*
G02X199400Y253561I1399J-781D01*
G03X200000I300J265D01*
G02X202400I1200J-1061D01*
G03X203000I300J265D01*
G02X205400I1200J-1061D01*
G03X206000I300J265D01*
G02X208261Y251300I1200J-1061D01*
G03Y250700I265J-300D01*
G02X207939Y248078I-1061J-1200D01*
G03X207829Y247452I184J-355D01*
G02X205774Y245545I-1029J-952D01*
G03X205165Y245517I-293J-273D01*
G02X202780Y245355I-1265J983D01*
G03X202220I-280J-286D01*
G02X199940Y245395I-1120J1145D01*
G37*
G36*
G01X1468298Y245076D02*
G03X1467721Y244868I-201J-345D01*
G02X1467110Y246561I-1317J482D01*
G03X1467687Y246769I201J345D01*
G02X1470015Y247258I1317J-482D01*
G03X1470593I289J277D01*
G02Y245316I1011J-971D01*
G03X1470015I-289J-277D01*
G02X1468298Y245076I-1011J971D01*
G37*
G36*
G01X1510804Y246222D02*
G03X1510800Y245658I282J-284D01*
G02X1508810Y245669I-1000J-982D01*
G03X1508814Y246233I-282J284D01*
G02X1510804Y246222I1000J982D01*
G37*
G36*
G01X89240Y260118D02*
G03X89760I260J304D01*
G02X91840I1040J-1218D01*
G03X92360I260J304D01*
G02X94440I1040J-1218D01*
G03X94960I260J304D01*
G02X97040I1040J-1218D01*
G03X97560I260J304D01*
G02X99818Y257860I1040J-1218D01*
G03Y257340I304J-260D01*
G02X99705Y255140I-1218J-1040D01*
G03Y254560I275J-290D01*
G02X99661Y252200I-1105J-1160D01*
G03Y251600I265J-300D01*
G02Y249200I-1061J-1200D01*
G03Y248600I265J-300D01*
G02Y246200I-1061J-1200D01*
G03Y245600I265J-300D01*
G02X97560Y243182I-1061J-1200D01*
G03X97040I-260J-304D01*
G02X94960I-1040J1218D01*
G03X94440I-260J-304D01*
G02X92360I-1040J1218D01*
G03X91840I-260J-304D01*
G02X89760I-1040J1218D01*
G03X89240I-260J-304D01*
G02X87139Y245600I-1040J1218D01*
G03Y246200I-265J300D01*
G02Y248600I1061J1200D01*
G03Y249200I-265J300D01*
G02Y251600I1061J1200D01*
G03Y252200I-265J300D01*
G02X87095Y254560I1061J1200D01*
G03Y255140I-275J290D01*
G02X86982Y257340I1105J1160D01*
G03Y257860I-304J260D01*
G02X89240Y260118I1218J1040D01*
G37*
G36*
G01X1662588Y245377D02*
G03X1662981Y244984I400J7D01*
G02X1661554Y243557I-25J-1402D01*
G03X1661161Y243950I-400J-7D01*
G02X1662588Y245377I25J1402D01*
G37*
G36*
G01X1215804Y244399D02*
G03X1216413Y244396I306J258D01*
G02X1216404Y242579I1063J-914D01*
G03X1215795Y242582I-306J-258D01*
G02X1215804Y244399I-1063J914D01*
G37*
G36*
G01X569422Y242495D02*
G03X568860Y242491I-279J-286D01*
G02X566796Y242579I-992J991D01*
G03X566187Y242582I-306J-258D01*
G02X566196Y244399I-1063J914D01*
G03X566805Y244396I306J258D01*
G02X568846Y244487I1063J-914D01*
G03X569408Y244491I279J286D01*
G02X569422Y242495I992J-991D01*
G37*
G36*
G01X1548542Y245073D02*
G03X1548652Y244519I333J-222D01*
G02X1546702Y244133I-783J-1163D01*
G03X1546592Y244687I-333J222D01*
G02X1548542Y245073I783J1163D01*
G37*
G36*
G01X1515570Y244955D02*
G03Y244424I299J-266D01*
G02X1513172Y244422I-1198J-1063D01*
G03Y244953I-299J265D01*
G02X1513153Y247057I1198J1063D01*
G03Y247577I-304J260D01*
G02X1515589Y247575I1219J1039D01*
G03Y247055I304J-260D01*
G02X1515570Y244955I-1219J-1039D01*
G37*
G36*
G01X1626025Y242615D02*
G03X1626599Y242478I350J194D01*
G02X1625390Y240152I1543J-2279D01*
G03X1624948Y240543I-400J-7D01*
G02X1626025Y242615I-150J1394D01*
G37*
G36*
G01X1779451Y236100D02*
X1774450D01*
G02X1774451Y239324I1J1612D01*
G01X1779451D01*
G02X1781062Y237722I0J-1611D01*
G01Y237627D01*
X1781053Y237542D01*
G02X1779451Y236100I-1602J169D01*
G37*
G36*
G01X1760554D02*
X1755554D01*
G02Y239324I0J1612D01*
G01X1760555D01*
G02X1762166Y237722I-1J-1612D01*
G01Y237627D01*
X1762156Y237542D01*
G02X1760554Y236100I-1602J169D01*
G37*
G36*
G01X642759Y237588D02*
G03Y237068I304J-260D01*
G02X640323I-1218J-1040D01*
G03Y237588I-304J260D01*
G02Y239668I1218J1040D01*
G03Y240188I-304J260D01*
G02Y242268I1218J1040D01*
G03Y242788I-304J260D01*
G02X642759I1218J1040D01*
G03Y242268I304J-260D01*
G02Y240188I-1218J-1040D01*
G03Y239668I304J-260D01*
G02Y237588I-1218J-1040D01*
G37*
G36*
G01X1572141Y234659D02*
G03X1571596Y234427I-167J-363D01*
G02X1570861Y236161I-1324J462D01*
G03X1571406Y236393I167J363D01*
G02X1572753Y237333I1324J-462D01*
G03X1573159Y237717I6J400D01*
G02X1573165Y237800I1401J-60D01*
G03X1572933Y238017I-199J20D01*
G02X1572213Y238085I-233J1383D01*
G03X1571684Y237800I-139J-375D01*
G02X1570805Y239431I-1366J316D01*
G03X1571334Y239716I139J375D01*
G02X1573024Y240764I1366J-316D01*
G03X1573512Y241097I92J389D01*
G02X1574377Y239599I1388J-197D01*
G03X1574102Y239412I-75J-185D01*
G02X1574095Y239260I-1402J-12D01*
G03X1574327Y239043I199J-20D01*
G02X1574537Y236258I232J-1383D01*
G03X1574131Y235874I-6J-400D01*
G02X1572141Y234659I-1401J57D01*
G37*
G36*
G01X772003Y236299D02*
G03X771937Y235762I260J-304D01*
G02X769730Y236157I-1305J-929D01*
G03X769767Y236455I-112J165D01*
G02X769672Y236574I1203J1058D01*
G03X769385Y236612I-162J-118D01*
G02X769575Y238930I-1003J1249D01*
G03X770091Y238862I298J267D01*
G02X772027Y238718I873J-1343D01*
G03X772594Y238754I266J299D01*
G02X772738Y236501I1206J-1054D01*
G03X772171Y236465I-266J-299D01*
G02X772003Y236299I-1207J1053D01*
G37*
G36*
G01X1844293Y237781D02*
G03X1844175Y237187I197J-348D01*
G02X1839851Y237383I-2246J-1757D01*
G03X1839724Y238022I-291J274D01*
G02X1841617Y238819I576J1278D01*
G03X1841985Y238281I376J-138D01*
G02X1842075Y238278I-50J-2851D01*
G03X1842275Y238543I11J200D01*
G02X1844293Y237781I1325J457D01*
G37*
G36*
G01X1682700Y234573D02*
G03X1683292Y234554I305J259D01*
G02X1683232Y232671I1008J-975D01*
G03X1682640Y232690I-305J-259D01*
G02X1682700Y234573I-1008J975D01*
G37*
G36*
G01X1767985Y232438D02*
G03X1767403Y232224I-204J-344D01*
G02X1766792Y233887I-1326J457D01*
G03X1767374Y234101I204J344D01*
G02X1767985Y232438I1326J-457D01*
G37*
G36*
G01X1804379Y233482D02*
G03X1805001Y233476I313J248D01*
G02X1804984Y231713I1082J-892D01*
G03X1804362Y231719I-313J-248D01*
G02X1804379Y233482I-1082J892D01*
G37*
G36*
G01X1794608Y234126D02*
G03X1794630Y233549I288J-278D01*
G02X1792692Y233474I-930J-1049D01*
G03X1792670Y234051I-288J278D01*
G02X1794608Y234126I930J1049D01*
G37*
G36*
G01X1883239Y233459D02*
G03X1883271Y232890I296J-269D01*
G02X1881306Y232778I-926J-1053D01*
G03X1881274Y233347I-296J269D01*
G02X1882924Y235600I926J1052D01*
G03X1883468Y235728I206J343D01*
G02X1883927Y233775I1183J-752D01*
G03X1883383Y233647I-206J-343D01*
G02X1883239Y233459I-1181J755D01*
G37*
G36*
G01X824272Y230535D02*
G03X823747Y230530I-260J-304D01*
G02X821464Y232767I-1064J1197D01*
G03Y233287I-304J260D01*
G02X821499Y235407I1218J1040D01*
G03Y235947I-295J270D01*
G02X821464Y238067I1183J1080D01*
G03Y238587I-304J260D01*
G02X823882Y240688I1218J1040D01*
G03X824482I300J265D01*
G02X826882I1200J-1061D01*
G03X827482I300J265D01*
G02X829882I1200J-1061D01*
G03X830482I300J265D01*
G02X832882I1200J-1061D01*
G03X833482I300J265D01*
G02X835861Y240712I1200J-1061D01*
G03X836424Y240687I294J271D01*
G02X838625Y238360I1076J-1187D01*
G03Y237790I281J-285D01*
G02X839043Y236218I-1125J-1141D01*
G03X839573Y235738I385J-108D01*
G02X839180Y232974I582J-1493D01*
G03X838650Y232935I-243J-318D01*
G02X836319Y232968I-1150J1115D01*
G03X835759Y232998I-295J-270D01*
G02X833448Y233200I-1059J1202D01*
G03X832845Y233226I-313J-249D01*
G02X830482Y233266I-1163J1101D01*
G03X829882I-300J-265D01*
G02X829668Y233064I-1202J1059D01*
G03X829567Y232549I246J-316D01*
G02X827031Y230632I-1387J-800D01*
G03X826458Y230633I-287J-279D01*
G02X824272Y230535I-1145J1120D01*
G37*
G36*
G01X1926924Y232852D02*
G03X1926983Y232289I311J-252D01*
G02X1925011Y232083I-883J-1089D01*
G03X1924952Y232646I-311J252D01*
G02X1926924Y232852I883J1089D01*
G37*
G36*
G01X186410Y240955D02*
G03X186979Y240945I289J276D01*
G02X189200Y238635I1121J-1145D01*
G03X189220Y238036I274J-291D01*
G02X189384Y235721I-1020J-1236D01*
G03X189404Y235161I295J-270D01*
G02X186995Y233070I-1105J-1160D01*
G03X186386Y233120I-326J-232D01*
G02X184090Y233145I-1136J1130D01*
G03X183521Y233155I-289J-276D01*
G02X181200Y233239I-1121J1145D01*
G03X180600I-300J-265D01*
G02X178200I-1200J1061D01*
G03X177600I-300J-265D01*
G02X177512Y233147I-1201J1060D01*
G03X177524Y232848I139J-144D01*
G02X175332Y230521I-1017J-1238D01*
G03X174711Y230479I-294J-272D01*
G02X172295Y232560I-1311J921D01*
G03Y233140I-275J290D01*
G02X172217Y235380I1105J1160D01*
G03Y235920I-295J270D01*
G02X172295Y238160I1183J1080D01*
G03Y238740I-275J290D01*
G02X174600Y240961I1105J1160D01*
G03X175200I300J265D01*
G02X177600I1200J-1061D01*
G03X178200I300J265D01*
G02X180600I1200J-1061D01*
G03X181200I300J265D01*
G02X183560Y241005I1200J-1061D01*
G03X184129Y240995I289J276D01*
G02X186410Y240955I1121J-1145D01*
G37*
G36*
G01X1499741Y233065D02*
G03X1499981Y232510I360J-174D01*
G02X1498296Y231783I-422J-1337D01*
G03X1498056Y232338I-360J174D01*
G02X1499741Y233065I422J1337D01*
G37*
G36*
G01X578805Y232720D02*
G03X578809Y232141I278J-288D01*
G02X576876Y232128I-960J-1022D01*
G03X576872Y232707I-278J288D01*
G02X578805Y232720I960J1022D01*
G37*
G36*
G01X1387761Y232456D02*
G03X1388231Y232161I388J96D01*
G02X1387157Y230451I287J-1372D01*
G03X1386687Y230746I-388J-96D01*
G02X1387761Y232456I-287J1372D01*
G37*
G36*
G01X1968220Y228637D02*
G03X1967580I-320J-240D01*
G02Y230563I-1280J963D01*
G03X1968220I320J240D01*
G02Y228637I1280J-963D01*
G37*
G36*
G01X571477Y230511D02*
G03X571449Y229950I270J-295D01*
G02X569455Y230047I-1045J-935D01*
G03X569483Y230608I-270J295D01*
G02X571477Y230511I1045J935D01*
G37*
G36*
G01X1939229Y229179D02*
G03X1939773Y229172I276J290D01*
G02X1939745Y226821I1074J-1188D01*
G03X1939201Y226828I-276J-290D01*
G02X1939229Y229179I-1074J1188D01*
G37*
G36*
G01X89640Y237668D02*
G03X90160I260J304D01*
G02X92240I1040J-1218D01*
G03X92760I260J304D01*
G02X94840I1040J-1218D01*
G03X95360I260J304D01*
G02X97440I1040J-1218D01*
G03X97960I260J304D01*
G02X100061Y235250I1040J-1218D01*
G03Y234650I265J-300D01*
G02Y232250I-1061J-1200D01*
G03Y231650I265J-300D01*
G02Y229250I-1061J-1200D01*
G03Y228650I265J-300D01*
G02X97960Y226232I-1061J-1200D01*
G03X97440I-260J-304D01*
G02X95360I-1040J1218D01*
G03X94840I-260J-304D01*
G02X92760I-1040J1218D01*
G03X92240I-260J-304D01*
G02X90160I-1040J1218D01*
G03X89640I-260J-304D01*
G02X87539Y228650I-1040J1218D01*
G03Y229250I-265J300D01*
G02Y231650I1061J1200D01*
G03Y232250I-265J300D01*
G02Y234650I1061J1200D01*
G03Y235250I-265J300D01*
G02X89640Y237668I1061J1200D01*
G37*
G36*
G01X703380Y225694D02*
G03X702770I-305J-259D01*
G02Y227506I-1070J906D01*
G03X703380I305J259D01*
G02Y225694I1070J-906D01*
G37*
G36*
G01X1253531Y228169D02*
G03X1253880Y227627I374J-143D01*
G02X1252796Y225241I-89J-1399D01*
G03X1252264Y225273I-284J-282D01*
G02X1250295Y225504I-869J1100D01*
G03X1249691Y225531I-314J-248D01*
G02X1249772Y227363I-1019J963D01*
G03X1250376Y227336I314J248D01*
G02X1250745Y227615I1018J-963D01*
G03X1250929Y228125I-185J355D01*
G02X1253531Y228169I1292J543D01*
G37*
G36*
G01X1945635Y227689D02*
G03X1945738Y227143I334J-220D01*
G02X1943753Y226770I-813J-1142D01*
G03X1943650Y227316I-334J220D01*
G02X1945635Y227689I813J1142D01*
G37*
G36*
G01X1627679Y224282D02*
G03X1627124Y224267I-270J-295D01*
G02X1627069Y226286I-1000J983D01*
G03X1627624Y226301I270J295D01*
G02X1627679Y224282I1000J-983D01*
G37*
G36*
G01X1883427Y223090D02*
G03X1882873I-277J-288D01*
G02Y225110I-973J1010D01*
G03X1883427I277J288D01*
G02Y223090I973J-1010D01*
G37*
G36*
G01X1401311Y222717D02*
G03X1400689I-311J-252D01*
G02Y224483I-1089J883D01*
G03X1401311I311J252D01*
G02Y222717I1089J-883D01*
G37*
G36*
G01X1622167Y224930D02*
G03Y224372I286J-279D01*
G02X1620161I-1003J-980D01*
G03Y224930I-286J279D01*
G02X1622167I1003J980D01*
G37*
G36*
G01X1245144Y223407D02*
G03X1244700Y223029I-44J-398D01*
G02X1243456Y224493I-1400J71D01*
G03X1243900Y224871I44J398D01*
G02X1245144Y223407I1400J-71D01*
G37*
G36*
G01X767662Y224140D02*
G03X767640Y223563I266J-299D01*
G02X765702Y223638I-1008J-974D01*
G03X765724Y224215I-266J299D01*
G02X767662Y224140I1008J974D01*
G37*
G36*
G01X638219Y223697D02*
G03Y223177I304J-260D01*
G02X635783I-1218J-1040D01*
G03Y223697I-304J260D01*
G02Y225777I1218J1040D01*
G03Y226297I-304J260D01*
G02Y228377I1218J1040D01*
G03Y228897I-304J260D01*
G02X638219I1218J1040D01*
G03Y228377I304J-260D01*
G02Y226297I-1218J-1040D01*
G03Y225777I304J-260D01*
G02Y223697I-1218J-1040D01*
G37*
G36*
G01X714708Y223170D02*
G03X714730Y222593I288J-278D01*
G02X712792Y222518I-930J-1049D01*
G03X712770Y223095I-288J278D01*
G02X714708Y223170I930J1049D01*
G37*
G36*
G01X115652Y224178D02*
G03X115823Y224709I-187J353D01*
G02X117738Y224092I1257J621D01*
G03X117567Y223561I187J-353D01*
G02X117707Y222824I-1257J-621D01*
G03X118084Y222391I399J-34D01*
G02X116611Y221107I-76J-1400D01*
G03X116234Y221540I-399J34D01*
G02X115652Y224178I76J1400D01*
G37*
G36*
G01X1911372Y222246D02*
G03X1911367Y221696I288J-278D01*
G02X1909230Y221597I-1027J-955D01*
G03X1909174Y222144I-317J244D01*
G02X1909022Y224423I1045J1214D01*
G03X1909009Y224969I-299J266D01*
G02X1911350Y225025I1144J1121D01*
G03X1911363Y224479I299J-266D01*
G02X1911372Y222246I-1144J-1121D01*
G37*
G36*
G01X1627988Y218701D02*
G03X1628578Y218690I300J264D01*
G02X1628542Y216799I1017J-965D01*
G03X1627952Y216810I-300J-264D01*
G02X1627988Y218701I-1017J965D01*
G37*
G36*
G01X94077Y218891D02*
G03X94053Y219509I-266J299D01*
G02X93755Y219794I1088J1436D01*
G03X93150Y219805I-307J-256D01*
G02X90389Y219899I-1341J1204D01*
G03X89779Y219922I-315J-247D01*
G02X87038Y220013I-1332J1214D01*
G03X86446Y220050I-313J-249D01*
G02X86597Y222464I-1258J1290D01*
G03X87189Y222427I313J249D01*
G02X89867Y222246I1258J-1291D01*
G03X90477Y222223I315J247D01*
G02X93194Y222161I1332J-1214D01*
G03X93799Y222150I307J256D01*
G02X96338Y219600I1341J-1204D01*
G03X96362Y218982I266J-299D01*
G02X94077Y218891I-1087J-1437D01*
G37*
G36*
G01X1592264Y213948D02*
G03X1591703Y213814I-216J-337D01*
G02X1589500Y215513I-1208J711D01*
G03X1589507Y216069I-284J282D01*
G02X1590941Y218372I1018J964D01*
G03X1591421Y218583I118J382D01*
G02X1593973Y216738I1449J-683D01*
G03X1593975Y216155I275J-291D01*
G02X1592264Y213948I-955J-1026D01*
G37*
G36*
G01X1898421Y215540D02*
G03Y214962I277J-289D01*
G02X1896479I-971J-1011D01*
G03Y215540I-277J289D01*
G02X1898421I971J1011D01*
G37*
G36*
G01X1612670Y215183D02*
G03Y214574I260J-305D01*
G02X1610852I-909J-1067D01*
G03Y215183I-260J304D01*
G02X1612670I909J1067D01*
G37*
G36*
G01X715613Y215122D02*
G03X715771Y214575I349J-196D01*
G02X713878Y214031I-671J-1231D01*
G03X713720Y214578I-349J196D01*
G02X714134Y217187I671J1231D01*
G03X714431Y217733I-73J393D01*
G02X715984Y216889I1296J534D01*
G03X715687Y216343I73J-393D01*
G02X715613Y215122I-1296J-534D01*
G37*
G36*
G01X591383Y214711D02*
G03Y214089I252J-311D01*
G02X589617I-883J-1089D01*
G03Y214711I-252J311D01*
G02X591383I883J1089D01*
G37*
G36*
G01X824127Y213264D02*
G03X823755Y212761I14J-400D01*
G02X821097Y212917I-1355J-361D01*
G03X820873Y213437I-372J148D01*
G02X820418Y216137I593J1488D01*
G03X820480Y216674I-262J302D01*
G02X822907Y218751I1295J944D01*
G03X823440Y218723I282J283D01*
G02X825615Y218572I1006J-1247D01*
G03X826189Y218563I291J274D01*
G02X828825Y216876I1133J-1133D01*
G03X829226Y216339I375J-138D01*
G02X830502Y215829I101J-1599D01*
G03X831091Y215832I293J272D01*
G02X831101Y213665I1185J-1078D01*
G03X830512Y213662I-293J-272D01*
G02X828247Y213556I-1185J1078D01*
G03X827723Y213569I-269J-295D01*
G02X825620Y213619I-1023J1233D01*
G03X825095Y213632I-270J-295D01*
G02X824127Y213264I-1023J1233D01*
G37*
G36*
G01X1814125Y210720D02*
X1809125D01*
G02Y213742I0J1511D01*
G01X1814126D01*
G02X1815636Y212241I-1J-1511D01*
G01Y212146D01*
X1815627Y212062D01*
G02X1814125Y210720I-1502J169D01*
G37*
G36*
G01X1801526D02*
X1796526D01*
G02Y213742I0J1511D01*
G01X1801527D01*
G02X1803038Y212241I0J-1512D01*
G01Y212146D01*
X1803028Y212062D01*
G02X1801526Y210720I-1502J169D01*
G37*
G36*
G01X1826685Y210650D02*
X1821685D01*
G02Y213672I0J1511D01*
G01X1826686D01*
G02X1828196Y212171I-1J-1511D01*
G01Y212076D01*
X1828187Y211992D01*
G02X1826685Y210650I-1502J169D01*
G37*
G36*
G01X778862Y211127D02*
G03X778252I-305J-259D01*
G02Y212939I-1070J906D01*
G03X778862I305J259D01*
G02Y211127I1070J-906D01*
G37*
G36*
G01X129393Y210985D02*
G03X128822Y210945I-266J-299D01*
G02X128685Y212901I-1068J908D01*
G03X129256Y212941I266J299D01*
G02X129393Y210985I1068J-908D01*
G37*
G36*
G01X1788925Y210120D02*
X1783925D01*
G02Y213142I0J1511D01*
G01X1788926D01*
G02X1790436Y211641I-1J-1511D01*
G01Y211546D01*
X1790427Y211462D01*
G02X1788925Y210120I-1502J169D01*
G37*
G36*
G01X1776325D02*
X1771325D01*
G02Y213142I0J1511D01*
G01X1776326D01*
G02X1777836Y211641I-1J-1511D01*
G01Y211546D01*
X1777827Y211462D01*
G02X1776325Y210120I-1502J169D01*
G37*
G36*
G01X1763725D02*
X1758725D01*
G02Y213142I0J1511D01*
G01X1763726D01*
G02X1765236Y211641I-1J-1511D01*
G01Y211546D01*
X1765227Y211462D01*
G02X1763725Y210120I-1502J169D01*
G37*
G36*
G01X1751125D02*
X1746125D01*
G02Y213142I0J1511D01*
G01X1751126D01*
G02X1752636Y211641I-1J-1511D01*
G01Y211546D01*
X1752627Y211462D01*
G02X1751125Y210120I-1502J169D01*
G37*
G36*
G01X1738484D02*
X1733484D01*
G02Y213142I0J1511D01*
G01X1738485D01*
G02X1739996Y211641I0J-1512D01*
G01Y211546D01*
X1739986Y211462D01*
G02X1738484Y210120I-1502J169D01*
G37*
G36*
G01X1863263Y210799D02*
G03X1862670Y210713I-259J-305D01*
G02X1860096Y211423I-1173J768D01*
G03X1859676Y211806I-400J-16D01*
G02X1861005Y213264I-72J1400D01*
G03X1861425Y212881I400J16D01*
G02X1862404Y212551I73J-1400D01*
G03X1862997Y212637I259J305D01*
G02X1863263Y210799I1173J-769D01*
G37*
G36*
G01X1726480Y210155D02*
G03X1725920I-280J-286D01*
G02Y212445I-1120J1145D01*
G03X1726480I280J286D01*
G02Y210155I1120J-1145D01*
G37*
G36*
G01X89628Y210958D02*
G03X89293Y210468I54J-396D01*
G02X85796Y210488I-1751J-425D01*
G03X85362Y210984I-388J99D01*
G02X83439Y213322I-206J1790D01*
G03X83114Y213840I-381J122D01*
G02X85083Y215076I252J1784D01*
G03X85408Y214558I381J-122D01*
G02X85527Y214537I-253J-1784D01*
G03X85753Y214810I41J196D01*
G02X89158Y215043I1663J694D01*
G03X89516Y214541I387J-103D01*
G02X89697Y214519I-127J-1797D01*
G03X89921Y214781I35J197D01*
G02X91562Y213563I1705J583D01*
G03X91155Y213087I-14J-400D01*
G02X89628Y210958I-1769J-343D01*
G37*
G36*
G01X1358537Y208181D02*
G03X1357965Y208159I-275J-290D01*
G02X1357889Y210119I-1039J941D01*
G03X1358461Y210141I275J290D01*
G02X1360432Y210247I1039J-941D01*
G03X1360987Y210269I266J299D01*
G02X1361068Y208253I1013J-969D01*
G03X1360513Y208231I-266J-299D01*
G02X1358537Y208181I-1013J969D01*
G37*
G36*
G01X1227826Y209464D02*
G03X1227844Y208909I297J-268D01*
G02X1225826Y208843I-977J-1005D01*
G03X1225808Y209398I-297J268D01*
G02X1225814Y211414I977J1005D01*
G03Y211992I-277J289D01*
G02X1225978Y214149I971J1011D01*
G03X1226070Y214713I-230J327D01*
G02X1228007Y214397I1130J830D01*
G03X1227915Y213833I230J-327D01*
G02X1227756Y211992I-1130J-830D01*
G03Y211414I277J-289D01*
G02X1227826Y209464I-971J-1011D01*
G37*
G36*
G01X1475934Y208720D02*
G03X1475721Y208189I153J-369D01*
G02X1473906Y208918I-1282J-568D01*
G03X1474119Y209449I-153J369D01*
G02X1475934Y208720I1282J568D01*
G37*
G36*
G01X1479760Y208891D02*
G03X1479846Y208343I328J-229D01*
G02X1477851Y208029I-846J-1118D01*
G03X1477765Y208577I-328J229D01*
G02X1479760Y208891I846J1118D01*
G37*
G36*
G01X617675Y205984D02*
G03X617121I-277J-288D01*
G02Y208004I-973J1010D01*
G03X617675I277J288D01*
G02X617771Y208088I970J-1012D01*
G03Y208400I-125J156D01*
G02X619658Y208521I877J1094D01*
G03Y207967I288J-277D01*
G02X619742Y207871I-1012J-970D01*
G03X620054I156J125D01*
G02X622121Y208004I1094J-877D01*
G03X622675I277J288D01*
G02X622771Y208088I970J-1012D01*
G03Y208400I-125J156D01*
G02X622638Y210467I877J1094D01*
G03Y211021I-288J277D01*
G02X622554Y211117I1012J970D01*
G03X622242I-156J-125D01*
G02X622121Y213004I-1094J877D01*
G03X622675I277J288D01*
G02X622771Y213088I970J-1012D01*
G03Y213400I-125J156D01*
G02X622638Y215467I877J1094D01*
G03Y216021I-288J277D01*
G02X622554Y216117I1012J970D01*
G03X622242I-156J-125D01*
G02X622121Y218004I-1094J877D01*
G03X622675I277J288D01*
G02X622771Y218088I970J-1012D01*
G03Y218400I-125J156D01*
G02X622638Y220467I877J1094D01*
G03Y221021I-288J277D01*
G02X622554Y221117I1012J970D01*
G03X622242I-156J-125D01*
G02X622121Y223004I-1094J877D01*
G03X622675I277J288D01*
G02X622771Y223088I970J-1012D01*
G03Y223400I-125J156D01*
G02X622638Y225467I877J1094D01*
G03Y226021I-288J277D01*
G02X622554Y226117I1012J970D01*
G03X622242I-156J-125D01*
G02X620175Y225984I-1094J877D01*
G03X619621I-277J-288D01*
G02X619525Y225900I-970J1012D01*
G03Y225588I125J-156D01*
G02X617638Y225467I-877J-1094D01*
G03Y226021I-288J277D01*
G02X617554Y226117I1012J970D01*
G03X617242I-156J-125D01*
G02X615175Y225984I-1094J877D01*
G03X614621I-277J-288D01*
G02X614525Y225900I-970J1012D01*
G03Y225588I125J-156D01*
G02X614658Y223521I-877J-1094D01*
G03Y222967I288J-277D01*
G02X614742Y222871I-1012J-970D01*
G03X615054I156J125D01*
G02X615175Y220984I1094J-877D01*
G03X614621I-277J-288D01*
G02X614525Y220900I-970J1012D01*
G03Y220588I125J-156D01*
G02X614658Y218521I-877J-1094D01*
G03Y217967I288J-277D01*
G02X614742Y217871I-1012J-970D01*
G03X615054I156J125D01*
G02X615175Y215984I1094J-877D01*
G03X614621I-277J-288D01*
G02X614525Y215900I-970J1012D01*
G03Y215588I125J-156D01*
G02X614658Y213521I-877J-1094D01*
G03Y212967I288J-277D01*
G02X614742Y212871I-1012J-970D01*
G03X615054I156J125D01*
G02X615175Y210984I1094J-877D01*
G03X614621I-277J-288D01*
G02X614525Y210900I-970J1012D01*
G03Y210588I125J-156D01*
G02X612638Y210467I-877J-1094D01*
G03Y211021I-288J277D01*
G02Y212967I1010J973D01*
G03Y213521I-288J277D01*
G02Y215467I1010J973D01*
G03Y216021I-288J277D01*
G02Y217967I1010J973D01*
G03Y218521I-288J277D01*
G02Y220467I1010J973D01*
G03Y221021I-288J277D01*
G02X612554Y221117I1012J970D01*
G03X612242I-156J-125D01*
G02X610138Y222967I-1094J877D01*
G03Y223521I-288J277D01*
G02X610054Y223617I1012J970D01*
G03X609742I-156J-125D01*
G02X607638Y225467I-1094J877D01*
G03Y226021I-288J277D01*
G02X609658I1010J973D01*
G03Y225467I288J-277D01*
G02X609742Y225371I-1012J-970D01*
G03X610054I156J125D01*
G02X612121Y225504I1094J-877D01*
G03X612675I277J288D01*
G02X612771Y225588I970J-1012D01*
G03Y225900I-125J156D01*
G02X612638Y227967I877J1094D01*
G03Y228521I-288J277D01*
G02X612554Y228617I1012J970D01*
G03X612242I-156J-125D01*
G02X612121Y230504I-1094J877D01*
G03X612675I277J288D01*
G02X614658Y228521I973J-1010D01*
G03Y227967I288J-277D01*
G02X614742Y227871I-1012J-970D01*
G03X615054I156J125D01*
G02X617121Y228004I1094J-877D01*
G03X617675I277J288D01*
G02X617771Y228088I970J-1012D01*
G03Y228400I-125J156D01*
G02X619621Y230504I877J1094D01*
G03X620175I277J288D01*
G02X622158Y228521I973J-1010D01*
G03Y227967I288J-277D01*
G02X622242Y227871I-1012J-970D01*
G03X622554I156J125D01*
G02X624658Y226021I1094J-877D01*
G03Y225467I288J-277D01*
G02Y223521I-1010J-973D01*
G03Y222967I288J-277D01*
G02Y221021I-1010J-973D01*
G03Y220467I288J-277D01*
G02Y218521I-1010J-973D01*
G03Y217967I288J-277D01*
G02Y216021I-1010J-973D01*
G03Y215467I288J-277D01*
G02Y213521I-1010J-973D01*
G03Y212967I288J-277D01*
G02Y211021I-1010J-973D01*
G03Y210467I288J-277D01*
G02Y208521I-1010J-973D01*
G03Y207967I288J-277D01*
G02X622675Y205984I-1010J-973D01*
G03X622121I-277J-288D01*
G02X620175I-973J1010D01*
G03X619621I-277J-288D01*
G02X617675I-973J1010D01*
G37*
G36*
G01X1856789Y207274D02*
G03X1857411Y207253I319J241D01*
G02X1857351Y205491I1059J-918D01*
G03X1856729Y205512I-319J-241D01*
G02X1856789Y207274I-1059J918D01*
G37*
G36*
G01X1222271Y206989D02*
G03Y206411I277J-289D01*
G02X1220329I-971J-1011D01*
G03Y206989I-277J289D01*
G02X1222271I971J1011D01*
G37*
G36*
G01X1517619Y204557D02*
G03X1517615Y204002I286J-280D01*
G02X1515595Y204017I-1017J-965D01*
G03X1515599Y204572I-286J280D01*
G02X1517619Y204557I1017J965D01*
G37*
G36*
G01X708189Y200329D02*
G03X707611I-289J-277D01*
G02X705698Y202374I-1011J972D01*
G03X705677Y203003I-257J306D01*
G02X707756Y205127I884J1214D01*
G03X708320Y205054I318J242D01*
G02X710479Y204479I862J-1106D01*
G03X711061Y204291I370J152D01*
G02X711171Y201847I739J-1191D01*
G03X710594Y201447I-179J-358D01*
G02X708189Y200329I-1394J-147D01*
G37*
G36*
G01X1884247Y201333D02*
G03X1884271Y201009I128J-153D01*
G02X1882499Y200753I-732J-1196D01*
G03X1882457Y201329I-297J268D01*
G02X1884491Y203224I893J1081D01*
G03X1885100Y203174I326J232D01*
G02X1884952Y201370I993J-990D01*
G03X1884343Y201420I-326J-232D01*
G02X1884247Y201333I-988J994D01*
G37*
G36*
G01X1227471Y201389D02*
G03Y200811I277J-289D01*
G02X1225529I-971J-1011D01*
G03Y201389I-277J289D01*
G02X1227471I971J1011D01*
G37*
G36*
G01X1546924Y199009D02*
G03X1546944Y198437I289J-276D01*
G02X1544986Y198368I-944J-1037D01*
G03X1544966Y198940I-289J276D01*
G02X1546924Y199009I944J1037D01*
G37*
G36*
G01X1763668Y195332D02*
X1758668D01*
G02Y198354I0J1511D01*
G01X1763669D01*
G02X1765180Y196853I0J-1512D01*
G01Y196758D01*
X1765170Y196674D01*
G02X1763668Y195332I-1502J169D01*
G37*
G36*
G01X1751082D02*
X1746082D01*
G02Y198354I0J1511D01*
G01X1751083D01*
G02X1752594Y196853I0J-1512D01*
G01Y196758D01*
X1752584Y196674D01*
G02X1751082Y195332I-1502J169D01*
G37*
G36*
G01X1826682Y195330D02*
X1821682D01*
G02Y198352I0J1511D01*
G01X1826683D01*
G02X1828194Y196851I0J-1512D01*
G01Y196756D01*
X1828184Y196672D01*
G02X1826682Y195330I-1502J169D01*
G37*
G36*
G01X1814041D02*
X1809041D01*
G02Y198352I0J1511D01*
G01X1814042D01*
G02X1815552Y196851I-1J-1511D01*
G01Y196756D01*
X1815543Y196672D01*
G02X1814041Y195330I-1502J169D01*
G37*
G36*
G01X1801441D02*
X1796441D01*
G02Y198352I0J1511D01*
G01X1801442D01*
G02X1802952Y196851I-1J-1511D01*
G01Y196756D01*
X1802943Y196672D01*
G02X1801441Y195330I-1502J169D01*
G37*
G36*
G01X1788841D02*
X1783841D01*
G02Y198352I0J1511D01*
G01X1788842D01*
G02X1790352Y196851I-1J-1511D01*
G01Y196756D01*
X1790343Y196672D01*
G02X1788841Y195330I-1502J169D01*
G37*
G36*
G01X1776241D02*
X1771241D01*
G02Y198352I0J1511D01*
G01X1776242D01*
G02X1777752Y196851I-1J-1511D01*
G01Y196756D01*
X1777743Y196672D01*
G02X1776241Y195330I-1502J169D01*
G37*
G36*
G01X720641Y196447D02*
G03X721181Y196442I273J293D01*
G02X721162Y194373I936J-1043D01*
G03X720622Y194378I-273J-293D01*
G02X720641Y196447I-936J1043D01*
G37*
G36*
G01X1638880Y196604D02*
G03Y196050I288J-277D01*
G02X1636860I-1010J-973D01*
G03Y196604I-288J277D01*
G02X1638880I1010J973D01*
G37*
G36*
G01X44856Y266869D02*
X44734Y266817D01*
Y197413D01*
X39300Y191980D01*
X11160D01*
X7096Y196043D01*
Y230657D01*
X2126Y235627D01*
Y235638D01*
X2100Y235664D01*
Y264836D01*
X8800Y271536D01*
Y338936D01*
X14164Y344300D01*
X40829D01*
X44734Y340395D01*
Y269503D01*
X44856Y269451D01*
G02Y266869I-546J-1291D01*
G37*
G36*
G01X1708794Y193293D02*
G02X1712894Y191735I3218J2294D01*
G02X1708794Y193293I-882J3852D01*
G37*
G36*
G01X1209145Y193611D02*
G03X1209161Y194233I-243J317D01*
G02X1210925Y194189I909J1067D01*
G03X1210909Y193567I243J-317D01*
G02X1209145Y193611I-909J-1067D01*
G37*
G36*
G01X1621217Y184110D02*
G03X1620607Y184084I-294J-271D01*
G02X1620531Y185894I-1107J860D01*
G03X1621141Y185920I294J271D01*
G02X1621217Y184110I1107J-860D01*
G37*
G36*
G01X1609625Y183827D02*
G03X1609071Y183803I-265J-300D01*
G02X1608985Y185821I-1015J968D01*
G03X1609539Y185845I265J300D01*
G02X1611497Y185914I1014J-968D01*
G03X1612052Y185930I269J296D01*
G02X1614042Y185943I1001J-981D01*
G03X1614597Y185934I282J283D01*
G02X1614564Y183914I956J-1026D01*
G03X1614009Y183923I-282J-283D01*
G02X1612110Y183912I-955J1026D01*
G03X1611555Y183896I-269J-296D01*
G02X1609625Y183827I-1001J981D01*
G37*
G36*
G01X1682294Y182678D02*
G03X1681795Y182531I-164J-365D01*
G02X1679261Y184475I-1345J870D01*
G03X1679252Y184752I-148J134D01*
G02X1681967Y186024I1118J1148D01*
G03X1682483Y185672I399J31D01*
G02X1682294Y182678I467J-1532D01*
G37*
G36*
G01X1656005Y183496D02*
G03X1656044Y182887I277J-288D01*
G02X1654235Y182770I-835J-1126D01*
G03X1654196Y183379I-277J288D01*
G02X1656005Y183496I835J1126D01*
G37*
G36*
G01X1493491Y178427D02*
G03X1493498Y177872I291J-274D01*
G02X1491478Y177847I-998J-985D01*
G03X1491471Y178402I-291J274D01*
G02X1493491Y178427I998J985D01*
G37*
G36*
G01X1615361Y178138D02*
G03X1615868Y177853I388J97D01*
G02X1614925Y176177I418J-1338D01*
G03X1614418Y176462I-388J-97D01*
G02X1615361Y178138I-418J1338D01*
G37*
G36*
G01X1820382Y175014D02*
X1815382D01*
G02Y178036I0J1511D01*
G01X1820383D01*
G02X1821894Y176535I0J-1512D01*
G01Y176440D01*
X1821884Y176356D01*
G02X1820382Y175014I-1502J169D01*
G37*
G36*
G01X1807784D02*
X1802784D01*
G02Y178036I0J1511D01*
G01X1807785D01*
G02X1809296Y176535I0J-1512D01*
G01Y176440D01*
X1809286Y176356D01*
G02X1807784Y175014I-1502J169D01*
G37*
G36*
G01X1795185D02*
X1790185D01*
G02Y178036I0J1511D01*
G01X1795185D01*
G02X1796696Y176535I0J-1511D01*
G01Y176440D01*
X1796687Y176356D01*
G02X1795185Y175014I-1502J169D01*
G37*
G36*
G01X1782587D02*
X1777587D01*
G02Y178036I0J1511D01*
G01X1782588D01*
G02X1784098Y176535I-1J-1511D01*
G01Y176440D01*
X1784089Y176356D01*
G02X1782587Y175014I-1502J169D01*
G37*
G36*
G01X1764988Y178036D02*
X1769989D01*
G02X1771500Y176535I0J-1512D01*
G01Y176440D01*
X1771490Y176356D01*
G02X1769988Y175014I-1502J169D01*
G01X1764987D01*
G02X1764988Y178036I1J1511D01*
G37*
G36*
G01X1739792D02*
X1744793D01*
G02X1746304Y176535I0J-1512D01*
G01Y176440D01*
X1746294Y176356D01*
G02X1744792Y175014I-1502J169D01*
G01X1739792D01*
G02Y178036I1J1511D01*
G37*
G36*
G01X1732193Y175014D02*
X1727193D01*
G02Y178036I1J1511D01*
G01X1732193D01*
G02X1733704Y176535I0J-1511D01*
G01Y176440D01*
X1733695Y176356D01*
G02X1732193Y175014I-1502J169D01*
G37*
G36*
G01X1254266Y174954D02*
G03X1253734I-266J-298D01*
G02Y177046I-934J1046D01*
G03X1254266I266J298D01*
G02Y174954I934J-1046D01*
G37*
G36*
G01X1856427Y174890D02*
G03X1855873I-277J-288D01*
G02Y176910I-973J1010D01*
G03X1856427I277J288D01*
G02Y174890I973J-1010D01*
G37*
G36*
G01X1876467Y175734D02*
G03X1876859Y175321I400J-13D01*
G02X1875431Y173967I-27J-1402D01*
G03X1875039Y174380I-400J13D01*
G02X1876467Y175734I27J1402D01*
G37*
G36*
G01X1472924Y172703D02*
G03X1472369Y172698I-275J-290D01*
G02X1472352Y174718I-981J1002D01*
G03X1472907Y174723I275J290D01*
G02X1472924Y172703I981J-1002D01*
G37*
G36*
G01X1245937Y172140D02*
G03X1245383I-277J-288D01*
G02X1243022Y173350I-973J1010D01*
G03X1242665Y173805I-396J57D01*
G02X1244188Y175000I135J1395D01*
G03X1244545Y174545I396J-57D01*
G02X1245383Y174160I-134J-1396D01*
G03X1245937I277J288D01*
G02Y172140I973J-1010D01*
G37*
G36*
G01X1614926Y174330D02*
G03X1615426Y174119I364J166D01*
G02X1614624Y172220I474J-1319D01*
G03X1614124Y172431I-364J-166D01*
G02X1613209Y172419I-475J1319D01*
G03X1612732Y172230I-126J-380D01*
G02X1610389Y172044I-1232J670D01*
G03X1609884Y172153I-317J-244D01*
G02X1610333Y174245I-662J1236D01*
G03X1610838Y174136I317J244D01*
G02X1611941Y174231I662J-1236D01*
G03X1612418Y174420I126J380D01*
G02X1614926Y174330I1232J-670D01*
G37*
G36*
G01X1596631Y171213D02*
G03X1596053I-289J-277D01*
G02Y173155I-1011J971D01*
G03X1596631I289J277D01*
G02Y171213I1011J-971D01*
G37*
G36*
G01X1887371Y171589D02*
G03Y171011I277J-289D01*
G02X1885429I-971J-1011D01*
G03Y171589I-277J289D01*
G02X1887371I971J1011D01*
G37*
G36*
G01X1701968Y162401D02*
G03X1702523Y162390I283J283D01*
G02X1702478Y160081I1087J-1176D01*
G03X1701923Y160092I-283J-283D01*
G02X1701968Y162401I-1087J1176D01*
G37*
G36*
G01X1840909Y158413D02*
G03X1840924Y157858I295J-270D01*
G02X1838905Y157803I-983J-1000D01*
G03X1838890Y158358I-295J270D01*
G02X1840909Y158413I983J1000D01*
G37*
G36*
G01X1531912Y157489D02*
G03X1532143Y156930I358J-179D01*
G02X1530362Y155182I-443J-1330D01*
G03X1529807Y155424I-382J-119D01*
G02X1531912Y157489I-1963J4107D01*
G37*
G36*
G01X20473Y158250D02*
G03X21740Y158653I-2J2199D01*
G02X21756Y154015I1488J-2314D01*
G03X20502Y154428I-1283J-1786D01*
G01X20471D01*
G03X19204Y154025I2J-2199D01*
G02X19188Y158663I-1488J2314D01*
G03X20442Y158250I1283J1786D01*
G01X20473D01*
G37*
G36*
G01X3938D02*
G03X5205Y158653I-2J2199D01*
G02X5221Y154015I1488J-2314D01*
G03X3967Y154428I-1283J-1786D01*
G01X3936D01*
G03X2669Y154025I2J-2199D01*
G02X2653Y158663I-1488J2314D01*
G03X3907Y158250I1283J1786D01*
G01X3938D01*
G37*
G36*
G01X-12598D02*
G03X-11331Y158653I-2J2199D01*
G02X-11315Y154015I1488J-2314D01*
G03X-12569Y154428I-1283J-1786D01*
G01X-12599D01*
G03X-13866Y154025I2J-2199D01*
G02X-13882Y158663I-1488J2314D01*
G03X-12628Y158250I1283J1786D01*
G01X-12598D01*
G37*
G36*
G01X51309Y152844D02*
X47309D01*
G02Y155868I0J1512D01*
G01X51310D01*
G02X52820Y154366I-1J-1512D01*
G01Y154271D01*
X52811Y154187D01*
G02X51309Y152844I-1502J168D01*
G37*
G36*
G01X1788818Y155649D02*
G03X1789375Y155428I376J136D01*
G02X1788550Y153595I725J-1428D01*
G03X1788016Y153866I-387J-101D01*
G02X1788818Y155649I-516J1304D01*
G37*
G36*
G01X1700076Y154255D02*
G03X1700357Y154249I144J140D01*
G02X1700306Y151967I1098J-1166D01*
G03X1700025Y151973I-144J-140D01*
G02X1700076Y154255I-1098J1166D01*
G37*
G36*
G01X1876493Y153833D02*
G03X1877086Y153815I305J259D01*
G02X1877028Y151935I1010J-972D01*
G03X1876435Y151953I-305J-259D01*
G02X1876493Y153833I-1010J972D01*
G37*
G36*
G01X1913160Y153727D02*
G03X1913765Y153634I342J208D01*
G02X1913491Y151853I925J-1054D01*
G03X1912886Y151946I-342J-208D01*
G02X1913160Y153727I-925J1054D01*
G37*
G36*
G01X1514888Y153600D02*
G03X1515300Y153144I396J-57D01*
G02X1513970Y151943I58J-1401D01*
G03X1513558Y152399I-396J57D01*
G02X1514888Y153600I-58J1401D01*
G37*
G36*
G01X1885299Y154911D02*
G03X1885233Y155526I-285J280D01*
G02X1887000Y155717I767J1174D01*
G03X1887066Y155102I285J-280D01*
G02X1887203Y152857I-767J-1173D01*
G03X1887148Y152303I258J-305D01*
G02X1885146Y152502I-1098J-872D01*
G03X1885201Y153056I-258J305D01*
G02X1885299Y154911I1098J872D01*
G37*
G36*
G01X68098Y149962D02*
X63098D01*
G02Y152984I0J1511D01*
G01X68099D01*
G02X69610Y151483I0J-1512D01*
G01Y151388D01*
X69600Y151304D01*
G02X68098Y149962I-1502J169D01*
G37*
G36*
G01X1265136Y151576D02*
G03X1265691Y151567I282J284D01*
G02X1265656Y149548I955J-1026D01*
G03X1265101Y149557I-282J-284D01*
G02X1263135Y149613I-955J1027D01*
G03X1262557I-289J-277D01*
G02Y151555I-1011J971D01*
G03X1263135I289J277D01*
G02X1265136Y151576I1011J-971D01*
G37*
G36*
G01X1574971Y151089D02*
G03Y150511I277J-289D01*
G02X1573029I-971J-1011D01*
G03Y151089I-277J289D01*
G02X1574971I971J1011D01*
G37*
G36*
G01X1945607Y150725D02*
G03X1945609Y150166I287J-278D01*
G02X1943602Y150159I-1000J-982D01*
G03X1943600Y150718I-287J278D01*
G02X1945607Y150725I1000J982D01*
G37*
G36*
G01X1295155Y148431D02*
G03X1294732Y148064I-24J-400D01*
G02X1291935Y148249I-1397J113D01*
G03X1291580Y148668I-400J21D01*
G02X1291742Y151463I156J1393D01*
G03X1292143Y151839I2J400D01*
G02X1292145Y151862I1398J-110D01*
G03X1291752Y152292I-399J30D01*
G02X1293170Y153588I20J1402D01*
G03X1293563Y153158I399J-30D01*
G02X1293594Y153157I-30J-1402D01*
G03X1293797Y153396I7J200D01*
G02X1295303Y152274I1375J274D01*
G03X1294942Y151849I38J-398D01*
G02Y151657I-1399J-96D01*
G03X1295318Y151230I399J-28D01*
G02X1295155Y148431I-78J-1400D01*
G37*
G36*
G01X1496967Y149755D02*
G03X1497034Y149203I319J-241D01*
G02X1495031Y148960I-884J-1088D01*
G03X1494964Y149512I-319J241D01*
G02X1496967Y149755I884J1088D01*
G37*
G36*
G01X1964194Y149150D02*
G03X1964545Y148710I398J-43D01*
G02X1962988Y147468I-163J-1392D01*
G03X1962637Y147908I-398J43D01*
G02X1964194Y149150I163J1392D01*
G37*
G36*
G01X25591Y150376D02*
G03X26858Y150779I-2J2199D01*
G02X26874Y146141I1488J-2314D01*
G03X25620Y146554I-1283J-1786D01*
G01X25590D01*
G03X24323Y146151I2J-2199D01*
G02X24307Y150789I-1488J2314D01*
G03X25561Y150376I1283J1786D01*
G01X25591D01*
G37*
G36*
G01X9056D02*
G03X10323Y150779I-2J2199D01*
G02X10339Y146141I1488J-2314D01*
G03X9085Y146554I-1283J-1786D01*
G01X9054D01*
G03X7787Y146151I2J-2199D01*
G02X7771Y150789I-1488J2314D01*
G03X9025Y150376I1283J1786D01*
G01X9056D01*
G37*
G36*
G01X-7480D02*
G03X-6213Y150779I-2J2199D01*
G02X-6197Y146141I1488J-2314D01*
G03X-7451Y146554I-1283J-1786D01*
G01X-7481D01*
G03X-8748Y146151I2J-2199D01*
G02X-8764Y150789I-1488J2314D01*
G03X-7510Y150376I1283J1786D01*
G01X-7480D01*
G37*
G36*
G01X1278933Y147438D02*
G03X1278927Y146832I258J-306D01*
G02X1277097Y146852I-927J-1052D01*
G03X1277103Y147458I-258J306D01*
G02X1278933Y147438I927J1052D01*
G37*
G36*
G01X1490661Y145218D02*
G03X1490195Y144863I-68J-394D01*
G02X1489039Y146382I-1395J138D01*
G03X1489505Y146737I68J394D01*
G02X1490661Y145218I1395J-138D01*
G37*
G36*
G01X1533237Y146370D02*
G03X1533446Y145819I358J-180D01*
G02X1531671Y145148I-523J-1301D01*
G03X1531462Y145699I-358J180D01*
G02X1533237Y146370I523J1301D01*
G37*
G36*
G01X1849616Y143180D02*
G03X1849627Y142581I270J-295D01*
G02X1847506Y142540I-1037J-1221D01*
G03X1847495Y143139I-270J295D01*
G02X1849616Y143180I1037J1221D01*
G37*
G36*
G01X1267743Y140626D02*
G03X1267208Y140322I-141J-375D01*
G02X1266321Y141880I-1380J246D01*
G03X1266856Y142184I141J375D01*
G02X1267743Y140626I1380J-246D01*
G37*
G36*
G01X62342Y144760D02*
Y139665D01*
X62333Y139581D01*
G02X59320Y139750I-1502J169D01*
G01Y144750D01*
G02X62342Y144760I1511J0D01*
G37*
G36*
G01X48412D02*
Y139665D01*
X48402Y139581D01*
G02X45388Y139750I-1502J169D01*
G01Y144750D01*
G02X48412Y144760I1512J0D01*
G37*
G36*
G01X3938Y142502D02*
G03X5205Y142905I-2J2199D01*
G02X5221Y138267I1488J-2314D01*
G03X3967Y138680I-1283J-1786D01*
G01X3936D01*
G03X2669Y138277I2J-2199D01*
G02X2653Y142915I-1488J2314D01*
G03X3907Y142502I1283J1786D01*
G01X3938D01*
G37*
G36*
G01X-12598D02*
G03X-11331Y142905I-2J2199D01*
G02X-11315Y138267I1488J-2314D01*
G03X-12569Y138680I-1283J-1786D01*
G01X-12599D01*
G03X-13866Y138277I2J-2199D01*
G02X-13882Y142915I-1488J2314D01*
G03X-12628Y142502I1283J1786D01*
G01X-12598D01*
G37*
G36*
G01X1452354Y140426D02*
G03X1452435Y139869I322J-238D01*
G02X1450464Y139585I-845J-1119D01*
G03X1450383Y140142I-322J238D01*
G02X1450207Y142221I845J1118D01*
G03X1450200Y142776I-292J274D01*
G02X1450259Y144802I998J985D01*
G03X1450267Y145389I-268J297D01*
G02X1452172Y145364I966J1016D01*
G03X1452164Y144777I268J-297D01*
G02X1452219Y142801I-966J-1016D01*
G03X1452226Y142246I292J-274D01*
G02X1452354Y140426I-998J-985D01*
G37*
G36*
G01X1856050Y137539D02*
G03X1855450I-300J-265D01*
G02Y139661I-1200J1061D01*
G03X1856050I300J265D01*
G02Y137539I1200J-1061D01*
G37*
G36*
G01X1846743Y136086D02*
G03X1847327Y135919I364J167D01*
G02X1846826Y134164I773J-1170D01*
G03X1846242Y134331I-364J-167D01*
G02X1846743Y136086I-773J1170D01*
G37*
G36*
G01X67198Y137760D02*
Y132665D01*
X67189Y132581D01*
G02X64176Y132750I-1502J169D01*
G01Y137750D01*
G02X67198Y137760I1511J0D01*
G37*
G36*
G01X53080D02*
Y132665D01*
X53071Y132581D01*
G02X50058Y132750I-1502J169D01*
G01Y137751D01*
G02X53080Y137760I1511J-1D01*
G37*
G36*
G01X1920235Y133456D02*
G03X1920306Y132858I297J-268D01*
G02X1918474Y132641I-792J-1157D01*
G03X1918403Y133239I-297J268D01*
G02X1920235Y133456I792J1157D01*
G37*
G36*
G01X25591Y134628D02*
G03X26858Y135031I-2J2199D01*
G02X26874Y130393I1488J-2314D01*
G03X25620Y130806I-1283J-1786D01*
G01X25590D01*
G03X24323Y130403I2J-2199D01*
G02X24307Y135041I-1488J2314D01*
G03X25561Y134628I1283J1786D01*
G01X25591D01*
G37*
G36*
G01X1855539Y132335D02*
G03X1855351Y131782I165J-364D01*
G02X1853538Y132399I-1236J-661D01*
G03X1853726Y132952I-165J364D01*
G02X1855539Y132335I1236J661D01*
G37*
G36*
G01X1580308Y130140D02*
G03X1580312Y129585I290J-275D01*
G02X1578292Y129568I-1002J-981D01*
G03X1578288Y130123I-290J275D01*
G02X1580308Y130140I1002J981D01*
G37*
G36*
G01X1469569Y130197D02*
G03X1469606Y129592I279J-287D01*
G02X1467776Y129481I-851J-1114D01*
G03X1467739Y130086I-279J287D01*
G02X1469569Y130197I851J1114D01*
G37*
G36*
G01X1920681Y127497D02*
G03Y126924I279J-287D01*
G02X1918723I-979J-1004D01*
G03Y127497I-279J286D01*
G02X1920681I979J1004D01*
G37*
G36*
G01X62342Y130760D02*
Y125665D01*
X62333Y125581D01*
G02X59320Y125750I-1502J169D01*
G01Y130750D01*
G02X62342Y130760I1511J0D01*
G37*
G36*
G01X48412D02*
Y125665D01*
X48402Y125581D01*
G02X45388Y125750I-1502J169D01*
G01Y130750D01*
G02X48412Y130760I1512J0D01*
G37*
G36*
G01X-12598Y126754D02*
G03X-11331Y127157I-2J2199D01*
G02X-11315Y122519I1488J-2314D01*
G03X-12569Y122932I-1283J-1786D01*
G01X-12599D01*
G03X-13866Y122529I2J-2199D01*
G02X-13882Y127167I-1488J2314D01*
G03X-12628Y126754I1283J1786D01*
G01X-12598D01*
G37*
G36*
G01X1270489Y121529D02*
G03X1269911I-289J-277D01*
G02Y123471I-1011J971D01*
G03X1270489I289J277D01*
G02Y121529I1011J-971D01*
G37*
G36*
G01X1543504Y120435D02*
G03X1543326Y119880I172J-361D01*
G02X1541496Y120465I-1226J-680D01*
G03X1541674Y121020I-172J361D01*
G02X1543504Y120435I1226J680D01*
G37*
G36*
G01X1760020Y118137D02*
G03X1759380I-320J-240D01*
G02Y120063I-1280J963D01*
G03X1760020I320J240D01*
G02Y118137I1280J-963D01*
G37*
G36*
G01X53080Y123760D02*
Y118665D01*
X53071Y118581D01*
G02X50058Y118750I-1502J169D01*
G01Y123751D01*
G02X53080Y123760I1511J-1D01*
G37*
G36*
G01X63894Y123731D02*
G02X66916Y123740I1511J-1D01*
G01Y118730D01*
X66917D01*
X66916Y118645D01*
X66907Y118561D01*
G02X63894Y118730I-1502J169D01*
G01Y123731D01*
G37*
G36*
G01X1474064Y119985D02*
G03X1474087Y119386I276J-289D01*
G02X1472232Y119314I-887J-1086D01*
G03X1472209Y119913I-276J289D01*
G02X1471986Y121856I887J1086D01*
G03X1471854Y122456I-316J245D01*
G02X1473610Y122843I646J1244D01*
G03X1473742Y122243I316J-245D01*
G02X1474064Y119985I-646J-1244D01*
G37*
G36*
G01X1528024Y120779D02*
Y115684D01*
X1528015Y115600D01*
G02X1525002Y115769I-1502J169D01*
G01Y120769D01*
G02X1528024Y120779I1511J0D01*
G37*
G36*
G01X25591Y118880D02*
G03X26858Y119283I-2J2199D01*
G02X26874Y114645I1488J-2314D01*
G03X25620Y115058I-1283J-1786D01*
G01X25590D01*
G03X24323Y114655I2J-2199D01*
G02X24307Y119293I-1488J2314D01*
G03X25561Y118880I1283J1786D01*
G01X25591D01*
G37*
G36*
G01X9054Y115058D02*
G03X7787Y114655I2J-2199D01*
G02X7771Y119293I-1488J2314D01*
G03X9025Y118880I1283J1786D01*
G01X9056D01*
G03X10323Y119283I-2J2199D01*
G02X10339Y114645I1488J-2314D01*
G03X9085Y115058I-1283J-1786D01*
G01X9054D01*
G37*
G36*
G01X1907363Y116972D02*
G03X1907375Y116373I271J-294D01*
G02X1905518Y116337I-908J-1068D01*
G03X1905506Y116936I-271J294D01*
G02X1907363Y116972I908J1068D01*
G37*
G36*
G01X1303475Y113289D02*
G03Y112711I277J-289D01*
G02X1301533I-971J-1011D01*
G03Y113289I-277J289D01*
G02X1301458Y115234I971J1011D01*
G03Y115766I-298J266D01*
G02X1301467Y117644I1046J934D01*
G03X1301472Y118177I-295J269D01*
G02X1303563Y118158I1054J925D01*
G03X1303558Y117625I295J-269D01*
G02X1303550Y115766I-1054J-925D01*
G03Y115234I298J-266D01*
G02X1303475Y113289I-1046J-934D01*
G37*
G36*
G01X62212Y116760D02*
Y111665D01*
X62202Y111581D01*
G02X59188Y111750I-1502J169D01*
G01Y116750D01*
G02X62212Y116760I1512J0D01*
G37*
G36*
G01X48412D02*
Y111665D01*
X48402Y111581D01*
G02X45388Y111750I-1502J169D01*
G01Y116750D01*
G02X48412Y116760I1512J0D01*
G37*
G36*
G01X1599621Y109666D02*
G03X1599111Y109654I-248J-314D01*
G02X1599059Y111811I-921J1057D01*
G03X1599569Y111823I248J314D01*
G02X1599621Y109666I921J-1057D01*
G37*
G36*
G01X1189051Y109479D02*
G03X1189057Y108922I290J-275D01*
G02X1186901Y108900I-1067J-1057D01*
G03X1186895Y109457I-290J275D01*
G02X1189051Y109479I1067J1057D01*
G37*
G36*
G01X1152240D02*
G03X1152246Y108922I290J-275D01*
G02X1150090Y108900I-1067J-1057D01*
G03X1150084Y109457I-290J275D01*
G02X1152240Y109479I1067J1057D01*
G37*
G36*
G01X934720D02*
G03X934726Y108922I290J-275D01*
G02X932570Y108900I-1067J-1057D01*
G03X932564Y109457I-290J275D01*
G02X934720Y109479I1067J1057D01*
G37*
G36*
G01X897909D02*
G03X897915Y108922I290J-275D01*
G02X895759Y108900I-1067J-1057D01*
G03X895753Y109457I-290J275D01*
G02X897909Y109479I1067J1057D01*
G37*
G36*
G01X539443D02*
G03X539449Y108922I290J-275D01*
G02X537293Y108900I-1067J-1057D01*
G03X537287Y109457I-290J275D01*
G02X539443Y109479I1067J1057D01*
G37*
G36*
G01X502632D02*
G03X502638Y108922I290J-275D01*
G02X500482Y108900I-1067J-1057D01*
G03X500476Y109457I-290J275D01*
G02X502632Y109479I1067J1057D01*
G37*
G36*
G01X285112D02*
G03X285118Y108922I290J-275D01*
G02X282962Y108900I-1067J-1057D01*
G03X282956Y109457I-290J275D01*
G02X285112Y109479I1067J1057D01*
G37*
G36*
G01X248301D02*
G03X248307Y108922I290J-275D01*
G02X246151Y108900I-1067J-1057D01*
G03X246145Y109457I-290J275D01*
G02X248301Y109479I1067J1057D01*
G37*
G36*
G01X20473Y111006D02*
G03X21740Y111409I-2J2199D01*
G02X21756Y106771I1488J-2314D01*
G03X20502Y107184I-1283J-1786D01*
G01X20471D01*
G03X19204Y106781I2J-2199D01*
G02X19188Y111419I-1488J2314D01*
G03X20442Y111006I1283J1786D01*
G01X20473D01*
G37*
G36*
G01X3936Y107184D02*
G03X2669Y106781I2J-2199D01*
G02X2653Y111419I-1488J2314D01*
G03X3907Y111006I1283J1786D01*
G01X3938D01*
G03X5205Y111409I-2J2199D01*
G02X5221Y106771I1488J-2314D01*
G03X3967Y107184I-1283J-1786D01*
G01X3936D01*
G37*
G36*
G01X-12598Y111006D02*
G03X-11331Y111409I-2J2199D01*
G02X-11315Y106771I1488J-2314D01*
G03X-12569Y107184I-1283J-1786D01*
G01X-12599D01*
G03X-13866Y106781I2J-2199D01*
G02X-13882Y111419I-1488J2314D01*
G03X-12628Y111006I1283J1786D01*
G01X-12598D01*
G37*
G36*
G01X1194172Y109223D02*
G03X1194166Y108674I288J-278D01*
G02X1191980Y108696I-1103J-1019D01*
G03X1191986Y109245I-288J278D01*
G02X1194172Y109223I1103J1019D01*
G37*
G36*
G01X1157361D02*
G03X1157355Y108674I288J-278D01*
G02X1155169Y108696I-1103J-1019D01*
G03X1155175Y109245I-288J278D01*
G02X1157361Y109223I1103J1019D01*
G37*
G36*
G01X939841D02*
G03X939835Y108674I288J-278D01*
G02X937649Y108696I-1103J-1019D01*
G03X937655Y109245I-288J278D01*
G02X939841Y109223I1103J1019D01*
G37*
G36*
G01X903030D02*
G03X903024Y108674I288J-278D01*
G02X900838Y108696I-1103J-1019D01*
G03X900844Y109245I-288J278D01*
G02X903030Y109223I1103J1019D01*
G37*
G36*
G01X544564D02*
G03X544558Y108674I288J-278D01*
G02X542372Y108696I-1103J-1019D01*
G03X542378Y109245I-288J278D01*
G02X544564Y109223I1103J1019D01*
G37*
G36*
G01X507753D02*
G03X507747Y108674I288J-278D01*
G02X505561Y108696I-1103J-1019D01*
G03X505567Y109245I-288J278D01*
G02X507753Y109223I1103J1019D01*
G37*
G36*
G01X290233D02*
G03X290227Y108674I288J-278D01*
G02X288041Y108696I-1103J-1019D01*
G03X288047Y109245I-288J278D01*
G02X290233Y109223I1103J1019D01*
G37*
G36*
G01X253422D02*
G03X253416Y108674I288J-278D01*
G02X251230Y108696I-1103J-1019D01*
G03X251236Y109245I-288J278D01*
G02X253422Y109223I1103J1019D01*
G37*
G36*
G01X1853181Y106802D02*
G03X1852743Y106393I-38J-398D01*
G02X1851477Y107753I-1402J-35D01*
G03X1851915Y108162I38J398D01*
G02X1853181Y106802I1402J35D01*
G37*
G36*
G01X66896Y109760D02*
Y104665D01*
X66886Y104581D01*
G02X63872Y104750I-1502J169D01*
G01Y109751D01*
G02X66896Y109760I1512J-1D01*
G37*
G36*
G01X52892D02*
Y104665D01*
X52883Y104581D01*
G02X49870Y104750I-1502J169D01*
G01Y109750D01*
G02X52892Y109760I1511J0D01*
G37*
G36*
G01X1512424Y108332D02*
G02X1515446Y108342I1511J0D01*
G01Y104447D01*
X1515437Y104363D01*
G02X1512424Y104532I-1502J169D01*
G01Y108332D01*
G37*
G36*
G01X1811259Y105468D02*
G03X1811814Y105445I289J276D01*
G02X1811729Y103427I929J-1050D01*
G03X1811174Y103450I-289J-276D01*
G02X1811259Y105468I-929J1050D01*
G37*
G36*
G01X1525004Y103876D02*
X1524995Y104048D01*
X1524994D01*
X1525295Y109060D01*
X1525327Y109232D01*
G02X1528314Y109136I1486J-275D01*
G01X1528335Y108960D01*
X1528378D01*
X1528498Y108816D01*
X1528246Y107442D01*
X1528032Y103868D01*
X1528031Y103867D01*
X1528027Y103788D01*
X1528015Y103789D01*
G02X1525004Y103876I-1502J168D01*
G37*
G36*
G01X1490430Y104578D02*
G03X1490268Y104024I185J-355D01*
G02X1488403Y104567I-1215J-699D01*
G03X1488565Y105121I-185J355D01*
G02X1490430Y104578I1215J699D01*
G37*
G36*
G01X1072050Y104759D02*
G03X1072052Y104163I268J-297D01*
G02X1070181Y104157I-932J-1047D01*
G03X1070179Y104753I-268J297D01*
G02X1072050Y104759I932J1047D01*
G37*
G36*
G01X1065363Y104756D02*
G03Y104160I267J-298D01*
G02X1063492I-935J-1044D01*
G03Y104756I-267J298D01*
G02X1065363I935J1044D01*
G37*
G36*
G01X1058691Y104725D02*
G03Y104141I273J-292D01*
G02X1056777I-957J-1025D01*
G03Y104725I-273J292D01*
G02X1058691I957J1025D01*
G37*
G36*
G01X1051919Y104756D02*
G03Y104160I267J-298D01*
G02X1050047I-936J-1044D01*
G03Y104756I-267J298D01*
G02X1051919I936J1044D01*
G37*
G36*
G01X422442Y104759D02*
G03X422444Y104163I268J-297D01*
G02X420573Y104157I-932J-1047D01*
G03X420571Y104753I-268J297D01*
G02X422442Y104759I932J1047D01*
G37*
G36*
G01X415755Y104756D02*
G03Y104160I267J-298D01*
G02X413884I-936J-1044D01*
G03Y104756I-267J298D01*
G02X415755I935J1044D01*
G37*
G36*
G01X409083Y104725D02*
G03Y104141I273J-292D01*
G02X407169I-957J-1025D01*
G03Y104725I-273J292D01*
G02X409083I957J1025D01*
G37*
G36*
G01X402311Y104756D02*
G03Y104160I267J-298D01*
G02X400439I-936J-1044D01*
G03Y104756I-267J298D01*
G02X402311I936J1044D01*
G37*
G36*
G01X1078233Y104750D02*
G03Y104150I265J-300D01*
G02X1076375I-929J-1050D01*
G03Y104750I-265J300D01*
G02X1078233I929J1050D01*
G37*
G36*
G01X428625D02*
G03Y104150I265J-300D01*
G02X426767I-929J-1050D01*
G03Y104750I-265J300D01*
G02X428625I929J1050D01*
G37*
G36*
G01X977337Y104779D02*
G03X977448Y104207I324J-234D01*
G02X975563Y103842I-748J-1186D01*
G03X975452Y104414I-324J234D01*
G02X977337Y104779I748J1186D01*
G37*
G36*
G01X327729D02*
G03X327840Y104207I324J-234D01*
G02X325955Y103842I-748J-1186D01*
G03X325844Y104414I-324J234D01*
G02X327729Y104779I748J1186D01*
G37*
G36*
G01X700017Y103801D02*
G03X699840Y103255I176J-359D01*
G02X697587Y101631I-1240J-655D01*
G03X697032Y101653I-289J-277D01*
G02X694970Y101870I-932J1047D01*
G03X694415Y101959I-323J-236D01*
G02X692290Y103599I-815J1141D01*
G03X691892Y104140I-374J142D01*
G02X692897Y106425I-82J1400D01*
G03X693485Y106390I310J253D01*
G02X695554Y106258I974J-1008D01*
G03X696081Y106170I312J249D01*
G02X697803Y105998I751J-1184D01*
G03X698373Y106014I277J288D01*
G02X700454Y105984I1027J-954D01*
G03X701021Y105949I301J264D01*
G02X703095Y105716I932J-1047D01*
G03X703642Y105615I326J232D01*
G02X703277Y103634I777J-1167D01*
G03X702730Y103735I-326J-232D01*
G02X700899Y103978I-777J1167D01*
G03X700332Y104013I-301J-264D01*
G02X700017Y103801I-933J1046D01*
G37*
G36*
G01X743520Y101574D02*
G03X742965Y101396I-194J-350D01*
G02X742380Y103226I-1265J604D01*
G03X742935Y103404I194J350D01*
G02X744736Y104095I1265J-604D01*
G03X745269Y104340I153J370D01*
G02X746064Y102605I1331J-440D01*
G03X745531Y102360I-153J-370D01*
G02X743520Y101574I-1331J440D01*
G37*
G36*
G01X25591Y103132D02*
G03X26858Y103535I-2J2199D01*
G02X26874Y98897I1488J-2314D01*
G03X25620Y99310I-1283J-1786D01*
G01X25590D01*
G03X24323Y98907I2J-2199D01*
G02X24307Y103545I-1488J2314D01*
G03X25561Y103132I1283J1786D01*
G01X25591D01*
G37*
G36*
G01X9054Y99310D02*
G03X7787Y98907I2J-2199D01*
G02X7771Y103545I-1488J2314D01*
G03X9025Y103132I1283J1786D01*
G01X9056D01*
G03X10323Y103535I-2J2199D01*
G02X10339Y98897I1488J-2314D01*
G03X9085Y99310I-1283J-1786D01*
G01X9054D01*
G37*
G36*
G01X-7480Y103132D02*
G03X-6213Y103535I-2J2199D01*
G02X-6197Y98897I1488J-2314D01*
G03X-7451Y99310I-1283J-1786D01*
G01X-7481D01*
G03X-8748Y98907I2J-2199D01*
G02X-8764Y103545I-1488J2314D01*
G03X-7510Y103132I1283J1786D01*
G01X-7480D01*
G37*
G36*
G01X1500216Y99529D02*
G02X1497194Y99501I-1511J-7D01*
G01X1497149Y102725D01*
G02X1500161Y102924I1511J21D01*
G01X1500169Y102860D01*
X1500171Y102795D01*
G02X1500172Y102767I-1510J-68D01*
G01Y102746D01*
X1500216Y99544D01*
G02Y99529I-1511J-8D01*
G37*
G36*
G01X757771Y100989D02*
G03Y100411I277J-289D01*
G02X755829I-971J-1011D01*
G03Y100989I-277J289D01*
G02X757771I971J1011D01*
G37*
G36*
G01X1375685Y100772D02*
G03Y100460I125J-156D01*
G02X1373798Y100339I-877J-1094D01*
G03Y100893I-288J277D01*
G02Y102839I1010J973D01*
G03Y103393I-288J277D01*
G02Y105339I1010J973D01*
G03Y105893I-288J277D01*
G02X1375781Y107876I1010J973D01*
G03X1376335I277J288D01*
G02X1378318Y105893I973J-1010D01*
G03Y105339I288J-277D01*
G02Y103393I-1010J-973D01*
G03Y102839I288J-277D01*
G02X1376335Y100856I-1010J-973D01*
G03X1375781I-277J-288D01*
G02X1375685Y100772I-970J1012D01*
G37*
G36*
G01X1687931Y99885D02*
G03X1688484Y99838I301J264D01*
G02X1688313Y97827I884J-1088D01*
G03X1687760Y97874I-301J-264D01*
G02X1687931Y99885I-884J1088D01*
G37*
G36*
G01X1659414Y100014D02*
G03X1659913Y99815I359J176D01*
G02X1659140Y97886I487J-1315D01*
G03X1658641Y98085I-359J-176D01*
G02X1659414Y100014I-487J1315D01*
G37*
G36*
G01X62312Y102760D02*
Y97665D01*
X62303Y97581D01*
G02X59290Y97750I-1502J169D01*
G01Y102751D01*
G02X62312Y102760I1511J-1D01*
G37*
G36*
G01X48412D02*
Y97665D01*
X48402Y97581D01*
G02X45388Y97750I-1502J169D01*
G01Y102751D01*
G02X48412Y102760I1512J-1D01*
G37*
G36*
G01X1542883Y98810D02*
G03X1542905Y98277I309J-254D01*
G02X1540817Y98190I-1005J-977D01*
G03X1540795Y98723I-309J254D01*
G02X1542883Y98810I1005J977D01*
G37*
G36*
G01X763520Y94433D02*
G03X762998Y94166I-137J-376D01*
G02X762130Y95867I-1348J384D01*
G03X762652Y96134I137J376D01*
G02X763520Y94433I1348J-384D01*
G37*
G36*
G01X1919170Y95082D02*
G03X1919149Y94521I274J-291D01*
G02X1917153Y94597I-1035J-945D01*
G03X1917174Y95158I-274J291D01*
G02X1917196Y97071I1036J945D01*
G03X1917137Y97674I-289J276D01*
G02X1919039Y97816I865J1228D01*
G03X1919070Y97210I276J-290D01*
G02X1919170Y95082I-860J-1107D01*
G37*
G36*
G01X1525232Y98265D02*
G02X1528256Y98275I1512J0D01*
G01Y93180D01*
X1528246Y93096D01*
G02X1525232Y93265I-1502J169D01*
G01Y98265D01*
G37*
G36*
G01X869174Y93782D02*
Y101284D01*
X871376D01*
Y93782D01*
G02X869174I-1101J-1021D01*
G37*
G36*
G01X219566D02*
Y101284D01*
X221768D01*
Y93782D01*
G02X219566I-1101J-1021D01*
G37*
G36*
G01X1240630Y93778D02*
Y101284D01*
X1242834D01*
Y93778D01*
G02X1240630I-1102J-1021D01*
G37*
G36*
G01X1233938D02*
Y101284D01*
X1236140D01*
Y93778D01*
G02X1233938I-1101J-1021D01*
G37*
G36*
G01X1217204Y93777D02*
Y101284D01*
X1219408D01*
Y93779D01*
G02X1217204Y93777I-1101J-1022D01*
G37*
G36*
G01X1210512D02*
Y101284D01*
X1212714D01*
Y93779D01*
G02X1210512Y93777I-1100J-1022D01*
G37*
G36*
G01X1203820Y93778D02*
Y101284D01*
X1206022D01*
Y93778D01*
G02X1203820I-1101J-1021D01*
G37*
G36*
G01X1197126D02*
Y101284D01*
X1199330D01*
Y93778D01*
G02X1197126I-1102J-1021D01*
G37*
G36*
G01X1180394Y93777D02*
Y101284D01*
X1182596D01*
Y93779D01*
G02X1180394Y93777I-1100J-1022D01*
G37*
G36*
G01X1173700D02*
Y101284D01*
X1175904D01*
Y93779D01*
G02X1173700Y93777I-1101J-1022D01*
G37*
G36*
G01X1167008Y93778D02*
Y101284D01*
X1169212D01*
Y93778D01*
G02X1167008I-1102J-1021D01*
G37*
G36*
G01X1160316D02*
Y101284D01*
X1162518D01*
Y93778D01*
G02X1160316I-1101J-1021D01*
G37*
G36*
G01X1143582Y93777D02*
Y101284D01*
X1145786D01*
Y93779D01*
G02X1143582Y93777I-1101J-1022D01*
G37*
G36*
G01X1136890D02*
Y101284D01*
X1139092D01*
Y93779D01*
G02X1136890Y93777I-1100J-1022D01*
G37*
G36*
G01X1130198Y93778D02*
Y101284D01*
X1132400D01*
Y93778D01*
G02X1130198I-1101J-1021D01*
G37*
G36*
G01X1123504D02*
Y101284D01*
X1125708D01*
Y93778D01*
G02X1123504I-1102J-1021D01*
G37*
G36*
G01X1106772Y93777D02*
Y101284D01*
X1108974D01*
Y93779D01*
G02X1106772Y93777I-1100J-1022D01*
G37*
G36*
G01X1100078D02*
Y101284D01*
X1102282D01*
Y93779D01*
G02X1100078Y93777I-1101J-1022D01*
G37*
G36*
G01X949490Y93779D02*
Y101284D01*
X951692D01*
Y93777D01*
G02X949490Y93779I-1102J-1020D01*
G37*
G36*
G01X942796Y93778D02*
Y101284D01*
X944998D01*
Y93778D01*
G02X942796I-1101J-1021D01*
G37*
G36*
G01X926064D02*
Y101284D01*
X928266D01*
Y93778D01*
G02X926064I-1101J-1021D01*
G37*
G36*
G01X919370D02*
Y101284D01*
X921574D01*
Y93778D01*
G02X919370I-1102J-1021D01*
G37*
G36*
G01X912678D02*
Y101284D01*
X914880D01*
Y93778D01*
G02X912678I-1101J-1021D01*
G37*
G36*
G01X905984D02*
Y101284D01*
X908188D01*
Y93778D01*
G02X905984I-1102J-1021D01*
G37*
G36*
G01X889252D02*
Y101284D01*
X891456D01*
Y93778D01*
G02X889252I-1102J-1021D01*
G37*
G36*
G01X882560D02*
Y101284D01*
X884762D01*
Y93778D01*
G02X882560I-1101J-1021D01*
G37*
G36*
G01X875866D02*
Y101284D01*
X878070D01*
Y93778D01*
G02X875866I-1102J-1021D01*
G37*
G36*
G01X852442D02*
Y101284D01*
X854644D01*
Y93778D01*
G02X852442I-1101J-1021D01*
G37*
G36*
G01X845748D02*
Y101284D01*
X847952D01*
Y93778D01*
G02X845748I-1102J-1021D01*
G37*
G36*
G01X839056D02*
Y101284D01*
X841258D01*
Y93778D01*
G02X839056I-1101J-1021D01*
G37*
G36*
G01X832362D02*
Y101284D01*
X834566D01*
Y93778D01*
G02X832362I-1102J-1021D01*
G37*
G36*
G01X815630D02*
Y101284D01*
X817834D01*
Y93778D01*
G02X815630I-1102J-1021D01*
G37*
G36*
G01X808938D02*
Y101284D01*
X811140D01*
Y93778D01*
G02X808938I-1101J-1021D01*
G37*
G36*
G01X802244D02*
Y101284D01*
X804448D01*
Y93778D01*
G02X802244I-1102J-1021D01*
G37*
G36*
G01X795552D02*
Y101284D01*
X797754D01*
Y93778D01*
G02X795552I-1101J-1021D01*
G37*
G36*
G01X778820D02*
Y101284D01*
X781022D01*
Y93778D01*
G02X778820I-1101J-1021D01*
G37*
G36*
G01X772126D02*
Y101284D01*
X774330D01*
Y93778D01*
G02X772126I-1102J-1021D01*
G37*
G36*
G01X591022D02*
Y101284D01*
X593226D01*
Y93778D01*
G02X591022I-1102J-1021D01*
G37*
G36*
G01X584330D02*
Y101284D01*
X586532D01*
Y93778D01*
G02X584330I-1101J-1021D01*
G37*
G36*
G01X567596Y93777D02*
Y101284D01*
X569800D01*
Y93779D01*
G02X567596Y93777I-1101J-1022D01*
G37*
G36*
G01X560904D02*
Y101284D01*
X563106D01*
Y93779D01*
G02X560904Y93777I-1100J-1022D01*
G37*
G36*
G01X554212Y93778D02*
Y101284D01*
X556414D01*
Y93778D01*
G02X554212I-1101J-1021D01*
G37*
G36*
G01X547518D02*
Y101284D01*
X549722D01*
Y93778D01*
G02X547518I-1102J-1021D01*
G37*
G36*
G01X530786Y93777D02*
Y101284D01*
X532988D01*
Y93779D01*
G02X530786Y93777I-1100J-1022D01*
G37*
G36*
G01X524092D02*
Y101284D01*
X526296D01*
Y93779D01*
G02X524092Y93777I-1101J-1022D01*
G37*
G36*
G01X517400Y93778D02*
Y101284D01*
X519604D01*
Y93778D01*
G02X517400I-1102J-1021D01*
G37*
G36*
G01X510708D02*
Y101284D01*
X512910D01*
Y93778D01*
G02X510708I-1101J-1021D01*
G37*
G36*
G01X493974Y93777D02*
Y101284D01*
X496178D01*
Y93779D01*
G02X493974Y93777I-1101J-1022D01*
G37*
G36*
G01X487282D02*
Y101284D01*
X489484D01*
Y93779D01*
G02X487282Y93777I-1100J-1022D01*
G37*
G36*
G01X480590Y93778D02*
Y101284D01*
X482792D01*
Y93778D01*
G02X480590I-1101J-1021D01*
G37*
G36*
G01X473896D02*
Y101284D01*
X476100D01*
Y93778D01*
G02X473896I-1102J-1021D01*
G37*
G36*
G01X457164Y93777D02*
Y101284D01*
X459366D01*
Y93779D01*
G02X457164Y93777I-1100J-1022D01*
G37*
G36*
G01X450470D02*
Y101284D01*
X452674D01*
Y93779D01*
G02X450470Y93777I-1101J-1022D01*
G37*
G36*
G01X299882Y93779D02*
Y101284D01*
X302084D01*
Y93777D01*
G02X299882Y93779I-1102J-1020D01*
G37*
G36*
G01X293188Y93778D02*
Y101284D01*
X295390D01*
Y93778D01*
G02X293188I-1101J-1021D01*
G37*
G36*
G01X276456D02*
Y101284D01*
X278658D01*
Y93778D01*
G02X276456I-1101J-1021D01*
G37*
G36*
G01X269762D02*
Y101284D01*
X271966D01*
Y93778D01*
G02X269762I-1102J-1021D01*
G37*
G36*
G01X263070D02*
Y101284D01*
X265272D01*
Y93778D01*
G02X263070I-1101J-1021D01*
G37*
G36*
G01X256376D02*
Y101284D01*
X258580D01*
Y93778D01*
G02X256376I-1102J-1021D01*
G37*
G36*
G01X239644D02*
Y101284D01*
X241848D01*
Y93778D01*
G02X239644I-1102J-1021D01*
G37*
G36*
G01X232952D02*
Y101284D01*
X235154D01*
Y93778D01*
G02X232952I-1101J-1021D01*
G37*
G36*
G01X226258D02*
Y101284D01*
X228462D01*
Y93778D01*
G02X226258I-1102J-1021D01*
G37*
G36*
G01X202834D02*
Y101284D01*
X205036D01*
Y93778D01*
G02X202834I-1101J-1021D01*
G37*
G36*
G01X196140D02*
Y101284D01*
X198344D01*
Y93778D01*
G02X196140I-1102J-1021D01*
G37*
G36*
G01X189448D02*
Y101284D01*
X191650D01*
Y93778D01*
G02X189448I-1101J-1021D01*
G37*
G36*
G01X182754D02*
Y101284D01*
X184958D01*
Y93778D01*
G02X182754I-1102J-1021D01*
G37*
G36*
G01X166022D02*
Y101284D01*
X168226D01*
Y93778D01*
G02X166022I-1102J-1021D01*
G37*
G36*
G01X159330D02*
Y101284D01*
X161532D01*
Y93778D01*
G02X159330I-1101J-1021D01*
G37*
G36*
G01X152636D02*
Y101284D01*
X154840D01*
Y93778D01*
G02X152636I-1102J-1021D01*
G37*
G36*
G01X145944D02*
Y101284D01*
X148146D01*
Y93778D01*
G02X145944I-1101J-1021D01*
G37*
G36*
G01X129212D02*
Y101284D01*
X131414D01*
Y93778D01*
G02X129212I-1101J-1021D01*
G37*
G36*
G01X122518D02*
Y101284D01*
X124722D01*
Y93778D01*
G02X122518I-1102J-1021D01*
G37*
G36*
G01X1405579Y90903D02*
G03X1404913I-333J-222D01*
G02X1403448Y93050I-1167J777D01*
G03X1403759Y93494I-85J391D01*
G02X1406205Y94601I1390J185D01*
G03X1406829Y94628I301J263D01*
G02X1408382Y92463I1131J-828D01*
G03X1408113Y91993I121J-381D01*
G02X1405579Y90903I-1367J-313D01*
G37*
G36*
G01X35367Y93038D02*
G03X35733Y92550I390J-89D01*
G02X34283Y91462I-83J-1400D01*
G03X33917Y91950I-390J89D01*
G02X35367Y93038I83J1400D01*
G37*
G36*
G01X1908550Y92826D02*
G03X1908558Y92268I291J-275D01*
G02X1906263Y92233I-1130J-1135D01*
G03X1906255Y92791I-291J275D01*
G02X1906213Y92833I1112J1153D01*
G03X1905913Y92824I-146J-136D01*
G02X1903524Y94956I-1234J1022D01*
G03X1903537Y95497I-288J278D01*
G02X1905797Y97757I1205J1055D01*
G03X1906338Y97770I263J301D01*
G02X1908609Y95511I1110J-1155D01*
G03X1908597Y94974I290J-275D01*
G02X1908550Y92826I-1212J-1048D01*
G37*
G36*
G01X68725Y89388D02*
X63724D01*
G02X63725Y92412I1J1512D01*
G01X68725D01*
G02X70236Y90910I-1J-1512D01*
G01Y90815D01*
X70227Y90731D01*
G02X68725Y89388I-1502J168D01*
G37*
G36*
G01X52892Y95760D02*
Y90665D01*
X52883Y90581D01*
G02X49870Y90750I-1502J169D01*
G01Y95750D01*
G02X52892Y95760I1511J0D01*
G37*
G36*
G01X1676372Y91718D02*
G03X1676946Y91514I374J142D01*
G02X1676339Y89802I703J-1213D01*
G03X1675765Y90006I-374J-142D01*
G02X1676372Y91718I-703J1213D01*
G37*
G36*
G01X733655Y89330D02*
G03X734242Y89312I302J263D01*
G02X734185Y87407I999J-983D01*
G03X733598Y87425I-302J-263D01*
G02X731603Y87422I-999J983D01*
G03X731034I-284J-282D01*
G02Y89394I-996J986D01*
G03X731603I285J282D01*
G02X733655Y89330I996J-986D01*
G37*
G36*
G01X1542878Y89123D02*
G03X1542807Y88580I253J-309D01*
G02X1540780Y88844I-1137J-820D01*
G03X1540851Y89387I-253J309D01*
G02X1540978Y91180I1137J820D01*
G03Y91734I-288J277D01*
G02X1543287Y93234I1010J973D01*
G03X1543774Y93002I371J151D01*
G02X1543857Y90296I406J-1342D01*
G03X1543370Y89973I-92J-389D01*
G02X1542878Y89123I-1383J233D01*
G37*
G36*
G01X1230970Y89087D02*
G03Y88541I292J-273D01*
G02X1228778I-1096J-1027D01*
G03Y89087I-292J273D01*
G02X1230970I1096J1027D01*
G37*
G36*
G01X1194159D02*
G03Y88541I292J-273D01*
G02X1191967I-1096J-1027D01*
G03Y89087I-292J273D01*
G02X1194159I1096J1027D01*
G37*
G36*
G01X1157348D02*
G03Y88541I292J-273D01*
G02X1155156I-1096J-1027D01*
G03Y89087I-292J273D01*
G02X1157348I1096J1027D01*
G37*
G36*
G01X1120536D02*
G03Y88541I292J-273D01*
G02X1118344I-1096J-1027D01*
G03Y89087I-292J273D01*
G02X1120536I1096J1027D01*
G37*
G36*
G01X939828D02*
G03Y88541I292J-273D01*
G02X937636I-1096J-1027D01*
G03Y89087I-292J273D01*
G02X939828I1096J1027D01*
G37*
G36*
G01X903017D02*
G03Y88541I292J-273D01*
G02X900825I-1096J-1027D01*
G03Y89087I-292J273D01*
G02X903017I1096J1027D01*
G37*
G36*
G01X866206D02*
G03Y88541I292J-273D01*
G02X864014I-1096J-1027D01*
G03Y89087I-292J273D01*
G02X866206I1096J1027D01*
G37*
G36*
G01X829395D02*
G03Y88541I292J-273D01*
G02X827203I-1096J-1027D01*
G03Y89087I-292J273D01*
G02X829395I1096J1027D01*
G37*
G36*
G01X792584D02*
G03Y88541I292J-273D01*
G02X790392I-1096J-1027D01*
G03Y89087I-292J273D01*
G02X792584I1096J1027D01*
G37*
G36*
G01X581362D02*
G03Y88541I292J-273D01*
G02X579170I-1096J-1027D01*
G03Y89087I-292J273D01*
G02X581362I1096J1027D01*
G37*
G36*
G01X544551D02*
G03Y88541I292J-273D01*
G02X542359I-1096J-1027D01*
G03Y89087I-292J273D01*
G02X544551I1096J1027D01*
G37*
G36*
G01X507740D02*
G03Y88541I292J-273D01*
G02X505548I-1096J-1027D01*
G03Y89087I-292J273D01*
G02X507740I1096J1027D01*
G37*
G36*
G01X470928D02*
G03Y88541I292J-273D01*
G02X468736I-1096J-1027D01*
G03Y89087I-292J273D01*
G02X470928I1096J1027D01*
G37*
G36*
G01X290220D02*
G03Y88541I292J-273D01*
G02X288028I-1096J-1027D01*
G03Y89087I-292J273D01*
G02X290220I1096J1027D01*
G37*
G36*
G01X253409D02*
G03Y88541I292J-273D01*
G02X251217I-1096J-1027D01*
G03Y89087I-292J273D01*
G02X253409I1096J1027D01*
G37*
G36*
G01X216598D02*
G03Y88541I292J-273D01*
G02X214406I-1096J-1027D01*
G03Y89087I-292J273D01*
G02X216598I1096J1027D01*
G37*
G36*
G01X179787D02*
G03Y88541I292J-273D01*
G02X177595I-1096J-1027D01*
G03Y89087I-292J273D01*
G02X179787I1096J1027D01*
G37*
G36*
G01X142976D02*
G03Y88541I292J-273D01*
G02X140784I-1096J-1027D01*
G03Y89087I-292J273D01*
G02X142976I1096J1027D01*
G37*
G36*
G01X1225870Y88873D02*
G03Y88327I292J-273D01*
G02X1223678I-1096J-1027D01*
G03Y88873I-292J273D01*
G02X1225870I1096J1027D01*
G37*
G36*
G01X1189059D02*
G03Y88327I292J-273D01*
G02X1186867I-1096J-1027D01*
G03Y88873I-292J273D01*
G02X1189059I1096J1027D01*
G37*
G36*
G01X1152248D02*
G03Y88327I292J-273D01*
G02X1150056I-1096J-1027D01*
G03Y88873I-292J273D01*
G02X1152248I1096J1027D01*
G37*
G36*
G01X1115436D02*
G03Y88327I292J-273D01*
G02X1113244I-1096J-1027D01*
G03Y88873I-292J273D01*
G02X1115436I1096J1027D01*
G37*
G36*
G01X934728D02*
G03Y88327I292J-273D01*
G02X932536I-1096J-1027D01*
G03Y88873I-292J273D01*
G02X934728I1096J1027D01*
G37*
G36*
G01X897917D02*
G03Y88327I292J-273D01*
G02X895725I-1096J-1027D01*
G03Y88873I-292J273D01*
G02X897917I1096J1027D01*
G37*
G36*
G01X861106D02*
G03Y88327I292J-273D01*
G02X858914I-1096J-1027D01*
G03Y88873I-292J273D01*
G02X861106I1096J1027D01*
G37*
G36*
G01X824295D02*
G03Y88327I292J-273D01*
G02X822103I-1096J-1027D01*
G03Y88873I-292J273D01*
G02X824295I1096J1027D01*
G37*
G36*
G01X787484D02*
G03Y88327I292J-273D01*
G02X785292I-1096J-1027D01*
G03Y88873I-292J273D01*
G02X787484I1096J1027D01*
G37*
G36*
G01X576262D02*
G03Y88327I292J-273D01*
G02X574070I-1096J-1027D01*
G03Y88873I-292J273D01*
G02X576262I1096J1027D01*
G37*
G36*
G01X539451D02*
G03Y88327I292J-273D01*
G02X537259I-1096J-1027D01*
G03Y88873I-292J273D01*
G02X539451I1096J1027D01*
G37*
G36*
G01X502640D02*
G03Y88327I292J-273D01*
G02X500448I-1096J-1027D01*
G03Y88873I-292J273D01*
G02X502640I1096J1027D01*
G37*
G36*
G01X465828D02*
G03Y88327I292J-273D01*
G02X463636I-1096J-1027D01*
G03Y88873I-292J273D01*
G02X465828I1096J1027D01*
G37*
G36*
G01X285120D02*
G03Y88327I292J-273D01*
G02X282928I-1096J-1027D01*
G03Y88873I-292J273D01*
G02X285120I1096J1027D01*
G37*
G36*
G01X248309D02*
G03Y88327I292J-273D01*
G02X246117I-1096J-1027D01*
G03Y88873I-292J273D01*
G02X248309I1096J1027D01*
G37*
G36*
G01X211498D02*
G03Y88327I292J-273D01*
G02X209306I-1096J-1027D01*
G03Y88873I-292J273D01*
G02X211498I1096J1027D01*
G37*
G36*
G01X174687D02*
G03Y88327I292J-273D01*
G02X172495I-1096J-1027D01*
G03Y88873I-292J273D01*
G02X174687I1096J1027D01*
G37*
G36*
G01X137876D02*
G03Y88327I292J-273D01*
G02X135684I-1096J-1027D01*
G03Y88873I-292J273D01*
G02X137876I1096J1027D01*
G37*
G36*
G01X1810887Y85685D02*
G03X1810347I-270J-295D01*
G02X1808049Y87908I-1080J1183D01*
G03Y88428I-304J260D01*
G02X1808084Y90548I1218J1040D01*
G03Y91088I-295J270D01*
G02Y93248I1183J1080D01*
G03Y93788I-295J270D01*
G02X1810347Y96051I1183J1080D01*
G03X1810887I270J295D01*
G02X1813047I1080J-1183D01*
G03X1813587I270J295D01*
G02X1815850Y93788I1080J-1183D01*
G03Y93248I295J-270D01*
G02Y91088I-1183J-1080D01*
G03Y90548I295J-270D01*
G02X1815885Y88428I-1183J-1080D01*
G03Y87908I304J-260D01*
G02X1813587Y85685I-1218J-1040D01*
G03X1813047I-270J-295D01*
G02X1810887I-1080J1183D01*
G37*
G36*
G01X1501386Y90491D02*
Y86596D01*
X1501377Y86512D01*
G02X1498364Y86681I-1502J169D01*
G01Y90481D01*
G02X1501386Y90491I1511J0D01*
G37*
G36*
G01X1598489Y83529D02*
G03X1597911I-289J-277D01*
G02Y85471I-1011J971D01*
G03X1598489I289J277D01*
G02X1600473Y85510I1011J-971D01*
G03X1601027I277J288D01*
G02Y83490I973J-1010D01*
G03X1600473I-277J-288D01*
G02X1598489Y83529I-973J1010D01*
G37*
G36*
G01X1953132Y85697D02*
G03X1953664Y85419I388J95D01*
G02X1952807Y83777I505J-1308D01*
G03X1952275Y84055I-388J-95D01*
G02X1950797Y84353I-505J1308D01*
G03X1950243I-277J-288D01*
G02X1948259Y84392I-973J1010D01*
G03X1947681I-289J-277D01*
G02X1945660Y86336I-1010J972D01*
G03Y86890I-288J277D01*
G02X1945623Y88795I1010J972D01*
G03X1945601Y89350I-299J266D01*
G02X1945560Y91336I969J1013D01*
G03Y91890I-288J277D01*
G02X1947581Y93834I1011J972D01*
G03X1948159I289J277D01*
G02X1948419Y94047I1012J-970D01*
G03X1948517Y94635I-214J338D01*
G02X1950583Y96523I1092J879D01*
G03X1951137I277J288D01*
G02X1953293Y96265I973J-1010D01*
G03X1953904Y96187I338J214D01*
G02X1955834Y96173I958J-1024D01*
G03X1956388I277J288D01*
G02X1958096Y93969I972J-1010D01*
G03X1957992Y93381I210J-340D01*
G02X1955918Y91503I-1100J-869D01*
G03X1955364I-277J-288D01*
G02X1953216Y91747I-973J1010D01*
G03X1952613Y91825I-335J-218D01*
G02X1952547Y91769I-940J1041D01*
G03Y91457I125J-156D01*
G02X1952717Y89431I-877J-1094D01*
G03X1952739Y88876I299J-266D01*
G02X1952780Y86890I-969J-1013D01*
G03Y86336I288J-277D01*
G02X1953132Y85697I-1010J-973D01*
G37*
G36*
G01X1025955Y85404D02*
G03Y84850I288J-277D01*
G02X1023935I-1010J-973D01*
G03Y85404I-288J277D01*
G02X1025955I1010J973D01*
G37*
G36*
G01X376347D02*
G03Y84850I288J-277D01*
G02X374327I-1010J-973D01*
G03Y85404I-288J277D01*
G02X376347I1010J973D01*
G37*
G36*
G01X753559Y85177D02*
G03X753577Y84578I274J-292D01*
G02X751721Y84523I-897J-1078D01*
G03X751703Y85122I-274J292D01*
G02X753559Y85177I897J1078D01*
G37*
G36*
G01X1491579Y84665D02*
G03X1491783Y84181I380J-125D01*
G02X1489789Y83197I-619J-1258D01*
G03X1489529Y83653I-392J78D01*
G02X1491579Y84665I528J1512D01*
G37*
G36*
G01X1664527Y80590D02*
G03X1663973I-277J-288D01*
G02Y82610I-973J1010D01*
G03X1664527I277J288D01*
G02X1666473I973J-1010D01*
G03X1667027I277J288D01*
G02X1668973I973J-1010D01*
G03X1669527I277J288D01*
G02X1671473I973J-1010D01*
G03X1672027I277J288D01*
G02X1673973I973J-1010D01*
G03X1674527I277J288D01*
G02X1676473I973J-1010D01*
G03X1677027I277J288D01*
G02Y80590I973J-1010D01*
G03X1676473I-277J-288D01*
G02X1674527I-973J1010D01*
G03X1673973I-277J-288D01*
G02X1672027I-973J1010D01*
G03X1671473I-277J-288D01*
G02X1669527I-973J1010D01*
G03X1668973I-277J-288D01*
G02X1667027I-973J1010D01*
G03X1666473I-277J-288D01*
G02X1664527I-973J1010D01*
G37*
G36*
G01X1540631Y78303D02*
G03X1540043Y78212I-253J-310D01*
G02X1539759Y80064I-1173J768D01*
G03X1540347Y80155I253J310D01*
G02X1540631Y78303I1173J-768D01*
G37*
G36*
G01X1695009Y79103D02*
G03X1695533Y79134I244J317D01*
G02Y76848I1122J-1143D01*
G03X1695009Y76879I-280J-286D01*
G02X1693182Y76981I-854J1112D01*
G03X1692628I-277J-288D01*
G02X1690682I-973J1010D01*
G03X1690128I-277J-288D01*
G02Y79001I-973J1010D01*
G03X1690682I277J288D01*
G02X1692628I973J-1010D01*
G03X1693182I277J288D01*
G02X1695009Y79103I973J-1010D01*
G37*
G36*
G01X1044450Y92211D02*
Y93911D01*
X1046189Y95650D01*
X1046536D01*
Y101284D01*
X1048738D01*
Y95650D01*
X1053228D01*
Y101284D01*
X1055432D01*
Y95650D01*
X1056576D01*
Y101284D01*
X1058778D01*
Y95650D01*
X1063268D01*
Y101284D01*
X1065472D01*
Y95650D01*
X1069962D01*
Y101284D01*
X1072164D01*
Y95650D01*
X1073308D01*
Y101284D01*
X1075510D01*
Y95650D01*
X1080000D01*
Y101284D01*
X1082204D01*
Y95650D01*
X1086694D01*
Y101284D01*
X1088896D01*
Y95650D01*
X1093386D01*
Y101284D01*
X1095590D01*
Y95672D01*
X1097450Y93811D01*
Y83589D01*
X1095590Y81728D01*
Y76072D01*
X1093386D01*
Y81650D01*
X1088896D01*
Y76072D01*
X1086694D01*
Y81650D01*
X1085550D01*
Y76072D01*
X1083346D01*
Y81650D01*
X1078856D01*
Y76072D01*
X1076654D01*
Y81650D01*
X1065472D01*
Y76072D01*
X1063268D01*
Y81650D01*
X1055432D01*
Y76072D01*
X1053228D01*
Y81650D01*
X1052086D01*
Y76072D01*
X1049882D01*
Y81650D01*
X1045392D01*
Y76072D01*
X1043190D01*
Y82550D01*
X1042050Y83689D01*
Y89465D01*
G02X1042294Y90055I751J35D01*
G01X1044450Y92211D01*
G37*
G36*
G01X972914Y76072D02*
Y81750D01*
X961730D01*
Y76072D01*
X959528D01*
Y81912D01*
X958350Y83089D01*
Y87489D01*
X954750Y91089D01*
Y93811D01*
X956182Y95242D01*
Y101284D01*
X958384D01*
Y95650D01*
X962874D01*
Y101284D01*
X965078D01*
Y95650D01*
X969568D01*
Y101284D01*
X971770D01*
Y95650D01*
X972914D01*
Y101284D01*
X975116D01*
Y95650D01*
X979606D01*
Y101284D01*
X981810D01*
Y95650D01*
X982954D01*
Y101284D01*
X985156D01*
Y95650D01*
X989646D01*
Y101284D01*
X991850D01*
Y95650D01*
X992992D01*
Y101284D01*
X995196D01*
Y95650D01*
X999686D01*
Y101284D01*
X1001888D01*
Y95650D01*
X1003032D01*
Y101284D01*
X1005234D01*
Y95650D01*
X1009724D01*
Y101284D01*
X1011928D01*
Y95650D01*
X1013072D01*
Y101284D01*
X1015274D01*
Y95650D01*
X1018311D01*
X1020050Y93911D01*
Y83789D01*
X1018011Y81750D01*
X1015274D01*
Y76072D01*
X1013072D01*
Y81750D01*
X1011928D01*
Y76072D01*
X1009724D01*
Y81750D01*
X1005234D01*
Y76072D01*
X1003032D01*
Y81750D01*
X998542D01*
Y76072D01*
X996340D01*
Y81750D01*
X995196D01*
Y76072D01*
X992992D01*
Y81750D01*
X988502D01*
Y76072D01*
X986300D01*
Y81750D01*
X985156D01*
Y76072D01*
X982954D01*
Y81750D01*
X978464D01*
Y76072D01*
X976260D01*
Y81750D01*
X975116D01*
Y76072D01*
X972914D01*
G37*
G36*
G01X306574Y95334D02*
Y101284D01*
X308776D01*
Y95450D01*
X313266D01*
Y101284D01*
X315470D01*
Y95450D01*
X319960D01*
Y101284D01*
X322162D01*
Y95450D01*
X323306D01*
Y101284D01*
X325508D01*
Y95450D01*
X329998D01*
Y101284D01*
X332202D01*
Y95450D01*
X333346D01*
Y101284D01*
X335548D01*
Y95450D01*
X340038D01*
Y101284D01*
X342242D01*
Y95450D01*
X343384D01*
Y101284D01*
X345588D01*
Y95450D01*
X350078D01*
Y101284D01*
X352280D01*
Y95450D01*
X353424D01*
Y101284D01*
X355626D01*
Y95450D01*
X360116D01*
Y101284D01*
X362320D01*
Y95450D01*
X363464D01*
Y101284D01*
X365666D01*
Y95450D01*
X368911D01*
X370350Y94011D01*
Y82789D01*
X369311Y81750D01*
X365666D01*
Y76072D01*
X363464D01*
Y81750D01*
X362320D01*
Y76072D01*
X360116D01*
Y81750D01*
X355626D01*
Y76072D01*
X353424D01*
Y81750D01*
X348934D01*
Y76072D01*
X346732D01*
Y81750D01*
X345588D01*
Y76072D01*
X343384D01*
Y81750D01*
X338894D01*
Y76072D01*
X336692D01*
Y81750D01*
X335548D01*
Y76072D01*
X333346D01*
Y81750D01*
X328856D01*
Y76072D01*
X326652D01*
Y81750D01*
X325508D01*
Y76072D01*
X323306D01*
Y81750D01*
X312122D01*
Y76072D01*
X309920D01*
Y81820D01*
X308650Y83089D01*
Y87689D01*
X305150Y91189D01*
Y93911D01*
X306442Y95203D01*
X306444Y95206D01*
G02X306493Y95253I545J-519D01*
G01X306574Y95334D01*
G37*
G36*
G01X1822075Y76146D02*
G03X1821535I-270J-295D01*
G02X1819255Y78390I-1079J1184D01*
G03X1819261Y78912I-300J264D01*
G02X1821568Y81126I1226J1032D01*
G03X1822108I270J295D01*
G02X1824388Y78882I1079J-1184D01*
G03X1824382Y78360I300J-264D01*
G02X1822075Y76146I-1226J-1032D01*
G37*
G36*
G01X1394060Y75160D02*
G03X1393524I-268J-297D01*
G02X1391612Y77211I-940J1040D01*
G03Y77787I-277J288D01*
G02X1393523Y79839I972J1011D01*
G03X1394059Y79840I267J297D01*
G02X1395934Y79846I941J-1040D01*
G03X1396466I266J298D01*
G02X1398371Y77789I934J-1045D01*
G03Y77211I277J-289D01*
G02X1396466Y75154I-971J-1012D01*
G03X1395934I-266J-298D01*
G02X1394060Y75160I-934J1046D01*
G37*
G36*
G01X1581396Y74870D02*
G03X1580818I-289J-277D01*
G02Y76812I-1011J971D01*
G03X1581396I289J277D01*
G02Y74870I1011J-971D01*
G37*
G36*
G01X1571535Y76354D02*
G03X1572104Y76339I292J273D01*
G02X1572052Y74370I972J-1011D01*
G03X1571483Y74385I-292J-273D01*
G02X1571535Y76354I-972J1011D01*
G37*
G36*
G01X732634Y74469D02*
G03X732024Y74447I-296J-270D01*
G02X731960Y76258I-1101J868D01*
G03X732570Y76280I296J270D01*
G02X732634Y74469I1101J-868D01*
G37*
G36*
G01X1622583Y74541D02*
G03X1622036Y74329I-175J-359D01*
G02X1621350Y76106I-1303J518D01*
G03X1621897Y76318I175J359D01*
G02X1622583Y74541I1303J-518D01*
G37*
G36*
G01X1675015Y75899D02*
G03X1675598Y75776I347J200D01*
G02X1675213Y73947I830J-1130D01*
G03X1674630Y74070I-347J-200D01*
G02X1675015Y75899I-830J1130D01*
G37*
G36*
G01X1680934Y75447D02*
G03X1681488Y75412I295J270D01*
G02X1681362Y73397I908J-1068D01*
G03X1680808Y73432I-295J-270D01*
G02X1680934Y75447I-908J1068D01*
G37*
G36*
G01X62027Y72990D02*
G03X61473I-277J-288D01*
G02X59490Y74973I-973J1010D01*
G03Y75527I-288J277D01*
G02Y77473I1010J973D01*
G03Y78027I-288J277D01*
G02Y79973I1010J973D01*
G03Y80527I-288J277D01*
G02X61473Y82510I1010J973D01*
G03X62027I277J288D01*
G02X64010Y80527I973J-1010D01*
G03Y79973I288J-277D01*
G02Y78027I-1010J-973D01*
G03Y77473I288J-277D01*
G02Y75527I-1010J-973D01*
G03Y74973I288J-277D01*
G02X62027Y72990I-1010J-973D01*
G37*
G36*
G01X1454277Y74673D02*
G03X1454869Y74662I301J263D01*
G02X1454833Y72777I1020J-962D01*
G03X1454241Y72788I-301J-263D01*
G02X1454277Y74673I-1020J962D01*
G37*
G36*
G01X1563646Y75326D02*
G03X1563707Y74752I306J-258D01*
G02X1561779Y74547I-857J-1110D01*
G03X1561718Y75121I-306J258D01*
G02X1563646Y75326I857J1110D01*
G37*
G36*
G01X1895824Y72653D02*
G03X1895156Y72632I-327J-230D01*
G02X1893701Y74743I-1195J733D01*
G03X1894010Y75250I-74J393D01*
G02X1896722Y75344I1344J400D01*
G03X1897081Y74858I390J-87D01*
G02X1895824Y72653I-111J-1398D01*
G37*
G36*
G01X76473Y71510D02*
G03X77027I277J288D01*
G02X77776Y71884I972J-1010D01*
G03X78109Y72328I-64J395D01*
G02X79724Y71116I1391J172D01*
G03X79391Y70672I64J-395D01*
G02X77027Y69490I-1391J-172D01*
G03X76473I-277J-288D01*
G02X74527I-973J1010D01*
G03X73973I-277J-288D01*
G02X72027I-973J1010D01*
G03X71473I-277J-288D01*
G02X69527I-973J1010D01*
G03X68973I-277J-288D01*
G02X67027I-973J1010D01*
G03X66473I-277J-288D01*
G02X64527I-973J1010D01*
G03X63973I-277J-288D01*
G02X62027I-973J1010D01*
G03X61473I-277J-288D01*
G02Y71510I-973J1010D01*
G03X62027I277J288D01*
G02X63973I973J-1010D01*
G03X64527I277J288D01*
G02X66473I973J-1010D01*
G03X67027I277J288D01*
G02X68973I973J-1010D01*
G03X69527I277J288D01*
G02X71473I973J-1010D01*
G03X72027I277J288D01*
G02X73973I973J-1010D01*
G03X74527I277J288D01*
G02X76473I973J-1010D01*
G37*
G36*
G01X1825167Y71302D02*
G03X1825191Y70703I276J-289D01*
G02X1823012Y68364I-1011J-1243D01*
G03X1822431Y68366I-291J-274D01*
G02X1820139Y70604I-1161J1104D01*
G03X1820099Y71206I-282J284D01*
G02X1822273Y73537I970J1275D01*
G03X1822871Y73533I301J264D01*
G02X1825167Y71302I1189J-1073D01*
G37*
G36*
G01X1795700Y70821D02*
G03X1796100Y70402I400J-19D01*
G01X1796101D01*
G02X1794500Y68877I-1J-1602D01*
G03X1794100Y69296I-400J19D01*
G01X1794099D01*
G02X1795700Y70821I1J1602D01*
G37*
G36*
G01X1225862Y70164D02*
G03X1225868Y69607I290J-275D01*
G02X1223712Y69585I-1067J-1057D01*
G03X1223706Y70142I-290J275D01*
G02X1225862Y70164I1067J1057D01*
G37*
G36*
G01X1189051D02*
G03X1189057Y69607I290J-275D01*
G02X1186901Y69585I-1067J-1057D01*
G03X1186895Y70142I-290J275D01*
G02X1189051Y70164I1067J1057D01*
G37*
G36*
G01X1152240D02*
G03X1152246Y69607I290J-275D01*
G02X1150090Y69585I-1067J-1057D01*
G03X1150084Y70142I-290J275D01*
G02X1152240Y70164I1067J1057D01*
G37*
G36*
G01X1115428D02*
G03X1115434Y69607I290J-275D01*
G02X1113278Y69585I-1067J-1057D01*
G03X1113272Y70142I-290J275D01*
G02X1115428Y70164I1067J1057D01*
G37*
G36*
G01X934720D02*
G03X934726Y69607I290J-275D01*
G02X932570Y69585I-1067J-1057D01*
G03X932564Y70142I-290J275D01*
G02X934720Y70164I1067J1057D01*
G37*
G36*
G01X897909D02*
G03X897915Y69607I290J-275D01*
G02X895759Y69585I-1067J-1057D01*
G03X895753Y70142I-290J275D01*
G02X897909Y70164I1067J1057D01*
G37*
G36*
G01X861098D02*
G03X861104Y69607I290J-275D01*
G02X858948Y69585I-1067J-1057D01*
G03X858942Y70142I-290J275D01*
G02X861098Y70164I1067J1057D01*
G37*
G36*
G01X824287D02*
G03X824293Y69607I290J-275D01*
G02X822137Y69585I-1067J-1057D01*
G03X822131Y70142I-290J275D01*
G02X824287Y70164I1067J1057D01*
G37*
G36*
G01X787476D02*
G03X787482Y69607I290J-275D01*
G02X785326Y69585I-1067J-1057D01*
G03X785320Y70142I-290J275D01*
G02X787476Y70164I1067J1057D01*
G37*
G36*
G01X576254D02*
G03X576260Y69607I290J-275D01*
G02X574104Y69585I-1067J-1057D01*
G03X574098Y70142I-290J275D01*
G02X576254Y70164I1067J1057D01*
G37*
G36*
G01X539443D02*
G03X539449Y69607I290J-275D01*
G02X537293Y69585I-1067J-1057D01*
G03X537287Y70142I-290J275D01*
G02X539443Y70164I1067J1057D01*
G37*
G36*
G01X502632D02*
G03X502638Y69607I290J-275D01*
G02X500482Y69585I-1067J-1057D01*
G03X500476Y70142I-290J275D01*
G02X502632Y70164I1067J1057D01*
G37*
G36*
G01X465820D02*
G03X465826Y69607I290J-275D01*
G02X463670Y69585I-1067J-1057D01*
G03X463664Y70142I-290J275D01*
G02X465820Y70164I1067J1057D01*
G37*
G36*
G01X285112D02*
G03X285118Y69607I290J-275D01*
G02X282962Y69585I-1067J-1057D01*
G03X282956Y70142I-290J275D01*
G02X285112Y70164I1067J1057D01*
G37*
G36*
G01X248301D02*
G03X248307Y69607I290J-275D01*
G02X246151Y69585I-1067J-1057D01*
G03X246145Y70142I-290J275D01*
G02X248301Y70164I1067J1057D01*
G37*
G36*
G01X211490D02*
G03X211496Y69607I290J-275D01*
G02X209340Y69585I-1067J-1057D01*
G03X209334Y70142I-290J275D01*
G02X211490Y70164I1067J1057D01*
G37*
G36*
G01X174679D02*
G03X174685Y69607I290J-275D01*
G02X172529Y69585I-1067J-1057D01*
G03X172523Y70142I-290J275D01*
G02X174679Y70164I1067J1057D01*
G37*
G36*
G01X137868D02*
G03X137874Y69607I290J-275D01*
G02X135718Y69585I-1067J-1057D01*
G03X135712Y70142I-290J275D01*
G02X137868Y70164I1067J1057D01*
G37*
G36*
G01X1230967Y69919D02*
G03Y69370I291J-274D01*
G02X1228781I-1093J-1030D01*
G03Y69919I-291J274D01*
G02X1230967I1093J1030D01*
G37*
G36*
G01X1194156D02*
G03Y69370I291J-274D01*
G02X1191970I-1093J-1030D01*
G03Y69919I-291J274D01*
G02X1194156I1093J1030D01*
G37*
G36*
G01X1157345D02*
G03Y69370I291J-274D01*
G02X1155159I-1093J-1030D01*
G03Y69919I-291J274D01*
G02X1157345I1093J1030D01*
G37*
G36*
G01X1120533D02*
G03Y69370I291J-274D01*
G02X1118347I-1093J-1030D01*
G03Y69919I-291J274D01*
G02X1120533I1093J1030D01*
G37*
G36*
G01X939825D02*
G03Y69370I291J-274D01*
G02X937639I-1093J-1030D01*
G03Y69919I-291J274D01*
G02X939825I1093J1030D01*
G37*
G36*
G01X903014D02*
G03Y69370I291J-274D01*
G02X900828I-1093J-1030D01*
G03Y69919I-291J274D01*
G02X903014I1093J1030D01*
G37*
G36*
G01X866203D02*
G03Y69370I291J-274D01*
G02X864017I-1093J-1030D01*
G03Y69919I-291J274D01*
G02X866203I1093J1030D01*
G37*
G36*
G01X829392D02*
G03Y69370I291J-274D01*
G02X827206I-1093J-1030D01*
G03Y69919I-291J274D01*
G02X829392I1093J1030D01*
G37*
G36*
G01X792581D02*
G03Y69370I291J-274D01*
G02X790395I-1093J-1030D01*
G03Y69919I-291J274D01*
G02X792581I1093J1030D01*
G37*
G36*
G01X581359D02*
G03Y69370I291J-274D01*
G02X579173I-1093J-1030D01*
G03Y69919I-291J274D01*
G02X581359I1093J1030D01*
G37*
G36*
G01X544548D02*
G03Y69370I291J-274D01*
G02X542362I-1093J-1030D01*
G03Y69919I-291J274D01*
G02X544548I1093J1030D01*
G37*
G36*
G01X507737D02*
G03Y69370I291J-274D01*
G02X505551I-1093J-1030D01*
G03Y69919I-291J274D01*
G02X507737I1093J1030D01*
G37*
G36*
G01X470925D02*
G03Y69370I291J-274D01*
G02X468739I-1093J-1030D01*
G03Y69919I-291J274D01*
G02X470925I1093J1030D01*
G37*
G36*
G01X290217D02*
G03Y69370I291J-274D01*
G02X288031I-1093J-1030D01*
G03Y69919I-291J274D01*
G02X290217I1093J1030D01*
G37*
G36*
G01X253406D02*
G03Y69370I291J-274D01*
G02X251220I-1093J-1030D01*
G03Y69919I-291J274D01*
G02X253406I1093J1030D01*
G37*
G36*
G01X216595D02*
G03Y69370I291J-274D01*
G02X214409I-1093J-1030D01*
G03Y69919I-291J274D01*
G02X216595I1093J1030D01*
G37*
G36*
G01X179784D02*
G03Y69370I291J-274D01*
G02X177598I-1093J-1030D01*
G03Y69919I-291J274D01*
G02X179784I1093J1030D01*
G37*
G36*
G01X142973D02*
G03Y69370I291J-274D01*
G02X140787I-1093J-1030D01*
G03Y69919I-291J274D01*
G02X142973I1093J1030D01*
G37*
G36*
G01X1845615Y66161D02*
G03X1845085I-265J-300D01*
G02X1842527Y67931I-1060J1201D01*
G03X1842226Y68466I-374J142D01*
G02X1841455Y68841I290J1576D01*
G03X1840925I-265J-300D01*
G02X1838834Y68816I-1060J1201D01*
G03X1838293Y68793I-258J-306D01*
G02X1835740Y69186I-1132J1133D01*
G03X1835120Y69301I-355J-185D01*
G02X1832973Y69324I-1061J1200D01*
G03X1832454Y69343I-271J-295D01*
G02X1830277Y71680I-994J1256D01*
G03Y72220I-295J270D01*
G02X1832643I1183J1080D01*
G03Y71680I295J-270D01*
G02X1832657Y71664I-1198J-1063D01*
G03X1832946Y71653I150J133D01*
G02X1835579Y71007I1113J-1152D01*
G03X1835923Y70943I190J63D01*
G02X1835930Y70951I1209J-1051D01*
G03X1835924Y71471I-307J256D01*
G02X1835592Y72979I1205J1056D01*
G03X1835310Y73479I-384J113D01*
G02X1835250Y76562I404J1550D01*
G03X1835522Y77042I-116J383D01*
G02X1838205Y78566I1555J387D01*
G03X1838786Y78585I282J284D01*
G02X1841073Y78698I1199J-1063D01*
G03X1841632Y78713I272J293D01*
G02X1844328Y77177I1151J-1114D01*
G03X1844581Y76695I386J-105D01*
G02X1845132Y76364I-533J-1511D01*
G03X1845655Y76348I271J294D01*
G02X1847024Y73544I1012J-1242D01*
G03X1846724Y73062I89J-390D01*
G02X1846366Y71632I-1559J-370D01*
G03Y71102I300J-265D01*
G02X1846663Y69473I-1201J-1061D01*
G03X1846964Y68938I374J-142D01*
G02X1847735Y68563I-290J-1576D01*
G03X1848265I265J300D01*
G02Y66161I1060J-1201D01*
G03X1847735I-265J-300D01*
G02X1845615I-1060J1201D01*
G37*
G36*
G01X1733Y66210D02*
G03X1351Y66698I-390J88D01*
G02X2749Y67790I31J1402D01*
G03X3131Y67302I390J-88D01*
G02X1733Y66210I-31J-1402D01*
G37*
G36*
G01X1328429Y66950D02*
G03Y66350I265J-300D01*
G02X1326571I-929J-1050D01*
G03Y66950I-265J300D01*
G02X1326598Y69073I929J1050D01*
G03X1326591Y69692I-257J307D01*
G02X1328369Y69713I876J1094D01*
G03X1328376Y69094I257J-307D01*
G02X1328429Y66950I-876J-1094D01*
G37*
G36*
G01X1649871Y64260D02*
G03X1649293Y64256I-287J-279D01*
G02X1649281Y66198I-1017J965D01*
G03X1649859Y66202I287J279D01*
G02X1649871Y64260I1017J-965D01*
G37*
G36*
G01X734722Y65252D02*
G03X734742Y64719I308J-255D01*
G02X732775Y62723I-1010J-972D01*
G03X732242Y62735I-273J-292D01*
G02X730252Y64695I-910J1067D01*
G03X730232Y65228I-308J255D01*
G02X730180Y67115I1010J972D01*
G03X730171Y67648I-303J261D01*
G02X732157Y69624I1029J952D01*
G03X732690Y69612I273J292D01*
G02X734662Y67631I909J-1067D01*
G03X734671Y67098I303J-261D01*
G02X734722Y65252I-1029J-952D01*
G37*
G36*
G01X1785725Y65065D02*
G03X1786169Y64732I395J64D01*
G02X1784957Y63117I172J-1391D01*
G03X1784513Y63450I-395J-64D01*
G02X1785725Y65065I-172J1391D01*
G37*
G36*
G01X1610284Y62579D02*
G03X1609752Y62364I-162J-365D01*
G02X1607065Y63094I-1300J526D01*
G03X1606698Y63551I-396J58D01*
G02X1608184Y64745I99J1398D01*
G03X1608551Y64288I396J-58D01*
G02X1609021Y64172I-96J-1399D01*
G03X1609553Y64387I162J365D01*
G02X1610284Y62579I1300J-526D01*
G37*
G36*
G01X1734177Y57140D02*
G03X1733623I-277J-288D01*
G02X1731640Y59123I-973J1010D01*
G03Y59677I-288J277D01*
G02X1733660I1010J973D01*
G03Y59123I288J-277D01*
G02X1733744Y59027I-1012J-970D01*
G03X1734056I156J125D01*
G02X1734177Y57140I1094J-877D01*
G37*
G36*
G01X15614Y55240D02*
G03X15036I-289J-277D01*
G02Y57182I-1011J971D01*
G03X15614I289J277D01*
G02Y55240I1011J-971D01*
G37*
G36*
G01X60527Y54990D02*
G03X59973I-277J-288D01*
G02X57990Y56973I-973J1010D01*
G03Y57527I-288J277D01*
G02Y59473I1010J973D01*
G03Y60027I-288J277D01*
G02X59973Y62010I1010J973D01*
G03X60527I277J288D01*
G02X62510Y60027I973J-1010D01*
G03Y59473I288J-277D01*
G02Y57527I-1010J-973D01*
G03Y56973I288J-277D01*
G02X60527Y54990I-1010J-973D01*
G37*
G36*
G01X1240630Y55978D02*
Y63484D01*
X1242834D01*
Y55978D01*
G02X1240630I-1102J-1021D01*
G37*
G36*
G01X1233938D02*
Y63484D01*
X1236140D01*
Y55978D01*
G02X1233938I-1101J-1021D01*
G37*
G36*
G01X1217204Y55977D02*
Y63484D01*
X1219408D01*
Y55979D01*
G02X1217204Y55977I-1101J-1022D01*
G37*
G36*
G01X1210512D02*
Y63484D01*
X1212714D01*
Y55979D01*
G02X1210512Y55977I-1100J-1022D01*
G37*
G36*
G01X1203820Y55978D02*
Y63484D01*
X1206022D01*
Y55978D01*
G02X1203820I-1101J-1021D01*
G37*
G36*
G01X1197126D02*
Y63484D01*
X1199330D01*
Y55978D01*
G02X1197126I-1102J-1021D01*
G37*
G36*
G01X1180394Y55977D02*
Y63484D01*
X1182596D01*
Y55979D01*
G02X1180394Y55977I-1100J-1022D01*
G37*
G36*
G01X1173700D02*
Y63484D01*
X1175904D01*
Y55979D01*
G02X1173700Y55977I-1101J-1022D01*
G37*
G36*
G01X1167008Y55978D02*
Y63484D01*
X1169212D01*
Y55978D01*
G02X1167008I-1102J-1021D01*
G37*
G36*
G01X1160316D02*
Y63484D01*
X1162518D01*
Y55978D01*
G02X1160316I-1101J-1021D01*
G37*
G36*
G01X1143582Y55977D02*
Y63484D01*
X1145786D01*
Y55979D01*
G02X1143582Y55977I-1101J-1022D01*
G37*
G36*
G01X1136890D02*
Y63484D01*
X1139092D01*
Y55979D01*
G02X1136890Y55977I-1100J-1022D01*
G37*
G36*
G01X1130198Y55978D02*
Y63484D01*
X1132400D01*
Y55978D01*
G02X1130198I-1101J-1021D01*
G37*
G36*
G01X1123504D02*
Y63484D01*
X1125708D01*
Y55978D01*
G02X1123504I-1102J-1021D01*
G37*
G36*
G01X1106772Y55977D02*
Y63484D01*
X1108974D01*
Y55979D01*
G02X1106772Y55977I-1100J-1022D01*
G37*
G36*
G01X1100078D02*
Y63484D01*
X1102282D01*
Y55979D01*
G02X1100078Y55977I-1101J-1022D01*
G37*
G36*
G01X949490Y55979D02*
Y63484D01*
X951692D01*
Y55977D01*
G02X949490Y55979I-1102J-1020D01*
G37*
G36*
G01X942796Y55978D02*
Y63484D01*
X944998D01*
Y55978D01*
G02X942796I-1101J-1021D01*
G37*
G36*
G01X926064D02*
Y63484D01*
X928266D01*
Y55978D01*
G02X926064I-1101J-1021D01*
G37*
G36*
G01X919370D02*
Y63484D01*
X921574D01*
Y55978D01*
G02X919370I-1102J-1021D01*
G37*
G36*
G01X912678D02*
Y63484D01*
X914880D01*
Y55978D01*
G02X912678I-1101J-1021D01*
G37*
G36*
G01X905984D02*
Y63484D01*
X908188D01*
Y55978D01*
G02X905984I-1102J-1021D01*
G37*
G36*
G01X889252D02*
Y63484D01*
X891456D01*
Y55978D01*
G02X889252I-1102J-1021D01*
G37*
G36*
G01X882560D02*
Y63484D01*
X884762D01*
Y55978D01*
G02X882560I-1101J-1021D01*
G37*
G36*
G01X875866D02*
Y63484D01*
X878070D01*
Y55978D01*
G02X875866I-1102J-1021D01*
G37*
G36*
G01X869174D02*
Y63484D01*
X871376D01*
Y55978D01*
G02X869174I-1101J-1021D01*
G37*
G36*
G01X852442D02*
Y63484D01*
X854644D01*
Y55978D01*
G02X852442I-1101J-1021D01*
G37*
G36*
G01X845748D02*
Y63484D01*
X847952D01*
Y55978D01*
G02X845748I-1102J-1021D01*
G37*
G36*
G01X839056D02*
Y63484D01*
X841258D01*
Y55978D01*
G02X839056I-1101J-1021D01*
G37*
G36*
G01X832362D02*
Y63484D01*
X834566D01*
Y55978D01*
G02X832362I-1102J-1021D01*
G37*
G36*
G01X815630D02*
Y63484D01*
X817834D01*
Y55978D01*
G02X815630I-1102J-1021D01*
G37*
G36*
G01X808938D02*
Y63484D01*
X811140D01*
Y55978D01*
G02X808938I-1101J-1021D01*
G37*
G36*
G01X802244D02*
Y63484D01*
X804448D01*
Y55978D01*
G02X802244I-1102J-1021D01*
G37*
G36*
G01X795552D02*
Y63484D01*
X797754D01*
Y55978D01*
G02X795552I-1101J-1021D01*
G37*
G36*
G01X778820D02*
Y63484D01*
X781022D01*
Y55978D01*
G02X778820I-1101J-1021D01*
G37*
G36*
G01X772126D02*
Y63484D01*
X774330D01*
Y55978D01*
G02X772126I-1102J-1021D01*
G37*
G36*
G01X591022D02*
Y63484D01*
X593226D01*
Y55978D01*
G02X591022I-1102J-1021D01*
G37*
G36*
G01X584330D02*
Y63484D01*
X586532D01*
Y55978D01*
G02X584330I-1101J-1021D01*
G37*
G36*
G01X567596Y55977D02*
Y63484D01*
X569800D01*
Y55979D01*
G02X567596Y55977I-1101J-1022D01*
G37*
G36*
G01X560904D02*
Y63484D01*
X563106D01*
Y55979D01*
G02X560904Y55977I-1100J-1022D01*
G37*
G36*
G01X554212Y55978D02*
Y63484D01*
X556414D01*
Y55978D01*
G02X554212I-1101J-1021D01*
G37*
G36*
G01X547518D02*
Y63484D01*
X549722D01*
Y55978D01*
G02X547518I-1102J-1021D01*
G37*
G36*
G01X530786Y55977D02*
Y63484D01*
X532988D01*
Y55979D01*
G02X530786Y55977I-1100J-1022D01*
G37*
G36*
G01X524092D02*
Y63484D01*
X526296D01*
Y55979D01*
G02X524092Y55977I-1101J-1022D01*
G37*
G36*
G01X517400Y55978D02*
Y63484D01*
X519604D01*
Y55978D01*
G02X517400I-1102J-1021D01*
G37*
G36*
G01X510708D02*
Y63484D01*
X512910D01*
Y55978D01*
G02X510708I-1101J-1021D01*
G37*
G36*
G01X493974Y55977D02*
Y63484D01*
X496178D01*
Y55979D01*
G02X493974Y55977I-1101J-1022D01*
G37*
G36*
G01X487282D02*
Y63484D01*
X489484D01*
Y55979D01*
G02X487282Y55977I-1100J-1022D01*
G37*
G36*
G01X480590Y55978D02*
Y63484D01*
X482792D01*
Y55978D01*
G02X480590I-1101J-1021D01*
G37*
G36*
G01X473896D02*
Y63484D01*
X476100D01*
Y55978D01*
G02X473896I-1102J-1021D01*
G37*
G36*
G01X457164Y55977D02*
Y63484D01*
X459366D01*
Y55979D01*
G02X457164Y55977I-1100J-1022D01*
G37*
G36*
G01X450470D02*
Y63484D01*
X452674D01*
Y55979D01*
G02X450470Y55977I-1101J-1022D01*
G37*
G36*
G01X299882Y55979D02*
Y63484D01*
X302084D01*
Y55977D01*
G02X299882Y55979I-1102J-1020D01*
G37*
G36*
G01X293188Y55978D02*
Y63484D01*
X295390D01*
Y55978D01*
G02X293188I-1101J-1021D01*
G37*
G36*
G01X276456D02*
Y63484D01*
X278658D01*
Y55978D01*
G02X276456I-1101J-1021D01*
G37*
G36*
G01X269762D02*
Y63484D01*
X271966D01*
Y55978D01*
G02X269762I-1102J-1021D01*
G37*
G36*
G01X263070D02*
Y63484D01*
X265272D01*
Y55978D01*
G02X263070I-1101J-1021D01*
G37*
G36*
G01X256376D02*
Y63484D01*
X258580D01*
Y55978D01*
G02X256376I-1102J-1021D01*
G37*
G36*
G01X239644D02*
Y63484D01*
X241848D01*
Y55978D01*
G02X239644I-1102J-1021D01*
G37*
G36*
G01X232952D02*
Y63484D01*
X235154D01*
Y55978D01*
G02X232952I-1101J-1021D01*
G37*
G36*
G01X226258D02*
Y63484D01*
X228462D01*
Y55978D01*
G02X226258I-1102J-1021D01*
G37*
G36*
G01X219566D02*
Y63484D01*
X221768D01*
Y55978D01*
G02X219566I-1101J-1021D01*
G37*
G36*
G01X202834D02*
Y63484D01*
X205036D01*
Y55978D01*
G02X202834I-1101J-1021D01*
G37*
G36*
G01X196140D02*
Y63484D01*
X198344D01*
Y55978D01*
G02X196140I-1102J-1021D01*
G37*
G36*
G01X189448D02*
Y63484D01*
X191650D01*
Y55978D01*
G02X189448I-1101J-1021D01*
G37*
G36*
G01X182754D02*
Y63484D01*
X184958D01*
Y55978D01*
G02X182754I-1102J-1021D01*
G37*
G36*
G01X166022D02*
Y63484D01*
X168226D01*
Y55978D01*
G02X166022I-1102J-1021D01*
G37*
G36*
G01X159330D02*
Y63484D01*
X161532D01*
Y55978D01*
G02X159330I-1101J-1021D01*
G37*
G36*
G01X152636D02*
Y63484D01*
X154840D01*
Y55978D01*
G02X152636I-1102J-1021D01*
G37*
G36*
G01X145944D02*
Y63484D01*
X148146D01*
Y55978D01*
G02X145944I-1101J-1021D01*
G37*
G36*
G01X129212D02*
Y63484D01*
X131414D01*
Y55978D01*
G02X129212I-1101J-1021D01*
G37*
G36*
G01X122518D02*
Y63484D01*
X124722D01*
Y55978D01*
G02X122518I-1102J-1021D01*
G37*
G36*
G01X1816718Y55668D02*
G03X1817330Y55663I308J255D01*
G02X1817315Y53859I1066J-911D01*
G03X1816703Y53864I-308J-255D01*
G02X1816718Y55668I-1066J911D01*
G37*
G36*
G01X1825893Y54749D02*
G03X1826068Y54496I193J-54D01*
G02X1824348Y53154I-138J-1596D01*
G03X1824033Y53610I-395J64D01*
G02X1823249Y56344I317J1570D01*
G03X1823261Y56913I-275J290D01*
G02X1823034Y58850I1149J1116D01*
G03X1822918Y59383I-344J204D01*
G02X1825206Y59880I912J1317D01*
G03X1825322Y59347I344J-204D01*
G02X1825980Y58351I-912J-1318D01*
G03X1826477Y58045I392J80D01*
G02X1826212Y55053I423J-1545D01*
G03X1825929Y54907I-86J-180D01*
G02X1825893Y54749I-1578J276D01*
G37*
G36*
G01X1668527Y50490D02*
G03X1667973I-277J-288D01*
G02Y52510I-973J1010D01*
G03X1668527I277J288D01*
G02Y50490I973J-1010D01*
G37*
G36*
G01X1230970Y51287D02*
G03Y50741I292J-273D01*
G02X1228778I-1096J-1027D01*
G03Y51287I-292J273D01*
G02X1230970I1096J1027D01*
G37*
G36*
G01X1194159D02*
G03Y50741I292J-273D01*
G02X1191967I-1096J-1027D01*
G03Y51287I-292J273D01*
G02X1194159I1096J1027D01*
G37*
G36*
G01X1157347D02*
G03Y50741I292J-273D01*
G02X1155155I-1096J-1027D01*
G03Y51287I-292J273D01*
G02X1157347I1096J1027D01*
G37*
G36*
G01X1120536D02*
G03Y50741I292J-273D01*
G02X1118344I-1096J-1027D01*
G03Y51287I-292J273D01*
G02X1120536I1096J1027D01*
G37*
G36*
G01X939828D02*
G03Y50741I292J-273D01*
G02X937636I-1096J-1027D01*
G03Y51287I-292J273D01*
G02X939828I1096J1027D01*
G37*
G36*
G01X903017D02*
G03Y50741I292J-273D01*
G02X900825I-1096J-1027D01*
G03Y51287I-292J273D01*
G02X903017I1096J1027D01*
G37*
G36*
G01X866206D02*
G03Y50741I292J-273D01*
G02X864014I-1096J-1027D01*
G03Y51287I-292J273D01*
G02X866206I1096J1027D01*
G37*
G36*
G01X829395D02*
G03Y50741I292J-273D01*
G02X827203I-1096J-1027D01*
G03Y51287I-292J273D01*
G02X829395I1096J1027D01*
G37*
G36*
G01X792584D02*
G03Y50741I292J-273D01*
G02X790392I-1096J-1027D01*
G03Y51287I-292J273D01*
G02X792584I1096J1027D01*
G37*
G36*
G01X581362D02*
G03Y50741I292J-273D01*
G02X579170I-1096J-1027D01*
G03Y51287I-292J273D01*
G02X581362I1096J1027D01*
G37*
G36*
G01X544551D02*
G03Y50741I292J-273D01*
G02X542359I-1096J-1027D01*
G03Y51287I-292J273D01*
G02X544551I1096J1027D01*
G37*
G36*
G01X507739D02*
G03Y50741I292J-273D01*
G02X505547I-1096J-1027D01*
G03Y51287I-292J273D01*
G02X507739I1096J1027D01*
G37*
G36*
G01X470928D02*
G03Y50741I292J-273D01*
G02X468736I-1096J-1027D01*
G03Y51287I-292J273D01*
G02X470928I1096J1027D01*
G37*
G36*
G01X290220D02*
G03Y50741I292J-273D01*
G02X288028I-1096J-1027D01*
G03Y51287I-292J273D01*
G02X290220I1096J1027D01*
G37*
G36*
G01X253409D02*
G03Y50741I292J-273D01*
G02X251217I-1096J-1027D01*
G03Y51287I-292J273D01*
G02X253409I1096J1027D01*
G37*
G36*
G01X216598D02*
G03Y50741I292J-273D01*
G02X214406I-1096J-1027D01*
G03Y51287I-292J273D01*
G02X216598I1096J1027D01*
G37*
G36*
G01X179787D02*
G03Y50741I292J-273D01*
G02X177595I-1096J-1027D01*
G03Y51287I-292J273D01*
G02X179787I1096J1027D01*
G37*
G36*
G01X142976D02*
G03Y50741I292J-273D01*
G02X140784I-1096J-1027D01*
G03Y51287I-292J273D01*
G02X142976I1096J1027D01*
G37*
G36*
G01X1225870Y51073D02*
G03Y50527I292J-273D01*
G02X1223678I-1096J-1027D01*
G03Y51073I-292J273D01*
G02X1225870I1096J1027D01*
G37*
G36*
G01X1189059D02*
G03Y50527I292J-273D01*
G02X1186867I-1096J-1027D01*
G03Y51073I-292J273D01*
G02X1189059I1096J1027D01*
G37*
G36*
G01X1152247D02*
G03Y50527I292J-273D01*
G02X1150055I-1096J-1027D01*
G03Y51073I-292J273D01*
G02X1152247I1096J1027D01*
G37*
G36*
G01X1115436D02*
G03Y50527I292J-273D01*
G02X1113244I-1096J-1027D01*
G03Y51073I-292J273D01*
G02X1115436I1096J1027D01*
G37*
G36*
G01X934728D02*
G03Y50527I292J-273D01*
G02X932536I-1096J-1027D01*
G03Y51073I-292J273D01*
G02X934728I1096J1027D01*
G37*
G36*
G01X897917D02*
G03Y50527I292J-273D01*
G02X895725I-1096J-1027D01*
G03Y51073I-292J273D01*
G02X897917I1096J1027D01*
G37*
G36*
G01X861106D02*
G03Y50527I292J-273D01*
G02X858914I-1096J-1027D01*
G03Y51073I-292J273D01*
G02X861106I1096J1027D01*
G37*
G36*
G01X824295D02*
G03Y50527I292J-273D01*
G02X822103I-1096J-1027D01*
G03Y51073I-292J273D01*
G02X824295I1096J1027D01*
G37*
G36*
G01X787484D02*
G03Y50527I292J-273D01*
G02X785292I-1096J-1027D01*
G03Y51073I-292J273D01*
G02X787484I1096J1027D01*
G37*
G36*
G01X576262D02*
G03Y50527I292J-273D01*
G02X574070I-1096J-1027D01*
G03Y51073I-292J273D01*
G02X576262I1096J1027D01*
G37*
G36*
G01X539451D02*
G03Y50527I292J-273D01*
G02X537259I-1096J-1027D01*
G03Y51073I-292J273D01*
G02X539451I1096J1027D01*
G37*
G36*
G01X502639D02*
G03Y50527I292J-273D01*
G02X500447I-1096J-1027D01*
G03Y51073I-292J273D01*
G02X502639I1096J1027D01*
G37*
G36*
G01X465828D02*
G03Y50527I292J-273D01*
G02X463636I-1096J-1027D01*
G03Y51073I-292J273D01*
G02X465828I1096J1027D01*
G37*
G36*
G01X285120D02*
G03Y50527I292J-273D01*
G02X282928I-1096J-1027D01*
G03Y51073I-292J273D01*
G02X285120I1096J1027D01*
G37*
G36*
G01X248309D02*
G03Y50527I292J-273D01*
G02X246117I-1096J-1027D01*
G03Y51073I-292J273D01*
G02X248309I1096J1027D01*
G37*
G36*
G01X211498D02*
G03Y50527I292J-273D01*
G02X209306I-1096J-1027D01*
G03Y51073I-292J273D01*
G02X211498I1096J1027D01*
G37*
G36*
G01X174687D02*
G03Y50527I292J-273D01*
G02X172495I-1096J-1027D01*
G03Y51073I-292J273D01*
G02X174687I1096J1027D01*
G37*
G36*
G01X137876D02*
G03Y50527I292J-273D01*
G02X135684I-1096J-1027D01*
G03Y51073I-292J273D01*
G02X137876I1096J1027D01*
G37*
G36*
G01X1744121Y46096D02*
G03X1743567I-277J-288D01*
G02Y48116I-973J1010D01*
G03X1744121I277J288D01*
G02Y46096I973J-1010D01*
G37*
G36*
G01X1363531Y44948D02*
G03X1363481Y44361I244J-316D01*
G02X1361591Y44523I-1033J-948D01*
G03X1361641Y45110I-244J316D01*
G02X1363531Y44948I1033J948D01*
G37*
G36*
G01X1309627Y40490D02*
G03X1309073I-277J-288D01*
G02Y42510I-973J1010D01*
G03X1309627I277J288D01*
G02Y40490I973J-1010D01*
G37*
G36*
G01X1324989Y40468D02*
G03X1324411I-289J-277D01*
G02X1322354Y42373I-1012J971D01*
G03Y42905I-298J266D01*
G02X1324392Y44829I1047J933D01*
G03X1324982Y44855I283J283D01*
G02X1327038Y42954I1076J-898D01*
G03X1327025Y42395I280J-286D01*
G02X1324989Y40468I-1025J-956D01*
G37*
G36*
G01X1721758Y38368D02*
X1717958D01*
G02Y41392I0J1512D01*
G01X1721759D01*
G02X1723270Y39890I-1J-1512D01*
G01Y39795D01*
X1723260Y39711D01*
G02X1721758Y38368I-1502J169D01*
G37*
G36*
G01X1703073Y38168D02*
X1699273D01*
G02Y41190I0J1511D01*
G01X1703074D01*
G02X1704584Y39689I-1J-1511D01*
G01Y39594D01*
X1704575Y39510D01*
G02X1703073Y38168I-1502J169D01*
G37*
G36*
G01X1740556Y37975D02*
Y37965D01*
X1736654Y38080D01*
X1736483Y38104D01*
G02X1736742Y41111I217J1496D01*
G01Y41121D01*
X1740642Y41006D01*
X1740650Y40998D01*
X1740723Y40992D01*
G02X1742110Y39496I-125J-1506D01*
G01Y39401D01*
X1742100Y39317D01*
G02X1740556Y37975I-1502J169D01*
G37*
G36*
G01X1731183Y37954D02*
X1727383D01*
G02Y40976I0J1511D01*
G01X1731183D01*
G02X1732694Y39475I0J-1511D01*
G01Y39380D01*
X1732685Y39296D01*
G02X1731183Y37954I-1502J169D01*
G37*
G36*
G01X1694098Y37950D02*
X1689098D01*
G02Y40974I0J1512D01*
G01X1694098D01*
G02X1695610Y39472I0J-1512D01*
G01Y39377D01*
X1695600Y39293D01*
G02X1694098Y37950I-1502J169D01*
G37*
G36*
G01X1684648D02*
X1679648D01*
G02Y40974I0J1512D01*
G01X1684649D01*
G02X1686160Y39472I-1J-1512D01*
G01Y39377D01*
X1686150Y39293D01*
G02X1684648Y37950I-1502J169D01*
G37*
G36*
G01X1675198D02*
X1670198D01*
G02Y40974I0J1512D01*
G01X1675199D01*
G02X1676710Y39472I-1J-1512D01*
G01Y39377D01*
X1676700Y39293D01*
G02X1675198Y37950I-1502J169D01*
G37*
G36*
G01X1646848D02*
X1641848D01*
G02Y40974I0J1512D01*
G01X1646849D01*
G02X1648360Y39472I-1J-1512D01*
G01Y39377D01*
X1648350Y39293D01*
G02X1646848Y37950I-1502J169D01*
G37*
G36*
G01X1712308Y37838D02*
X1708508D01*
G02Y40862I0J1512D01*
G01X1712309D01*
G02X1713820Y39360I-1J-1512D01*
G01Y39265D01*
X1713810Y39181D01*
G02X1712308Y37838I-1502J168D01*
G37*
G36*
G01X1368689Y36829D02*
G03X1368111I-289J-277D01*
G02Y38771I-1011J971D01*
G03X1368689I289J277D01*
G02Y36829I1011J-971D01*
G37*
G36*
G01X1660748Y40974D02*
X1665749D01*
G02X1667260Y39472I-1J-1512D01*
G01Y39377D01*
X1667250Y39293D01*
G02X1665748Y37950I-1502J169D01*
G01X1662563D01*
G03X1662204Y37375I1J-400D01*
G02X1659887Y37682I-1260J-614D01*
G03X1659829Y38262I-302J263D01*
G02X1660748Y40974I919J1200D01*
G37*
G36*
G01X1651297D02*
X1656299D01*
G02X1657810Y39472I-1J-1512D01*
G01Y39377D01*
X1657800Y39293D01*
G02X1656298Y37950I-1502J169D01*
G01X1652864D01*
G03X1652506Y37373I0J-400D01*
G02X1650282Y37764I-1256J-623D01*
G03X1650276Y38348I-276J289D01*
G02X1651297Y40974I1022J1114D01*
G37*
G36*
G01X1847503Y35441D02*
G03X1848058Y35439I279J287D01*
G02X1848051Y33420I969J-1013D01*
G03X1847496Y33422I-279J-287D01*
G02X1847503Y35441I-969J1013D01*
G37*
G36*
G01X655725Y30405D02*
G03X655151Y30327I-250J-312D01*
G02X652986Y30199I-1135J823D01*
G03X652415Y30215I-293J-272D01*
G02X650428Y30257I-973J1010D01*
G03X649856Y30264I-289J-276D01*
G02X649881Y32226I-989J994D01*
G03X650453Y32219I289J276D01*
G02X652472Y32176I989J-994D01*
G03X653043Y32160I293J272D01*
G02X654891Y32245I972J-1010D01*
G03X655465Y32323I250J312D01*
G02X655725Y30405I1135J-823D01*
G37*
G36*
G01X1311586Y30712D02*
G03X1311131Y30400I-64J-395D01*
G02X1309983Y32075I-1371J291D01*
G03X1310438Y32387I64J395D01*
G02X1313179Y32393I1371J-292D01*
G03X1313653Y32086I391J84D01*
G02X1314428Y32029I289J-1372D01*
G03X1314952Y32295I139J375D01*
G02X1317220Y32969I1348J-384D01*
G03X1317752Y32976I262J302D01*
G02X1319816Y32791I948J-1033D01*
G03X1320427Y32760I319J242D01*
G02X1320336Y30955I1025J-956D01*
G03X1319725Y30986I-319J-242D01*
G02X1317780Y30885I-1025J957D01*
G03X1317248Y30878I-262J-302D01*
G02X1315814Y30596I-948J1033D01*
G03X1315290Y30330I-139J-375D01*
G02X1312572Y30417I-1348J384D01*
G03X1312098Y30724I-391J-84D01*
G02X1311586Y30712I-288J1372D01*
G37*
G36*
G01X1225862Y32364D02*
G03X1225868Y31807I290J-275D01*
G02X1223712Y31785I-1067J-1057D01*
G03X1223706Y32342I-290J275D01*
G02X1225862Y32364I1067J1057D01*
G37*
G36*
G01X1189051D02*
G03X1189057Y31807I290J-275D01*
G02X1186901Y31785I-1067J-1057D01*
G03X1186895Y32342I-290J275D01*
G02X1189051Y32364I1067J1057D01*
G37*
G36*
G01X1152239D02*
G03X1152245Y31807I290J-275D01*
G02X1150089Y31785I-1067J-1057D01*
G03X1150083Y32342I-290J275D01*
G02X1152239Y32364I1067J1057D01*
G37*
G36*
G01X1115428D02*
G03X1115434Y31807I290J-275D01*
G02X1113278Y31785I-1067J-1057D01*
G03X1113272Y32342I-290J275D01*
G02X1115428Y32364I1067J1057D01*
G37*
G36*
G01X934720D02*
G03X934726Y31807I290J-275D01*
G02X932570Y31785I-1067J-1057D01*
G03X932564Y32342I-290J275D01*
G02X934720Y32364I1067J1057D01*
G37*
G36*
G01X897909D02*
G03X897915Y31807I290J-275D01*
G02X895759Y31785I-1067J-1057D01*
G03X895753Y32342I-290J275D01*
G02X897909Y32364I1067J1057D01*
G37*
G36*
G01X861098D02*
G03X861104Y31807I290J-275D01*
G02X858948Y31785I-1067J-1057D01*
G03X858942Y32342I-290J275D01*
G02X861098Y32364I1067J1057D01*
G37*
G36*
G01X824287D02*
G03X824293Y31807I290J-275D01*
G02X822137Y31785I-1067J-1057D01*
G03X822131Y32342I-290J275D01*
G02X824287Y32364I1067J1057D01*
G37*
G36*
G01X787476D02*
G03X787482Y31807I290J-275D01*
G02X785326Y31785I-1067J-1057D01*
G03X785320Y32342I-290J275D01*
G02X787476Y32364I1067J1057D01*
G37*
G36*
G01X576254D02*
G03X576260Y31807I290J-275D01*
G02X574104Y31785I-1067J-1057D01*
G03X574098Y32342I-290J275D01*
G02X576254Y32364I1067J1057D01*
G37*
G36*
G01X539443D02*
G03X539449Y31807I290J-275D01*
G02X537293Y31785I-1067J-1057D01*
G03X537287Y32342I-290J275D01*
G02X539443Y32364I1067J1057D01*
G37*
G36*
G01X502631D02*
G03X502637Y31807I290J-275D01*
G02X500481Y31785I-1067J-1057D01*
G03X500475Y32342I-290J275D01*
G02X502631Y32364I1067J1057D01*
G37*
G36*
G01X465820D02*
G03X465826Y31807I290J-275D01*
G02X463670Y31785I-1067J-1057D01*
G03X463664Y32342I-290J275D01*
G02X465820Y32364I1067J1057D01*
G37*
G36*
G01X285112D02*
G03X285118Y31807I290J-275D01*
G02X282962Y31785I-1067J-1057D01*
G03X282956Y32342I-290J275D01*
G02X285112Y32364I1067J1057D01*
G37*
G36*
G01X248301D02*
G03X248307Y31807I290J-275D01*
G02X246151Y31785I-1067J-1057D01*
G03X246145Y32342I-290J275D01*
G02X248301Y32364I1067J1057D01*
G37*
G36*
G01X211490D02*
G03X211496Y31807I290J-275D01*
G02X209340Y31785I-1067J-1057D01*
G03X209334Y32342I-290J275D01*
G02X211490Y32364I1067J1057D01*
G37*
G36*
G01X174679D02*
G03X174685Y31807I290J-275D01*
G02X172529Y31785I-1067J-1057D01*
G03X172523Y32342I-290J275D01*
G02X174679Y32364I1067J1057D01*
G37*
G36*
G01X137868D02*
G03X137874Y31807I290J-275D01*
G02X135718Y31785I-1067J-1057D01*
G03X135712Y32342I-290J275D01*
G02X137868Y32364I1067J1057D01*
G37*
G36*
G01X1230967Y32119D02*
G03Y31570I291J-275D01*
G02X1228781I-1093J-1030D01*
G03Y32119I-291J274D01*
G02X1230967I1093J1030D01*
G37*
G36*
G01X1194156D02*
G03Y31570I291J-275D01*
G02X1191970I-1093J-1030D01*
G03Y32119I-291J274D01*
G02X1194156I1093J1030D01*
G37*
G36*
G01X1157344D02*
G03Y31570I291J-275D01*
G02X1155158I-1093J-1030D01*
G03Y32119I-291J274D01*
G02X1157344I1093J1030D01*
G37*
G36*
G01X1120533D02*
G03Y31570I291J-275D01*
G02X1118347I-1093J-1030D01*
G03Y32119I-291J274D01*
G02X1120533I1093J1030D01*
G37*
G36*
G01X939825D02*
G03Y31570I291J-275D01*
G02X937639I-1093J-1030D01*
G03Y32119I-291J274D01*
G02X939825I1093J1030D01*
G37*
G36*
G01X903014D02*
G03Y31570I291J-275D01*
G02X900828I-1093J-1030D01*
G03Y32119I-291J274D01*
G02X903014I1093J1030D01*
G37*
G36*
G01X866203D02*
G03Y31570I291J-275D01*
G02X864017I-1093J-1030D01*
G03Y32119I-291J274D01*
G02X866203I1093J1030D01*
G37*
G36*
G01X829392D02*
G03Y31570I291J-275D01*
G02X827206I-1093J-1030D01*
G03Y32119I-291J274D01*
G02X829392I1093J1030D01*
G37*
G36*
G01X792581D02*
G03Y31570I291J-275D01*
G02X790395I-1093J-1030D01*
G03Y32119I-291J274D01*
G02X792581I1093J1030D01*
G37*
G36*
G01X581359D02*
G03Y31570I291J-275D01*
G02X579173I-1093J-1030D01*
G03Y32119I-291J274D01*
G02X581359I1093J1030D01*
G37*
G36*
G01X544548D02*
G03Y31570I291J-275D01*
G02X542362I-1093J-1030D01*
G03Y32119I-291J274D01*
G02X544548I1093J1030D01*
G37*
G36*
G01X507736D02*
G03Y31570I291J-275D01*
G02X505550I-1093J-1030D01*
G03Y32119I-291J274D01*
G02X507736I1093J1030D01*
G37*
G36*
G01X470925D02*
G03Y31570I291J-275D01*
G02X468739I-1093J-1030D01*
G03Y32119I-291J274D01*
G02X470925I1093J1030D01*
G37*
G36*
G01X290217D02*
G03Y31570I291J-275D01*
G02X288031I-1093J-1030D01*
G03Y32119I-291J274D01*
G02X290217I1093J1030D01*
G37*
G36*
G01X253406D02*
G03Y31570I291J-275D01*
G02X251220I-1093J-1030D01*
G03Y32119I-291J274D01*
G02X253406I1093J1030D01*
G37*
G36*
G01X216595D02*
G03Y31570I291J-275D01*
G02X214409I-1093J-1030D01*
G03Y32119I-291J274D01*
G02X216595I1093J1030D01*
G37*
G36*
G01X179784D02*
G03Y31570I291J-275D01*
G02X177598I-1093J-1030D01*
G03Y32119I-291J274D01*
G02X179784I1093J1030D01*
G37*
G36*
G01X142973D02*
G03Y31570I291J-275D01*
G02X140787I-1093J-1030D01*
G03Y32119I-291J274D01*
G02X142973I1093J1030D01*
G37*
G36*
G01X1758406Y34262D02*
Y30367D01*
X1758397Y30283D01*
G02X1755384Y30452I-1502J169D01*
G01Y34252D01*
G02X1758406Y34262I1511J0D01*
G37*
G36*
G01X1523780Y27567D02*
G03X1523280Y27252I-106J-386D01*
G02X1522274Y28851I-1380J248D01*
G03X1522774Y29166I106J386D01*
G02X1523780Y27567I1380J-248D01*
G37*
G36*
G01X1509078Y30563D02*
G03X1508559Y30154I-120J-381D01*
G02X1507596Y32459I-3893J-273D01*
G03X1508253Y32540I301J264D01*
G02X1509078Y30563I1247J-640D01*
G37*
G36*
G01X1808288Y27703D02*
G03X1808887Y27629I332J224D01*
G02X1808661Y25800I935J-1044D01*
G03X1808062Y25874I-332J-224D01*
G02X1808288Y27703I-935J1044D01*
G37*
G36*
G01X1380536Y27426D02*
G03X1381078Y27181I381J121D01*
G02X1380306Y25472I564J-1284D01*
G03X1379764Y25717I-381J-121D01*
G02X1380536Y27426I-564J1284D01*
G37*
G36*
G01X673838Y36681D02*
X673832Y36754D01*
X671500Y39086D01*
Y47914D01*
X674086Y50500D01*
X681586D01*
X684586Y53500D01*
X688414D01*
X691000Y50914D01*
Y44414D01*
X691414Y44000D01*
X701914D01*
X703500Y42414D01*
Y39414D01*
X704500Y38414D01*
Y32086D01*
X703500Y31086D01*
Y25586D01*
X701414Y23500D01*
X689086D01*
X687586Y25000D01*
X680586D01*
X676000Y29586D01*
Y34586D01*
X675192Y35394D01*
X675119Y35400D01*
G02X673838Y36681I116J1397D01*
G37*
G36*
G01X14801Y25749D02*
G03X15397Y25723I310J253D01*
G02X15315Y23856I1003J-979D01*
G03X14719Y23882I-310J-253D01*
G02X14801Y25749I-1003J979D01*
G37*
G36*
G01X1767069Y22498D02*
X1763360D01*
G02Y25522I0J1512D01*
G01X1767069D01*
G02X1768580Y24020I-1J-1512D01*
G01Y23925D01*
X1768571Y23841D01*
G02X1767069Y22498I-1502J169D01*
G37*
G36*
G01X1550861Y22846D02*
G03X1550307I-277J-288D01*
G02Y24866I-973J1010D01*
G03X1550861I277J288D01*
G02X1552845Y24827I973J-1010D01*
G03X1553423I289J277D01*
G02Y22885I1011J-971D01*
G03X1552845I-289J-277D01*
G02X1550861Y22846I-1011J971D01*
G37*
G36*
G01X1748152Y21686D02*
X1743152D01*
G02Y24708I0J1511D01*
G01X1748153D01*
G02X1749664Y23207I0J-1512D01*
G01Y23112D01*
X1749654Y23028D01*
G02X1748152Y21686I-1502J169D01*
G37*
G36*
G01X655327Y21790D02*
G03X654773I-277J-288D01*
G02Y23810I-973J1010D01*
G03X655327I277J288D01*
G02Y21790I973J-1010D01*
G37*
G36*
G01X1738168Y20800D02*
X1733168D01*
G02Y23824I0J1512D01*
G01X1738169D01*
G02X1739680Y22322I-1J-1512D01*
G01Y22227D01*
X1739670Y22143D01*
G02X1738168Y20800I-1502J169D01*
G37*
G36*
G01X1532430Y23307D02*
G02Y24629I3693J661D01*
G02Y23307I3693J-661D01*
G37*
G36*
G01X1824343Y22637D02*
G03X1824913Y22612I297J267D01*
G02X1824827Y20650I957J-1025D01*
G03X1824257Y20675I-297J-267D01*
G02X1824343Y22637I-957J1025D01*
G37*
G36*
G01X691427Y19790D02*
G03X690873I-277J-288D01*
G02Y21810I-973J1010D01*
G03X691427I277J288D01*
G02Y19790I973J-1010D01*
G37*
G36*
G01X1760709Y18534D02*
X1757009Y18496D01*
G02X1756976Y21518I-16J1511D01*
G01X1760677Y21556D01*
G02X1762198Y20189I16J-1511D01*
G01X1762204Y20130D01*
X1762205Y20071D01*
G02Y20019I-1512J-26D01*
G01X1762204Y20017D01*
Y20007D01*
G02X1760709Y18534I-1511J38D01*
G37*
G36*
G01X373192Y18898D02*
G03X373437Y19395I-136J376D01*
G02X375251Y18501I1336J424D01*
G03X375006Y18004I136J-376D01*
G02X373192Y18898I-1336J-424D01*
G37*
G36*
G01X1240630Y18178D02*
Y25684D01*
X1242834D01*
Y18178D01*
G02X1240630I-1102J-1021D01*
G37*
G36*
G01X1233938D02*
Y25684D01*
X1236140D01*
Y18178D01*
G02X1233938I-1101J-1021D01*
G37*
G36*
G01X1217204Y18177D02*
Y25684D01*
X1219408D01*
Y18179D01*
G02X1217204Y18177I-1101J-1022D01*
G37*
G36*
G01X1210512D02*
Y25684D01*
X1212714D01*
Y18179D01*
G02X1210512Y18177I-1100J-1022D01*
G37*
G36*
G01X1203820Y18178D02*
Y25684D01*
X1206022D01*
Y18178D01*
G02X1203820I-1101J-1021D01*
G37*
G36*
G01X1197126D02*
Y25684D01*
X1199330D01*
Y18178D01*
G02X1197126I-1102J-1021D01*
G37*
G36*
G01X1180394Y18177D02*
Y25684D01*
X1182596D01*
Y18179D01*
G02X1180394Y18177I-1100J-1022D01*
G37*
G36*
G01X1173700D02*
Y25684D01*
X1175904D01*
Y18179D01*
G02X1173700Y18177I-1101J-1022D01*
G37*
G36*
G01X1167008Y18178D02*
Y25684D01*
X1169212D01*
Y18178D01*
G02X1167008I-1102J-1021D01*
G37*
G36*
G01X1160316D02*
Y25684D01*
X1162518D01*
Y18178D01*
G02X1160316I-1101J-1021D01*
G37*
G36*
G01X1143582Y18177D02*
Y25684D01*
X1145786D01*
Y18179D01*
G02X1143582Y18177I-1101J-1022D01*
G37*
G36*
G01X1136890D02*
Y25684D01*
X1139092D01*
Y18179D01*
G02X1136890Y18177I-1100J-1022D01*
G37*
G36*
G01X1130198Y18178D02*
Y25684D01*
X1132400D01*
Y18178D01*
G02X1130198I-1101J-1021D01*
G37*
G36*
G01X1123504D02*
Y25684D01*
X1125708D01*
Y18178D01*
G02X1123504I-1102J-1021D01*
G37*
G36*
G01X1106772Y18177D02*
Y25684D01*
X1108974D01*
Y18179D01*
G02X1106772Y18177I-1100J-1022D01*
G37*
G36*
G01X1100078D02*
Y25684D01*
X1102282D01*
Y18179D01*
G02X1100078Y18177I-1101J-1022D01*
G37*
G36*
G01X949490Y18179D02*
Y25684D01*
X951692D01*
Y18177D01*
G02X949490Y18179I-1102J-1020D01*
G37*
G36*
G01X942796Y18178D02*
Y25684D01*
X944998D01*
Y18178D01*
G02X942796I-1101J-1021D01*
G37*
G36*
G01X926064D02*
Y25684D01*
X928266D01*
Y18178D01*
G02X926064I-1101J-1021D01*
G37*
G36*
G01X919370D02*
Y25684D01*
X921574D01*
Y18178D01*
G02X919370I-1102J-1021D01*
G37*
G36*
G01X912678D02*
Y25684D01*
X914880D01*
Y18178D01*
G02X912678I-1101J-1021D01*
G37*
G36*
G01X905984D02*
Y25684D01*
X908188D01*
Y18178D01*
G02X905984I-1102J-1021D01*
G37*
G36*
G01X889252D02*
Y25684D01*
X891456D01*
Y18178D01*
G02X889252I-1102J-1021D01*
G37*
G36*
G01X882560D02*
Y25684D01*
X884762D01*
Y18178D01*
G02X882560I-1101J-1021D01*
G37*
G36*
G01X875866D02*
Y25684D01*
X878070D01*
Y18178D01*
G02X875866I-1102J-1021D01*
G37*
G36*
G01X869174D02*
Y25684D01*
X871376D01*
Y18178D01*
G02X869174I-1101J-1021D01*
G37*
G36*
G01X852442D02*
Y25684D01*
X854644D01*
Y18178D01*
G02X852442I-1101J-1021D01*
G37*
G36*
G01X845748D02*
Y25684D01*
X847952D01*
Y18178D01*
G02X845748I-1102J-1021D01*
G37*
G36*
G01X839056D02*
Y25684D01*
X841258D01*
Y18178D01*
G02X839056I-1101J-1021D01*
G37*
G36*
G01X832362D02*
Y25684D01*
X834566D01*
Y18178D01*
G02X832362I-1102J-1021D01*
G37*
G36*
G01X815630D02*
Y25684D01*
X817834D01*
Y18178D01*
G02X815630I-1102J-1021D01*
G37*
G36*
G01X808938D02*
Y25684D01*
X811140D01*
Y18178D01*
G02X808938I-1101J-1021D01*
G37*
G36*
G01X802244D02*
Y25684D01*
X804448D01*
Y18178D01*
G02X802244I-1102J-1021D01*
G37*
G36*
G01X795552D02*
Y25684D01*
X797754D01*
Y18178D01*
G02X795552I-1101J-1021D01*
G37*
G36*
G01X778820D02*
Y25684D01*
X781022D01*
Y18178D01*
G02X778820I-1101J-1021D01*
G37*
G36*
G01X772126D02*
Y25684D01*
X774330D01*
Y18178D01*
G02X772126I-1102J-1021D01*
G37*
G36*
G01X591022D02*
Y25684D01*
X593226D01*
Y18178D01*
G02X591022I-1102J-1021D01*
G37*
G36*
G01X584330D02*
Y25684D01*
X586532D01*
Y18178D01*
G02X584330I-1101J-1021D01*
G37*
G36*
G01X567596Y18177D02*
Y25684D01*
X569800D01*
Y18179D01*
G02X567596Y18177I-1101J-1022D01*
G37*
G36*
G01X554212Y18178D02*
Y25684D01*
X556414D01*
Y18178D01*
G02X554212I-1101J-1021D01*
G37*
G36*
G01X547518D02*
Y25684D01*
X549722D01*
Y18178D01*
G02X547518I-1102J-1021D01*
G37*
G36*
G01X530786Y18177D02*
Y25684D01*
X532988D01*
Y18179D01*
G02X530786Y18177I-1100J-1022D01*
G37*
G36*
G01X524092D02*
Y25684D01*
X526296D01*
Y18179D01*
G02X524092Y18177I-1101J-1022D01*
G37*
G36*
G01X517400Y18178D02*
Y25684D01*
X519604D01*
Y18178D01*
G02X517400I-1102J-1021D01*
G37*
G36*
G01X510708D02*
Y25684D01*
X512910D01*
Y18178D01*
G02X510708I-1101J-1021D01*
G37*
G36*
G01X493974Y18177D02*
Y25684D01*
X496178D01*
Y18179D01*
G02X493974Y18177I-1101J-1022D01*
G37*
G36*
G01X487282D02*
Y25684D01*
X489484D01*
Y18179D01*
G02X487282Y18177I-1100J-1022D01*
G37*
G36*
G01X480590Y18178D02*
Y25684D01*
X482792D01*
Y18178D01*
G02X480590I-1101J-1021D01*
G37*
G36*
G01X473896D02*
Y25684D01*
X476100D01*
Y18178D01*
G02X473896I-1102J-1021D01*
G37*
G36*
G01X457164Y18177D02*
Y25684D01*
X459366D01*
Y18179D01*
G02X457164Y18177I-1100J-1022D01*
G37*
G36*
G01X450470D02*
Y25684D01*
X452674D01*
Y18179D01*
G02X450470Y18177I-1101J-1022D01*
G37*
G36*
G01X299882Y18179D02*
Y25684D01*
X302084D01*
Y18177D01*
G02X299882Y18179I-1102J-1020D01*
G37*
G36*
G01X293188Y18178D02*
Y25684D01*
X295390D01*
Y18178D01*
G02X293188I-1101J-1021D01*
G37*
G36*
G01X276456D02*
Y25684D01*
X278658D01*
Y18178D01*
G02X276456I-1101J-1021D01*
G37*
G36*
G01X269762D02*
Y25684D01*
X271966D01*
Y18178D01*
G02X269762I-1102J-1021D01*
G37*
G36*
G01X263070D02*
Y25684D01*
X265272D01*
Y18178D01*
G02X263070I-1101J-1021D01*
G37*
G36*
G01X256376D02*
Y25684D01*
X258580D01*
Y18178D01*
G02X256376I-1102J-1021D01*
G37*
G36*
G01X239644D02*
Y25684D01*
X241848D01*
Y18178D01*
G02X239644I-1102J-1021D01*
G37*
G36*
G01X232952D02*
Y25684D01*
X235154D01*
Y18178D01*
G02X232952I-1101J-1021D01*
G37*
G36*
G01X226258D02*
Y25684D01*
X228462D01*
Y18178D01*
G02X226258I-1102J-1021D01*
G37*
G36*
G01X219566D02*
Y25684D01*
X221768D01*
Y18178D01*
G02X219566I-1101J-1021D01*
G37*
G36*
G01X202834D02*
Y25684D01*
X205036D01*
Y18178D01*
G02X202834I-1101J-1021D01*
G37*
G36*
G01X196140D02*
Y25684D01*
X198344D01*
Y18178D01*
G02X196140I-1102J-1021D01*
G37*
G36*
G01X189448D02*
Y25684D01*
X191650D01*
Y18178D01*
G02X189448I-1101J-1021D01*
G37*
G36*
G01X182754D02*
Y25684D01*
X184958D01*
Y18178D01*
G02X182754I-1102J-1021D01*
G37*
G36*
G01X166022D02*
Y25684D01*
X168226D01*
Y18178D01*
G02X166022I-1102J-1021D01*
G37*
G36*
G01X159330D02*
Y25684D01*
X161532D01*
Y18178D01*
G02X159330I-1101J-1021D01*
G37*
G36*
G01X152636D02*
Y25684D01*
X154840D01*
Y18178D01*
G02X152636I-1102J-1021D01*
G37*
G36*
G01X145944D02*
Y25684D01*
X148146D01*
Y18178D01*
G02X145944I-1101J-1021D01*
G37*
G36*
G01X129212D02*
Y25684D01*
X131414D01*
Y18178D01*
G02X129212I-1101J-1021D01*
G37*
G36*
G01X122518D02*
Y25684D01*
X124722D01*
Y18178D01*
G02X122518I-1102J-1021D01*
G37*
G36*
G01X1375911Y14137D02*
G03X1375375Y14134I-266J-299D01*
G02X1373408Y14211I-944J1036D01*
G03X1372860Y14245I-292J-273D01*
G02X1370835Y16459I-959J1156D01*
G03Y16741I-142J141D01*
G02X1370857Y18881I1065J1059D01*
G03X1370863Y19163I-139J144D01*
G02X1370888Y21263I1087J1037D01*
G03X1370887Y21547I-141J142D01*
G02X1373003Y21554I1054J1070D01*
G03X1373004Y21270I141J-142D01*
G02X1372993Y19119I-1054J-1070D01*
G03X1372987Y18837I139J-144D01*
G02X1372965Y16741I-1087J-1037D01*
G03Y16459I142J-141D01*
G02X1373053Y16363I-1062J-1062D01*
G03X1373598Y16297I307J256D01*
G02X1375362Y16218I833J-1127D01*
G03X1375898Y16221I266J299D01*
G02X1375911Y14137I944J-1036D01*
G37*
G36*
G01X1577048Y10994D02*
X1573048D01*
G02Y14018I0J1512D01*
G01X1577049D01*
G02X1578560Y12516I-1J-1512D01*
G01Y12421D01*
X1578550Y12337D01*
G02X1577048Y10994I-1502J169D01*
G37*
G36*
G01X1567498D02*
X1563498D01*
G02Y14018I0J1512D01*
G01X1567499D01*
G02X1569010Y12516I-1J-1512D01*
G01Y12421D01*
X1569000Y12337D01*
G02X1567498Y10994I-1502J169D01*
G37*
G36*
G01X1548698D02*
X1544698D01*
G02Y14018I0J1512D01*
G01X1548699D01*
G02X1550210Y12516I-1J-1512D01*
G01Y12421D01*
X1550200Y12337D01*
G02X1548698Y10994I-1502J169D01*
G37*
G36*
G01X1554148Y13818D02*
X1558148D01*
G02X1559660Y12316I0J-1512D01*
G01Y12221D01*
X1559650Y12137D01*
G02X1558148Y10794I-1502J169D01*
G01X1554148D01*
G02Y13818I0J1512D01*
G37*
G36*
G01X1230970Y13487D02*
G03Y12941I292J-273D01*
G02X1228778I-1096J-1027D01*
G03Y13487I-292J273D01*
G02X1230970I1096J1027D01*
G37*
G36*
G01X1194159D02*
G03Y12941I292J-273D01*
G02X1191967I-1096J-1027D01*
G03Y13487I-292J273D01*
G02X1194159I1096J1027D01*
G37*
G36*
G01X1157348D02*
G03Y12941I292J-273D01*
G02X1155156I-1096J-1027D01*
G03Y13487I-292J273D01*
G02X1157348I1096J1027D01*
G37*
G36*
G01X1120536D02*
G03Y12941I292J-273D01*
G02X1118344I-1096J-1027D01*
G03Y13487I-292J273D01*
G02X1120536I1096J1027D01*
G37*
G36*
G01X939828D02*
G03Y12941I292J-273D01*
G02X937636I-1096J-1027D01*
G03Y13487I-292J273D01*
G02X939828I1096J1027D01*
G37*
G36*
G01X903017D02*
G03Y12941I292J-273D01*
G02X900825I-1096J-1027D01*
G03Y13487I-292J273D01*
G02X903017I1096J1027D01*
G37*
G36*
G01X866206D02*
G03Y12941I292J-273D01*
G02X864014I-1096J-1027D01*
G03Y13487I-292J273D01*
G02X866206I1096J1027D01*
G37*
G36*
G01X829395D02*
G03Y12941I292J-273D01*
G02X827203I-1096J-1027D01*
G03Y13487I-292J273D01*
G02X829395I1096J1027D01*
G37*
G36*
G01X792584D02*
G03Y12941I292J-273D01*
G02X790392I-1096J-1027D01*
G03Y13487I-292J273D01*
G02X792584I1096J1027D01*
G37*
G36*
G01X581362D02*
G03Y12941I292J-273D01*
G02X579170I-1096J-1027D01*
G03Y13487I-292J273D01*
G02X581362I1096J1027D01*
G37*
G36*
G01X544551D02*
G03Y12941I292J-273D01*
G02X542359I-1096J-1027D01*
G03Y13487I-292J273D01*
G02X544551I1096J1027D01*
G37*
G36*
G01X507740D02*
G03Y12941I292J-273D01*
G02X505548I-1096J-1027D01*
G03Y13487I-292J273D01*
G02X507740I1096J1027D01*
G37*
G36*
G01X470928D02*
G03Y12941I292J-273D01*
G02X468736I-1096J-1027D01*
G03Y13487I-292J273D01*
G02X470928I1096J1027D01*
G37*
G36*
G01X290220D02*
G03Y12941I292J-273D01*
G02X288028I-1096J-1027D01*
G03Y13487I-292J273D01*
G02X290220I1096J1027D01*
G37*
G36*
G01X253409D02*
G03Y12941I292J-273D01*
G02X251217I-1096J-1027D01*
G03Y13487I-292J273D01*
G02X253409I1096J1027D01*
G37*
G36*
G01X216598D02*
G03Y12941I292J-273D01*
G02X214406I-1096J-1027D01*
G03Y13487I-292J273D01*
G02X216598I1096J1027D01*
G37*
G36*
G01X179787D02*
G03Y12941I292J-273D01*
G02X177595I-1096J-1027D01*
G03Y13487I-292J273D01*
G02X179787I1096J1027D01*
G37*
G36*
G01X142976D02*
G03Y12941I292J-273D01*
G02X140784I-1096J-1027D01*
G03Y13487I-292J273D01*
G02X142976I1096J1027D01*
G37*
G36*
G01X1225870Y13273D02*
G03Y12727I292J-273D01*
G02X1223678I-1096J-1027D01*
G03Y13273I-292J273D01*
G02X1225870I1096J1027D01*
G37*
G36*
G01X1189059D02*
G03Y12727I292J-273D01*
G02X1186867I-1096J-1027D01*
G03Y13273I-292J273D01*
G02X1189059I1096J1027D01*
G37*
G36*
G01X1152248D02*
G03Y12727I292J-273D01*
G02X1150056I-1096J-1027D01*
G03Y13273I-292J273D01*
G02X1152248I1096J1027D01*
G37*
G36*
G01X1115436D02*
G03Y12727I292J-273D01*
G02X1113244I-1096J-1027D01*
G03Y13273I-292J273D01*
G02X1115436I1096J1027D01*
G37*
G36*
G01X934728D02*
G03Y12727I292J-273D01*
G02X932536I-1096J-1027D01*
G03Y13273I-292J273D01*
G02X934728I1096J1027D01*
G37*
G36*
G01X897917D02*
G03Y12727I292J-273D01*
G02X895725I-1096J-1027D01*
G03Y13273I-292J273D01*
G02X897917I1096J1027D01*
G37*
G36*
G01X861106D02*
G03Y12727I292J-273D01*
G02X858914I-1096J-1027D01*
G03Y13273I-292J273D01*
G02X861106I1096J1027D01*
G37*
G36*
G01X824295D02*
G03Y12727I292J-273D01*
G02X822103I-1096J-1027D01*
G03Y13273I-292J273D01*
G02X824295I1096J1027D01*
G37*
G36*
G01X787484D02*
G03Y12727I292J-273D01*
G02X785292I-1096J-1027D01*
G03Y13273I-292J273D01*
G02X787484I1096J1027D01*
G37*
G36*
G01X576262D02*
G03Y12727I292J-273D01*
G02X574070I-1096J-1027D01*
G03Y13273I-292J273D01*
G02X576262I1096J1027D01*
G37*
G36*
G01X539451D02*
G03Y12727I292J-273D01*
G02X537259I-1096J-1027D01*
G03Y13273I-292J273D01*
G02X539451I1096J1027D01*
G37*
G36*
G01X502640D02*
G03Y12727I292J-273D01*
G02X500448I-1096J-1027D01*
G03Y13273I-292J273D01*
G02X502640I1096J1027D01*
G37*
G36*
G01X465828D02*
G03Y12727I292J-273D01*
G02X463636I-1096J-1027D01*
G03Y13273I-292J273D01*
G02X465828I1096J1027D01*
G37*
G36*
G01X285120D02*
G03Y12727I292J-273D01*
G02X282928I-1096J-1027D01*
G03Y13273I-292J273D01*
G02X285120I1096J1027D01*
G37*
G36*
G01X248309D02*
G03Y12727I292J-273D01*
G02X246117I-1096J-1027D01*
G03Y13273I-292J273D01*
G02X248309I1096J1027D01*
G37*
G36*
G01X211498D02*
G03Y12727I292J-273D01*
G02X209306I-1096J-1027D01*
G03Y13273I-292J273D01*
G02X211498I1096J1027D01*
G37*
G36*
G01X174687D02*
G03Y12727I292J-273D01*
G02X172495I-1096J-1027D01*
G03Y13273I-292J273D01*
G02X174687I1096J1027D01*
G37*
G36*
G01X137876D02*
G03Y12727I292J-273D01*
G02X135684I-1096J-1027D01*
G03Y13273I-292J273D01*
G02X137876I1096J1027D01*
G37*
G36*
G01X1484135Y10052D02*
X1479135D01*
G02Y13074I0J1511D01*
G01X1484136D01*
G02X1485646Y11573I-1J-1511D01*
G01Y11478D01*
X1485637Y11394D01*
G02X1484135Y10052I-1502J169D01*
G37*
G36*
G01X1465237D02*
X1460237D01*
G02Y13074I0J1511D01*
G01X1465238D01*
G02X1466748Y11573I-1J-1511D01*
G01Y11478D01*
X1466739Y11394D01*
G02X1465237Y10052I-1502J169D01*
G37*
G36*
G01X1441340Y13074D02*
X1446341D01*
G02X1447852Y11573I0J-1512D01*
G01Y11478D01*
X1447842Y11394D01*
G02X1446340Y10052I-1502J169D01*
G01X1441340D01*
G02Y13074I1J1511D01*
G37*
G36*
G01X1427442Y10052D02*
X1422442D01*
G02Y13074I0J1511D01*
G01X1427443D01*
G02X1428954Y11573I0J-1512D01*
G01Y11478D01*
X1428944Y11394D01*
G02X1427442Y10052I-1502J169D01*
G37*
G36*
G01X1728678Y9870D02*
X1723678D01*
G02Y12892I0J1511D01*
G01X1728679D01*
G02X1730190Y11391I0J-1512D01*
G01Y11296D01*
X1730180Y11212D01*
G02X1728678Y9870I-1502J169D01*
G37*
G36*
G01X1681428D02*
X1676428D01*
G02Y12892I0J1511D01*
G01X1681429D01*
G02X1682940Y11391I0J-1512D01*
G01Y11296D01*
X1682930Y11212D01*
G02X1681428Y9870I-1502J169D01*
G37*
G36*
G01X1605898Y9844D02*
X1600898D01*
G02Y12866I0J1511D01*
G01X1605899D01*
G02X1607410Y11365I0J-1512D01*
G01Y11270D01*
X1607400Y11186D01*
G02X1605898Y9844I-1502J169D01*
G37*
G36*
G01X1586998D02*
X1581998D01*
G02Y12866I0J1511D01*
G01X1586999D01*
G02X1588510Y11365I0J-1512D01*
G01Y11270D01*
X1588500Y11186D01*
G02X1586998Y9844I-1502J169D01*
G37*
G36*
G01X1700200Y9806D02*
X1695200D01*
G02Y12828I0J1511D01*
G01X1700201D01*
G02X1701712Y11327I0J-1512D01*
G01Y11232D01*
X1701702Y11148D01*
G02X1700200Y9806I-1502J170D01*
G37*
G36*
G01X1709771Y9750D02*
X1704771D01*
G02Y12772I0J1511D01*
G01X1709772D01*
G02X1711282Y11271I-1J-1511D01*
G01Y11176D01*
X1711273Y11092D01*
G02X1709771Y9750I-1502J169D01*
G37*
G36*
G01X1719297Y9668D02*
X1714297D01*
G02Y12692I0J1512D01*
G01X1719298D01*
G02X1720808Y11190I-1J-1512D01*
G01Y11095D01*
X1720799Y11011D01*
G02X1719297Y9668I-1502J169D01*
G37*
G36*
G01X1643865Y9594D02*
X1638865D01*
G02Y12616I0J1511D01*
G01X1643866D01*
G02X1645376Y11115I-1J-1511D01*
G01Y11020D01*
X1645367Y10936D01*
G02X1643865Y9594I-1502J169D01*
G37*
G36*
G01X1690948Y9214D02*
X1685948D01*
G02Y12236I0J1511D01*
G01X1690949D01*
G02X1692460Y10735I0J-1512D01*
G01Y10640D01*
X1692450Y10556D01*
G02X1690948Y9214I-1502J169D01*
G37*
G36*
G01X1302990Y9175D02*
G03X1302368I-311J-252D01*
G02X1300259Y11020I-1089J883D01*
G03X1300242Y11587I-291J275D01*
G02X1300225Y13618I958J1024D01*
G03Y14192I-278J287D01*
G02X1302289Y16083I976J1007D01*
G03X1302911I311J252D01*
G02X1305089I1089J-883D01*
G03X1305711I311J252D01*
G02X1307775Y14192I1088J-884D01*
G03Y13618I278J-287D01*
G02X1307820Y11648I-975J-1008D01*
G03X1307837Y11081I291J-275D01*
G02X1305790Y9175I-957J-1024D01*
G03X1305168I-311J-252D01*
G02X1302990I-1089J883D01*
G37*
G36*
G01X1663884Y10164D02*
Y10069D01*
X1663875Y9985D01*
G02X1662342Y8643I-1502J169D01*
G01X1657338Y8747D01*
G02X1657400Y11769I31J1511D01*
G01X1662403Y11665D01*
G02X1663884Y10164I-30J-1511D01*
G37*
G36*
G01X1401627Y8990D02*
G03X1401073I-277J-288D01*
G02Y11010I-973J1010D01*
G03X1401627I277J288D01*
G02X1403573I973J-1010D01*
G03X1404127I277J288D01*
G02Y8990I973J-1010D01*
G03X1403573I-277J-288D01*
G02X1401627I-973J1010D01*
G37*
G36*
G01X665011Y9117D02*
G03X664389I-311J-252D01*
G02Y10883I-1089J883D01*
G03X665011I311J252D01*
G02Y9117I1089J-883D01*
G37*
G36*
G01X82642Y10684D02*
G03X82629Y10122I278J-288D01*
G02X80364Y8516I-1019J-963D01*
G03X79806Y8677I-355J-184D01*
G02X78085Y10857I-710J1209D01*
G03X78089Y11406I-289J277D01*
G02X78229Y13446I1027J954D01*
G03X78285Y14009I-253J309D01*
G02X80652Y15467I1087J886D01*
G03X81238Y15297I365J164D01*
G02X82894Y13038I775J-1168D01*
G03X82817Y12497I251J-312D01*
G02X82642Y10684I-1148J-804D01*
G37*
G36*
G01X1259473Y10130D02*
G03X1260036Y10118I288J278D01*
G02X1259991Y8127I964J-1018D01*
G03X1259428Y8139I-288J-278D01*
G02X1259473Y10130I-964J1018D01*
G37*
G36*
G01X1754065Y10273D02*
G03X1754640Y10183I330J226D01*
G02X1754343Y8284I860J-1107D01*
G03X1753768Y8374I-330J-226D01*
G02X1754065Y10273I-860J1107D01*
G37*
G36*
G01X1591848Y12918D02*
X1595849D01*
G02X1597360Y11416I-1J-1512D01*
G01Y11321D01*
X1597350Y11237D01*
G02X1595848Y9894I-1502J169D01*
G01X1593957D01*
G03X1593623Y9274I0J-400D01*
G02X1591378Y9402I-1170J-772D01*
G03X1591234Y10025I-306J257D01*
G02X1591848Y12918I614J1381D01*
G37*
G36*
G01X1436025Y6244D02*
X1431025D01*
G02Y9268I0J1512D01*
G01X1436026D01*
G02X1437536Y7766I-1J-1512D01*
G01Y7671D01*
X1437527Y7587D01*
G02X1436025Y6244I-1502J169D01*
G37*
G36*
G01X1493770Y5398D02*
X1488770D01*
G02Y8420I0J1511D01*
G01X1493771D01*
G02X1495282Y6919I0J-1512D01*
G01Y6824D01*
X1495272Y6740D01*
G02X1493770Y5398I-1502J169D01*
G37*
G36*
G01X1634148Y5314D02*
X1629148D01*
G02Y8336I0J1511D01*
G01X1634149D01*
G02X1635660Y6835I0J-1512D01*
G01Y6740D01*
X1635650Y6656D01*
G02X1634148Y5314I-1502J169D01*
G37*
G36*
G01X1653748Y4814D02*
X1648748D01*
G02Y7836I0J1511D01*
G01X1653749D01*
G02X1655260Y6335I0J-1512D01*
G01Y6240D01*
X1655250Y6156D01*
G02X1653748Y4814I-1502J169D01*
G37*
G36*
G01X1671979Y4724D02*
X1666979D01*
G02Y7748I0J1512D01*
G01X1671979D01*
G02X1673490Y6246I-1J-1512D01*
G01Y6151D01*
X1673481Y6067D01*
G02X1671979Y4724I-1502J168D01*
G37*
G36*
G01X1368378Y4805D02*
G03X1367800I-289J-277D01*
G02Y6747I-1011J971D01*
G03X1368378I289J277D01*
G02Y4805I1011J-971D01*
G37*
G36*
G01X1474388Y4078D02*
X1469388D01*
G02Y7100I0J1511D01*
G01X1474389D01*
G02X1475900Y5599I0J-1512D01*
G01Y5504D01*
X1475890Y5420D01*
G02X1474388Y4078I-1502J169D01*
G37*
G36*
G01X1454991D02*
X1449991D01*
G02Y7100I0J1511D01*
G01X1454992D01*
G02X1456502Y5599I-1J-1511D01*
G01Y5504D01*
X1456493Y5420D01*
G02X1454991Y4078I-1502J169D01*
G37*
G36*
G01X1614833Y3914D02*
X1609833D01*
G02Y6936I0J1511D01*
G01X1614834D01*
G02X1616344Y5435I-1J-1511D01*
G01Y5340D01*
X1616335Y5256D01*
G02X1614833Y3914I-1502J169D01*
G37*
G36*
G01X665442Y3406D02*
G03X664944Y3216I-143J-374D01*
G02X664199Y5171I-1245J645D01*
G03X664697Y5361I143J374D01*
G02X665442Y3406I1245J-645D01*
G37*
G36*
G01X115022Y5064D02*
G03X115000Y4483I263J-301D01*
G02X113078Y4556I-1000J-983D01*
G03X113100Y5137I-263J301D01*
G02X115022Y5064I1000J983D01*
G37*
G36*
G01X1381205Y4584D02*
G03X1381223Y3999I282J-284D01*
G02X1379314Y3941I-923J-1055D01*
G03X1379296Y4526I-282J284D01*
G02X1381205Y4584I923J1055D01*
G37*
G36*
G01X1328965Y4380D02*
G03X1329273Y3898I389J-91D01*
G02X1327952Y1579I-286J-1373D01*
G03X1327378Y1596I-295J-270D01*
G02X1325311Y1717I-978J1004D01*
G03X1324689I-311J-252D01*
G02X1322511I-1089J883D01*
G03X1321889I-311J-252D01*
G02X1319672Y1768I-1089J883D01*
G03X1319028I-322J-238D01*
G02X1316783Y1753I-1128J832D01*
G03X1316140Y1745I-319J-242D01*
G02X1313907Y1694I-1136J822D01*
G03X1313306Y1724I-314J-248D01*
G02X1311211Y1817I-1006J976D01*
G03X1310589I-311J-252D01*
G02X1308411I-1089J883D01*
G03X1307789I-311J-252D01*
G02X1305611I-1089J883D01*
G03X1304989I-311J-252D01*
G02X1302811I-1089J883D01*
G03X1302189I-311J-252D01*
G02X1300664Y4033I-1089J883D01*
G03X1300931Y4499I-124J380D01*
G02X1303389Y5683I1369J301D01*
G03X1304011I311J252D01*
G02X1306189I1089J-883D01*
G03X1306811I311J252D01*
G02X1308989I1089J-883D01*
G03X1309611I311J252D01*
G02X1311789I1089J-883D01*
G03X1312411I311J252D01*
G02X1314621Y5642I1089J-883D01*
G03X1315242Y5620I319J241D01*
G02X1317428Y5532I1058J-920D01*
G03X1318072I322J238D01*
G02X1320289Y5583I1128J-832D01*
G03X1320911I311J252D01*
G02X1323089I1089J-883D01*
G03X1323711I311J252D01*
G02X1325889I1089J-883D01*
G03X1326511I311J252D01*
G02X1328965Y4380I1089J-883D01*
G37*
G36*
G01X1825803Y2785D02*
G03X1825972Y2243I354J-187D01*
G02X1824085Y1656I-648J-1243D01*
G03X1823916Y2198I-354J187D01*
G02X1825803Y2785I648J1243D01*
G37*
G36*
G01X752985Y1288D02*
G03X753584Y1266I309J254D01*
G02X753515Y-588I1016J-966D01*
G03X752916Y-566I-309J-254D01*
G02X752985Y1288I-1016J966D01*
G37*
G36*
G01X1600129Y-1610D02*
G03X1599575I-277J-288D01*
G02Y410I-973J1010D01*
G03X1600129I277J288D01*
G02Y-1610I973J-1010D01*
G37*
G36*
G01X63074Y-533D02*
G03X63194Y-1141I308J-255D01*
G02X61456Y-1484I-659J-1238D01*
G03X61336Y-876I-308J255D01*
G02X63074Y-533I659J1238D01*
G37*
G36*
G01X1381410Y-3782D02*
G03X1381885Y-4168I400J7D01*
G02X1380749Y-5568I266J-1377D01*
G03X1380274Y-5182I-400J-7D01*
G02X1381410Y-3782I-266J1377D01*
G37*
G36*
G01X718771Y-5838D02*
G03X718316Y-6193I-57J-396D01*
G02X717125Y-4661I-1395J145D01*
G03X717580Y-4306I57J396D01*
G02X718771Y-5838I1395J-145D01*
G37*
G36*
G01X1225862Y-5436D02*
G03X1225868Y-5993I290J-275D01*
G02X1223712Y-6015I-1067J-1057D01*
G03X1223706Y-5458I-290J275D01*
G02X1225862Y-5436I1067J1057D01*
G37*
G36*
G01X1189051D02*
G03X1189057Y-5993I290J-275D01*
G02X1186901Y-6015I-1067J-1057D01*
G03X1186895Y-5458I-290J275D01*
G02X1189051Y-5436I1067J1057D01*
G37*
G36*
G01X1152240D02*
G03X1152246Y-5993I290J-275D01*
G02X1150090Y-6015I-1067J-1057D01*
G03X1150084Y-5458I-290J275D01*
G02X1152240Y-5436I1067J1057D01*
G37*
G36*
G01X1115428D02*
G03X1115434Y-5993I290J-275D01*
G02X1113278Y-6015I-1067J-1057D01*
G03X1113272Y-5458I-290J275D01*
G02X1115428Y-5436I1067J1057D01*
G37*
G36*
G01X934720D02*
G03X934726Y-5993I290J-275D01*
G02X932570Y-6015I-1067J-1057D01*
G03X932564Y-5458I-290J275D01*
G02X934720Y-5436I1067J1057D01*
G37*
G36*
G01X897909D02*
G03X897915Y-5993I290J-275D01*
G02X895759Y-6015I-1067J-1057D01*
G03X895753Y-5458I-290J275D01*
G02X897909Y-5436I1067J1057D01*
G37*
G36*
G01X861098D02*
G03X861104Y-5993I290J-275D01*
G02X858948Y-6015I-1067J-1057D01*
G03X858942Y-5458I-290J275D01*
G02X861098Y-5436I1067J1057D01*
G37*
G36*
G01X824287D02*
G03X824293Y-5993I290J-275D01*
G02X822137Y-6015I-1067J-1057D01*
G03X822131Y-5458I-290J275D01*
G02X824287Y-5436I1067J1057D01*
G37*
G36*
G01X787476D02*
G03X787482Y-5993I290J-275D01*
G02X785326Y-6015I-1067J-1057D01*
G03X785320Y-5458I-290J275D01*
G02X787476Y-5436I1067J1057D01*
G37*
G36*
G01X576254D02*
G03X576260Y-5993I290J-275D01*
G02X574104Y-6015I-1067J-1057D01*
G03X574098Y-5458I-290J275D01*
G02X576254Y-5436I1067J1057D01*
G37*
G36*
G01X539443D02*
G03X539449Y-5993I290J-275D01*
G02X537293Y-6015I-1067J-1057D01*
G03X537287Y-5458I-290J275D01*
G02X539443Y-5436I1067J1057D01*
G37*
G36*
G01X502632D02*
G03X502638Y-5993I290J-275D01*
G02X500482Y-6015I-1067J-1057D01*
G03X500476Y-5458I-290J275D01*
G02X502632Y-5436I1067J1057D01*
G37*
G36*
G01X465820D02*
G03X465826Y-5993I290J-275D01*
G02X463670Y-6015I-1067J-1057D01*
G03X463664Y-5458I-290J275D01*
G02X465820Y-5436I1067J1057D01*
G37*
G36*
G01X285112D02*
G03X285118Y-5993I290J-275D01*
G02X282962Y-6015I-1067J-1057D01*
G03X282956Y-5458I-290J275D01*
G02X285112Y-5436I1067J1057D01*
G37*
G36*
G01X248301D02*
G03X248307Y-5993I290J-275D01*
G02X246151Y-6015I-1067J-1057D01*
G03X246145Y-5458I-290J275D01*
G02X248301Y-5436I1067J1057D01*
G37*
G36*
G01X211490D02*
G03X211496Y-5993I290J-275D01*
G02X209340Y-6015I-1067J-1057D01*
G03X209334Y-5458I-290J275D01*
G02X211490Y-5436I1067J1057D01*
G37*
G36*
G01X174679D02*
G03X174685Y-5993I290J-275D01*
G02X172529Y-6015I-1067J-1057D01*
G03X172523Y-5458I-290J275D01*
G02X174679Y-5436I1067J1057D01*
G37*
G36*
G01X137868D02*
G03X137874Y-5993I290J-275D01*
G02X135718Y-6015I-1067J-1057D01*
G03X135712Y-5458I-290J275D01*
G02X137868Y-5436I1067J1057D01*
G37*
G36*
G01X1230967Y-5681D02*
G03Y-6230I291J-274D01*
G02X1228781I-1093J-1030D01*
G03Y-5681I-291J274D01*
G02X1230967I1093J1030D01*
G37*
G36*
G01X1194156D02*
G03Y-6230I291J-274D01*
G02X1191970I-1093J-1030D01*
G03Y-5681I-291J274D01*
G02X1194156I1093J1030D01*
G37*
G36*
G01X1157345D02*
G03Y-6230I291J-274D01*
G02X1155159I-1093J-1030D01*
G03Y-5681I-291J274D01*
G02X1157345I1093J1030D01*
G37*
G36*
G01X1120533D02*
G03Y-6230I291J-274D01*
G02X1118347I-1093J-1030D01*
G03Y-5681I-291J274D01*
G02X1120533I1093J1030D01*
G37*
G36*
G01X939825D02*
G03Y-6230I291J-274D01*
G02X937639I-1093J-1030D01*
G03Y-5681I-291J274D01*
G02X939825I1093J1030D01*
G37*
G36*
G01X903014D02*
G03Y-6230I291J-274D01*
G02X900828I-1093J-1030D01*
G03Y-5681I-291J274D01*
G02X903014I1093J1030D01*
G37*
G36*
G01X866203D02*
G03Y-6230I291J-274D01*
G02X864017I-1093J-1030D01*
G03Y-5681I-291J274D01*
G02X866203I1093J1030D01*
G37*
G36*
G01X829392D02*
G03Y-6230I291J-274D01*
G02X827206I-1093J-1030D01*
G03Y-5681I-291J274D01*
G02X829392I1093J1030D01*
G37*
G36*
G01X792581D02*
G03Y-6230I291J-274D01*
G02X790395I-1093J-1030D01*
G03Y-5681I-291J274D01*
G02X792581I1093J1030D01*
G37*
G36*
G01X581359D02*
G03Y-6230I291J-274D01*
G02X579173I-1093J-1030D01*
G03Y-5681I-291J274D01*
G02X581359I1093J1030D01*
G37*
G36*
G01X544548D02*
G03Y-6230I291J-274D01*
G02X542362I-1093J-1030D01*
G03Y-5681I-291J274D01*
G02X544548I1093J1030D01*
G37*
G36*
G01X507737D02*
G03Y-6230I291J-274D01*
G02X505551I-1093J-1030D01*
G03Y-5681I-291J274D01*
G02X507737I1093J1030D01*
G37*
G36*
G01X470925D02*
G03Y-6230I291J-274D01*
G02X468739I-1093J-1030D01*
G03Y-5681I-291J274D01*
G02X470925I1093J1030D01*
G37*
G36*
G01X290217D02*
G03Y-6230I291J-274D01*
G02X288031I-1093J-1030D01*
G03Y-5681I-291J274D01*
G02X290217I1093J1030D01*
G37*
G36*
G01X253406D02*
G03Y-6230I291J-274D01*
G02X251220I-1093J-1030D01*
G03Y-5681I-291J274D01*
G02X253406I1093J1030D01*
G37*
G36*
G01X216595D02*
G03Y-6230I291J-274D01*
G02X214409I-1093J-1030D01*
G03Y-5681I-291J274D01*
G02X216595I1093J1030D01*
G37*
G36*
G01X179784D02*
G03Y-6230I291J-274D01*
G02X177598I-1093J-1030D01*
G03Y-5681I-291J274D01*
G02X179784I1093J1030D01*
G37*
G36*
G01X142973D02*
G03Y-6230I291J-274D01*
G02X140787I-1093J-1030D01*
G03Y-5681I-291J274D01*
G02X142973I1093J1030D01*
G37*
G36*
G01X647971Y-10511D02*
G03Y-11089I277J-289D01*
G02X646029I-971J-1011D01*
G03Y-10511I-277J289D01*
G02X646208Y-8343I971J1011D01*
G03X646297Y-7766I-226J330D01*
G02X648192Y-8057I1103J866D01*
G03X648103Y-8634I226J-330D01*
G02X647971Y-10511I-1103J-866D01*
G37*
G36*
G01X64936Y-12238D02*
G03X65464Y-12420I357J180D01*
G02X64808Y-14317I597J-1268D01*
G03X64280Y-14135I-357J-180D01*
G02X64936Y-12238I-597J1268D01*
G37*
G36*
G01X730372Y-16258D02*
G03X729818Y-16331I-240J-320D01*
G02X727466Y-16100I-1102J866D01*
G03X726936Y-15921I-356J-181D01*
G02X725354Y-15668I-609J1263D01*
G03X724800I-277J-288D01*
G02Y-13648I-973J1010D01*
G03X725354I277J288D01*
G02X726891Y-13374I973J-1010D01*
G03X727448Y-12954I161J366D01*
G02X729716Y-13856I1389J191D01*
G03X729689Y-14455I250J-311D01*
G02X729693Y-14460I-1084J-871D01*
G03X730004Y-14418I139J144D01*
G02X730372Y-16258I1206J-716D01*
G37*
G36*
G01X1585527Y-17110D02*
G03X1584973I-277J-288D01*
G02Y-15090I-973J1010D01*
G03X1585527I277J288D01*
G02Y-17110I973J-1010D01*
G37*
G36*
G01X41289Y-16225D02*
G03X41102Y-15669I-351J191D01*
G02X42908Y-15061I575J1279D01*
G03X43095Y-15617I351J-191D01*
G02X41289Y-16225I-575J-1279D01*
G37*
G36*
G01X1375736Y-17802D02*
G03X1375155Y-17824I-280J-285D01*
G02X1373099Y-17881I-1054J924D01*
G03X1372569Y-17844I-286J-280D01*
G02X1370533Y-15654I-916J1190D01*
G03X1370522Y-15110I-299J266D01*
G02X1370449Y-13110I1083J1041D01*
G03X1370447Y-12598I-308J255D01*
G02X1370460Y-10653I1151J965D01*
G03X1370467Y-10139I-303J261D01*
G02X1372770Y-10171I1165J948D01*
G03X1372763Y-10685I303J-261D01*
G02X1372754Y-12592I-1165J-948D01*
G03X1372756Y-13104I308J-255D01*
G02X1372725Y-15069I-1151J-965D01*
G03X1372736Y-15613I299J-266D01*
G02X1372788Y-15670I-1083J-1041D01*
G03X1373314Y-15739I302J262D01*
G02X1375083Y-15900I786J-1161D01*
G03X1375664Y-15878I280J285D01*
G02X1375736Y-17802I1055J-924D01*
G37*
G36*
G01X1316783Y-17747D02*
G03X1316140Y-17755I-319J-242D01*
G02X1313907Y-17806I-1136J822D01*
G03X1313306Y-17776I-314J-248D01*
G02X1311211Y-17683I-1006J976D01*
G03X1310589I-311J-252D01*
G02X1308411I-1089J883D01*
G03X1307789I-311J-252D01*
G02X1306264Y-15467I-1089J883D01*
G03X1306531Y-15001I-124J380D01*
G02X1308989Y-13817I1369J301D01*
G03X1309611I311J252D01*
G02X1311789I1089J-883D01*
G03X1312411I311J252D01*
G02X1314621Y-13858I1089J-883D01*
G03X1315242Y-13880I319J241D01*
G02X1317428Y-13968I1058J-920D01*
G03X1318072I322J238D01*
G02X1320289Y-13917I1128J-832D01*
G03X1320911I311J252D01*
G02X1321879Y-13403I1089J-883D01*
G03X1322234Y-12915I-35J398D01*
G02X1324577Y-11595I1366J315D01*
G03X1325110Y-11617I279J287D01*
G02X1327089Y-11817I890J-1083D01*
G03X1327711I311J252D01*
G02X1329236Y-14033I1089J-883D01*
G03X1328969Y-14499I124J-380D01*
G02X1328036Y-16133I-1369J-302D01*
G03X1327769Y-16599I124J-380D01*
G02X1325311Y-17783I-1369J-301D01*
G03X1324689I-311J-252D01*
G02X1322511I-1089J883D01*
G03X1321889I-311J-252D01*
G02X1319672Y-17732I-1089J883D01*
G03X1319028I-322J-238D01*
G02X1316783Y-17747I-1128J832D01*
G37*
G36*
G01X1606531Y-18356D02*
G03X1605977I-277J-288D01*
G02Y-16336I-973J1010D01*
G03X1606531I277J288D01*
G02X1608477I973J-1010D01*
G03X1609031I277J288D01*
G02Y-18356I973J-1010D01*
G03X1608477I-277J-288D01*
G02X1606531I-973J1010D01*
G37*
G36*
G01X1596531D02*
G03X1595977I-277J-288D01*
G02Y-16336I-973J1010D01*
G03X1596531I277J288D01*
G02X1598477I973J-1010D01*
G03X1599031I277J288D01*
G02Y-18356I973J-1010D01*
G03X1598477I-277J-288D01*
G02X1596531I-973J1010D01*
G37*
G36*
G01X661185Y-16750D02*
G03X661784Y-16839I338J214D01*
G02X661515Y-18650I916J-1062D01*
G03X660916Y-18561I-338J-214D01*
G02X661185Y-16750I-916J1062D01*
G37*
G36*
G01X1300366Y-16666D02*
G03X1300430Y-17281I284J-281D01*
G02X1298511Y-17399I-881J-1338D01*
G03X1298500Y-16780I-259J305D01*
G02X1300366Y-16666I869J1100D01*
G37*
G36*
G01X21111Y-18129D02*
G03X21683Y-18241I339J213D01*
G02X21312Y-20127I816J-1140D01*
G03X20740Y-20015I-339J-213D01*
G02X21111Y-18129I-816J1140D01*
G37*
G36*
G01X709720Y-17986D02*
G03X710115Y-18437I397J-51D01*
G02X708717Y-19659I-8J-1402D01*
G03X708322Y-19208I-397J51D01*
G02X709720Y-17986I8J1402D01*
G37*
G36*
G01X1902168Y-18425D02*
G02X1901892Y-20014I992J-991D01*
G03X1901248Y-19902I-361J-171D01*
G02X1901524Y-18313I-992J991D01*
G03X1902168Y-18425I361J171D01*
G37*
G36*
G01X714334Y-17027D02*
G02X712514Y-17832I-510J-1306D01*
G03X712286Y-17317I-373J143D01*
G02X711398Y-16115I510J1306D01*
G03X710836Y-15780I-399J-30D01*
G02X709291Y-13490I-573J1280D01*
G03X709305Y-12928I-277J288D01*
G02X711299Y-12978I1022J960D01*
G03X711285Y-13540I277J-288D01*
G02X711661Y-14396I-1022J-960D01*
G03X712223Y-14731I399J30D01*
G02X714106Y-16512I573J-1280D01*
G03X714334Y-17027I373J-143D01*
G37*
G36*
G01X1674935Y-17561D02*
G02X1674904Y-16078I-1435J712D01*
G03X1675602Y-16084I351J193D01*
G02X1675632Y-17526I1217J-696D01*
G03X1674935Y-17561I-339J-213D01*
G37*
G36*
G01X1280343Y-15495D02*
G02X1280321Y-14060I-1443J696D01*
G03X1281025Y-14068I354J186D01*
G02X1283184Y-13700I1227J-679D01*
G03X1283763Y-13650I266J299D01*
G02X1283927Y-15571I1096J-874D01*
G03X1283348Y-15621I-266J-299D01*
G02X1281047Y-15464I-1096J874D01*
G03X1280343Y-15495I-344J-205D01*
G37*
G36*
G01X1498611Y-11287D02*
G02X1497445Y-12317I189J-1389D01*
G03X1496979Y-11822I-387J103D01*
G02X1498178Y-10763I-319J1570D01*
G03X1498611Y-11287I379J-127D01*
G37*
G36*
G01X90170Y-10745D02*
G02X88916Y-9191I-1393J159D01*
G03X89311Y-8609I40J398D01*
G02X90822Y-10483I5373J2786D01*
G03X90170Y-10745I-255J-308D01*
G37*
G36*
G01X362540Y-10500D02*
G02Y-9072I-1322J714D01*
G03X363243I352J190D01*
G02Y-10500I1322J-714D01*
G03X362540I-351J-190D01*
G37*
G36*
G01X1012148D02*
G02Y-9072I-1322J714D01*
G03X1012851I352J190D01*
G02Y-10500I1322J-714D01*
G03X1012148I-352J-190D01*
G37*
G36*
G01X735454Y-7525D02*
G02X734182Y-7734I-434J-1333D01*
G03X734066Y-7033I-239J320D01*
G02X733101Y-5790I434J1333D01*
G03X732588Y-5432I-399J-25D01*
G02X731232Y-3064I-397J1345D01*
G03X731260Y-2509I-273J292D01*
G02X733327Y-616I1056J922D01*
G03X733905I289J277D01*
G02Y-2558I1011J-971D01*
G03X733327I-289J-277D01*
G02X733275Y-2610I-1017J965D01*
G03X733247Y-3165I273J-292D01*
G02X733590Y-3997I-1056J-922D01*
G03X734103Y-4355I399J25D01*
G02X735338Y-6824I397J-1345D01*
G03X735454Y-7525I239J-320D01*
G37*
G36*
G01X1606667Y-4377D02*
G02Y-2823I-1167J777D01*
G03X1607333I333J222D01*
G02Y-4377I1167J-777D01*
G03X1606667I-333J-222D01*
G37*
G36*
G01X1837406Y-2254D02*
G02X1836404Y-3467I394J-1346D01*
G03X1835894Y-3046I-398J37D01*
G02X1836896Y-1833I-394J1346D01*
G03X1837406Y-2254I398J-37D01*
G37*
G36*
G01X624333Y-2565D02*
G02X623044Y-1599I-1333J-435D01*
G03X623437Y-1075I13J400D01*
G02X624726Y-2041I1333J435D01*
G03X624333Y-2565I-13J-400D01*
G37*
G36*
G01X362540Y-2572D02*
G02Y-1144I-1322J714D01*
G03X363243I352J190D01*
G02Y-2572I1322J-714D01*
G03X362540I-351J-190D01*
G37*
G36*
G01X1012148D02*
G02Y-1144I-1322J714D01*
G03X1012851I352J190D01*
G02Y-2572I1322J-714D01*
G03X1012148I-352J-190D01*
G37*
G36*
G01X120981Y7947D02*
X120882Y7889D01*
Y7574D01*
X121374D01*
Y472D01*
X119172D01*
Y7574D01*
X119664D01*
Y7889D01*
X119565Y7947D01*
G02X120981I708J1210D01*
G37*
G36*
G01X311790Y7942D02*
X311700Y7882D01*
Y7574D01*
X312122D01*
Y472D01*
X309920D01*
Y7574D01*
X310342D01*
Y7882D01*
X310252Y7942D01*
G02X311790I769J1172D01*
G37*
G36*
G01X325176D02*
X325086Y7882D01*
Y7574D01*
X325508D01*
Y472D01*
X323306D01*
Y7574D01*
X323728D01*
Y7882D01*
X323638Y7942D01*
G02X325176I769J1172D01*
G37*
G36*
G01X328523D02*
X328433Y7882D01*
Y7574D01*
X328856D01*
Y472D01*
X326652D01*
Y7574D01*
X327075D01*
Y7882D01*
X326985Y7942D01*
G02X328523I769J1172D01*
G37*
G36*
G01X335215D02*
X335125Y7882D01*
Y7574D01*
X335548D01*
Y472D01*
X333346D01*
Y7574D01*
X333767D01*
Y7882D01*
X333677Y7942D01*
G02X335215I769J1172D01*
G37*
G36*
G01X338562D02*
X338472Y7882D01*
Y7574D01*
X338894D01*
Y472D01*
X336692D01*
Y7574D01*
X337114D01*
Y7882D01*
X337024Y7942D01*
G02X338562I769J1172D01*
G37*
G36*
G01X345244Y7943D02*
X345152Y7884D01*
Y7574D01*
X345588D01*
Y472D01*
X343384D01*
Y7574D01*
X343820D01*
Y7884D01*
X343728Y7943D01*
G02X345244I758J1179D01*
G37*
G36*
G01X348591D02*
X348499Y7884D01*
Y7574D01*
X348934D01*
Y472D01*
X346732D01*
Y7574D01*
X347167D01*
Y7884D01*
X347075Y7943D01*
G02X348591I758J1179D01*
G37*
G36*
G01X355751Y9802D02*
G03X356449Y9800I350J194D01*
G02X356446Y8434I1223J-686D01*
G03X355748Y8436I-350J-194D01*
G02X355283Y7943I-1222J687D01*
G01X355191Y7884D01*
Y7574D01*
X355626D01*
Y472D01*
X353424D01*
Y7574D01*
X353859D01*
Y7884D01*
X353767Y7943D01*
G02X355751Y9802I758J1179D01*
G37*
G36*
G01X362540Y9828D02*
G03X363243I352J190D01*
G02X365492Y7932I1322J-714D01*
G01X365415Y7872D01*
Y7574D01*
X365666D01*
Y472D01*
X363464D01*
Y7574D01*
X363715D01*
Y7872D01*
X363638Y7932D01*
G02X363243Y8400I926J1183D01*
G03X362540I-351J-190D01*
G02X362145Y7932I-1321J715D01*
G01X362068Y7872D01*
Y7574D01*
X362320D01*
Y472D01*
X360116D01*
Y7574D01*
X360368D01*
Y7872D01*
X360291Y7932D01*
G02X362540Y9828I927J1182D01*
G37*
G36*
G01X393345Y14606D02*
G02X393935Y14850I555J-507D01*
G01X404911D01*
X407511Y12250D01*
X409311D01*
X410650Y10911D01*
Y10886D01*
G03X411131Y10495I400J1D01*
G02X410869Y7831I285J-1373D01*
G01X410745Y7884D01*
X408911Y6050D01*
X405824D01*
Y472D01*
X403620D01*
Y6050D01*
X402478D01*
Y472D01*
X400274D01*
Y6050D01*
X395784D01*
Y472D01*
X393582D01*
Y6358D01*
X392050Y7889D01*
Y8624D01*
G03X391304Y8824I-400J-1D01*
G02X384586Y10628I-3117J1804D01*
G01Y15528D01*
G02X391788I3601J0D01*
G01Y14015D01*
G03X392471Y13732I400J0D01*
G01X393345Y14606D01*
G37*
G36*
G01X415521Y7943D02*
X415429Y7884D01*
Y7574D01*
X415864D01*
Y472D01*
X413660D01*
Y7574D01*
X414097D01*
Y7884D01*
X414005Y7943D01*
G02X415521I758J1179D01*
G37*
G36*
G01X428908Y7942D02*
X428816Y7883D01*
Y7574D01*
X429248D01*
Y472D01*
X427046D01*
Y7574D01*
X427478D01*
Y7883D01*
X427386Y7942D01*
G02X428908I761J1178D01*
G37*
G36*
G01X435601D02*
X435509Y7883D01*
Y7574D01*
X435942D01*
Y472D01*
X433738D01*
Y7574D01*
X434171D01*
Y7883D01*
X434079Y7942D01*
G02X435601I761J1178D01*
G37*
G36*
G01X438948D02*
X438856Y7883D01*
Y7574D01*
X439288D01*
Y472D01*
X437086D01*
Y7574D01*
X437518D01*
Y7883D01*
X437426Y7942D01*
G02X438948I761J1178D01*
G37*
G36*
G01X445638Y7943D02*
X445546Y7884D01*
Y7574D01*
X445982D01*
Y472D01*
X443778D01*
Y7574D01*
X444214D01*
Y7884D01*
X444122Y7943D01*
G02X445638I758J1179D01*
G37*
G36*
G01X770589Y7947D02*
X770490Y7889D01*
Y7574D01*
X770982D01*
Y472D01*
X768780D01*
Y7574D01*
X769272D01*
Y7889D01*
X769173Y7947D01*
G02X770589I708J1210D01*
G37*
G36*
G01X961398Y7942D02*
X961308Y7882D01*
Y7574D01*
X961730D01*
Y472D01*
X959528D01*
Y7574D01*
X959950D01*
Y7882D01*
X959860Y7942D01*
G02X961398I769J1172D01*
G37*
G36*
G01X974784D02*
X974694Y7882D01*
Y7574D01*
X975116D01*
Y472D01*
X972914D01*
Y7574D01*
X973336D01*
Y7882D01*
X973246Y7942D01*
G02X974784I769J1172D01*
G37*
G36*
G01X978131D02*
X978041Y7882D01*
Y7574D01*
X978464D01*
Y472D01*
X976260D01*
Y7574D01*
X976683D01*
Y7882D01*
X976593Y7942D01*
G02X978131I769J1172D01*
G37*
G36*
G01X984823D02*
X984733Y7882D01*
Y7574D01*
X985156D01*
Y472D01*
X982954D01*
Y7574D01*
X983375D01*
Y7882D01*
X983285Y7942D01*
G02X984823I769J1172D01*
G37*
G36*
G01X988170D02*
X988080Y7882D01*
Y7574D01*
X988502D01*
Y472D01*
X986300D01*
Y7574D01*
X986722D01*
Y7882D01*
X986632Y7942D01*
G02X988170I769J1172D01*
G37*
G36*
G01X994852Y7943D02*
X994760Y7884D01*
Y7574D01*
X995196D01*
Y472D01*
X992992D01*
Y7574D01*
X993428D01*
Y7884D01*
X993336Y7943D01*
G02X994852I758J1179D01*
G37*
G36*
G01X998199D02*
X998107Y7884D01*
Y7574D01*
X998542D01*
Y472D01*
X996340D01*
Y7574D01*
X996775D01*
Y7884D01*
X996683Y7943D01*
G02X998199I758J1179D01*
G37*
G36*
G01X1005359Y9802D02*
G03X1006057Y9800I350J194D01*
G02X1006054Y8434I1223J-686D01*
G03X1005356Y8436I-350J-194D01*
G02X1004891Y7943I-1222J687D01*
G01X1004799Y7884D01*
Y7574D01*
X1005234D01*
Y472D01*
X1003032D01*
Y7574D01*
X1003467D01*
Y7884D01*
X1003375Y7943D01*
G02X1005359Y9802I758J1179D01*
G37*
G36*
G01X1012148Y9828D02*
G03X1012851I352J190D01*
G02X1015100Y7932I1322J-714D01*
G01X1015023Y7872D01*
Y7574D01*
X1015274D01*
Y472D01*
X1013072D01*
Y7574D01*
X1013323D01*
Y7872D01*
X1013246Y7932D01*
G02X1012851Y8400I926J1183D01*
G03X1012148I-352J-190D01*
G02X1011753Y7932I-1321J715D01*
G01X1011676Y7872D01*
Y7574D01*
X1011928D01*
Y472D01*
X1009724D01*
Y7574D01*
X1009976D01*
Y7872D01*
X1009899Y7932D01*
G02X1012148Y9828I927J1182D01*
G37*
G36*
G01X1042745Y14706D02*
G02X1043335Y14950I555J-507D01*
G01X1043723D01*
G03X1044123Y15352I0J400D01*
G02X1045768Y16738I1402J5D01*
G03X1046237Y17112I70J394D01*
G02X1046868Y18214I1400J-70D01*
G01X1046958Y18274D01*
Y18582D01*
X1046536D01*
Y25684D01*
X1048738D01*
Y18582D01*
X1048316D01*
Y18274D01*
X1048406Y18214D01*
G02X1047394Y15661I-769J-1172D01*
G03X1046925Y15287I-70J-394D01*
G02X1046915Y15176I-1400J70D01*
G01X1046914Y15163D01*
Y14950D01*
X1054511D01*
X1057211Y12250D01*
X1058911D01*
X1060350Y10811D01*
Y10452D01*
X1060580D01*
X1060609Y10461D01*
G02X1060600Y7786I415J-1339D01*
G01X1060484Y7823D01*
X1059011Y6350D01*
X1055432D01*
Y472D01*
X1053228D01*
Y6350D01*
X1052086D01*
Y472D01*
X1049882D01*
Y6350D01*
X1045392D01*
Y472D01*
X1043190D01*
Y6350D01*
X1041650Y7889D01*
Y8606D01*
G03X1040905Y8808I-400J0D01*
G02X1034196Y10628I-3108J1820D01*
G01Y15528D01*
G02X1041398I3601J0D01*
G01Y14325D01*
G03X1042081Y14042I400J0D01*
G01X1042745Y14706D01*
G37*
G36*
G01X1065129Y7943D02*
X1065037Y7884D01*
Y7574D01*
X1065472D01*
Y472D01*
X1063268D01*
Y7574D01*
X1063705D01*
Y7884D01*
X1063613Y7943D01*
G02X1065129I758J1179D01*
G37*
G36*
G01X1078515D02*
X1078423Y7884D01*
Y7574D01*
X1078856D01*
Y472D01*
X1076654D01*
Y7574D01*
X1077091D01*
Y7884D01*
X1076999Y7943D01*
G02X1078515I758J1179D01*
G37*
G36*
G01X1085208D02*
X1085116Y7884D01*
Y7574D01*
X1085550D01*
Y472D01*
X1083346D01*
Y7574D01*
X1083784D01*
Y7884D01*
X1083692Y7943D01*
G02X1085208I758J1179D01*
G37*
G36*
G01X1088555D02*
X1088463Y7884D01*
Y7574D01*
X1088896D01*
Y472D01*
X1086694D01*
Y7574D01*
X1087131D01*
Y7884D01*
X1087039Y7943D01*
G02X1088555I758J1179D01*
G37*
G36*
G01X1095246D02*
X1095154Y7884D01*
Y7574D01*
X1095590D01*
Y472D01*
X1093386D01*
Y7574D01*
X1093822D01*
Y7884D01*
X1093730Y7943D01*
G02X1095246I758J1179D01*
G37*
G36*
G01X1689167Y2223D02*
G02Y3777I-1167J777D01*
G03X1689833I333J222D01*
G02Y2223I1167J-777D01*
G03X1689167I-333J-222D01*
G37*
G36*
G01X1547967Y2623D02*
G02Y4177I-1167J777D01*
G03X1548633I333J222D01*
G02X1550773Y4410I1167J-777D01*
G03X1551327I277J288D01*
G02X1553273I973J-1010D01*
G03X1553827I277J288D01*
G02X1556045Y4045I973J-1010D01*
G03X1556755I355J184D01*
G02X1558973Y4410I1245J-645D01*
G03X1559527I277J288D01*
G02X1561550Y4329I973J-1010D01*
G03X1562150I300J265D01*
G02X1564289Y4283I1050J-929D01*
G03X1564911I311J252D01*
G02X1567167Y4177I1089J-883D01*
G03X1567833I333J222D01*
G02Y2623I1167J-777D01*
G03X1567167I-333J-222D01*
G02X1564911Y2517I-1167J777D01*
G03X1564289I-311J-252D01*
G02X1562150Y2471I-1089J883D01*
G03X1561550I-300J-265D01*
G02X1559527Y2390I-1050J929D01*
G03X1558973I-277J-288D01*
G02X1556755Y2755I-973J1010D01*
G03X1556045I-355J-184D01*
G02X1553827Y2390I-1245J645D01*
G03X1553273I-277J-288D01*
G02X1551327I-973J1010D01*
G03X1550773I-277J-288D01*
G02X1548633Y2623I-973J1010D01*
G03X1547967I-333J-222D01*
G37*
G36*
G01X1510373Y2490D02*
G02Y4510I-973J1010D01*
G03X1510927I277J288D01*
G02X1512873I973J-1010D01*
G03X1513427I277J288D01*
G02X1515373I973J-1010D01*
G03X1515927I277J288D01*
G02X1518145Y4145I973J-1010D01*
G03X1518855I355J184D01*
G02Y2855I1245J-645D01*
G03X1518145I-355J-184D01*
G02X1515927Y2490I-1245J645D01*
G03X1515373I-277J-288D01*
G02X1513427I-973J1010D01*
G03X1512873I-277J-288D01*
G02X1510927I-973J1010D01*
G03X1510373I-277J-288D01*
G37*
G36*
G01X1525889Y2617D02*
G02Y4383I-1089J883D01*
G03X1526511I311J252D01*
G02X1528845Y4145I1089J-883D01*
G03X1529555I355J184D01*
G02X1532045I1245J-645D01*
G03X1532755I355J184D01*
G02Y2855I1245J-645D01*
G03X1532045I-355J-184D01*
G02X1529555I-1245J645D01*
G03X1528845I-355J-184D01*
G02X1526511Y2617I-1245J645D01*
G03X1525889I-311J-252D01*
G37*
G36*
G01X1786560Y7365D02*
G02X1786549Y8852I-1194J735D01*
G03X1787227Y8857I337J215D01*
G02X1787238Y7370I1194J-735D01*
G03X1786560Y7365I-337J-215D01*
G37*
G36*
G01X649581Y7600D02*
G02X647784Y9724I-1031J950D01*
G03X647773Y10401I-218J335D01*
G02X649474Y12608I727J1199D01*
G03X650051Y12630I278J288D01*
G02X651847Y10513I1049J-931D01*
G03Y9837I213J-338D01*
G02X650147Y7622I-747J-1186D01*
G03X649581Y7600I-272J-293D01*
G37*
G36*
G01X1809523Y10358D02*
G02X1807832Y10471I-920J-1058D01*
G03X1807875Y11107I-220J334D01*
G02X1809566Y10994I920J1058D01*
G03X1809523Y10358I220J-334D01*
G37*
G36*
G01X1619797Y12266D02*
X1624799D01*
G02X1626310Y10765I0J-1512D01*
G01Y10670D01*
X1626300Y10586D01*
G02X1624798Y9244I-1502J169D01*
G01X1619796D01*
G02X1618983Y9482I1J1511D01*
G03X1618375Y9224I-216J-336D01*
G02X1617708Y10710I-1375J276D01*
G03X1618305Y10992I202J345D01*
G02X1619797Y12266I1493J-237D01*
G37*
G36*
G01X1842292Y10352D02*
G02X1842206Y8838I1134J-824D01*
G03X1841534Y8876I-348J-197D01*
G02X1839427Y8690I-1134J824D01*
G03X1838873I-277J-288D01*
G02Y10710I-973J1010D01*
G03X1839427I277J288D01*
G02X1841620Y10390I972J-1010D01*
G03X1842292Y10352I348J197D01*
G37*
G36*
G01X1323621Y8939D02*
G02X1321743Y10981I-1089J883D01*
G03X1321733Y11650I-224J331D01*
G02X1321660Y13969I750J1184D01*
G03X1321666Y14613I-234J324D01*
G02X1323597Y16617I842J1121D01*
G03X1324219I311J252D01*
G02X1326340Y16682I1089J-883D01*
G03X1326948Y16704I295J271D01*
G02X1328789Y14643I1097J-873D01*
G03X1328806Y13954I212J-339D01*
G02X1328959Y11604I-683J-1224D01*
G03X1328950Y10968I238J-321D01*
G02X1327028Y8944I-865J-1103D01*
G03X1326417Y8934I-301J-263D01*
G02X1324243Y8939I-1085J888D01*
G03X1323621I-311J-252D01*
G37*
G36*
G01X1833522Y11557D02*
G02X1831621Y9726I-622J-1257D01*
G03X1830952Y9822I-365J-164D01*
G02X1831167Y11309I-1064J913D01*
G03X1831836Y11213I365J164D01*
G02X1832233Y11533I1064J-913D01*
G03X1832220Y12243I-190J352D01*
G02X1833509Y12267I621J1257D01*
G03X1833522Y11557I190J-352D01*
G37*
G36*
G01X63880Y12677D02*
G02X62764Y11443I279J-1374D01*
G03X62287Y11875I-398J40D01*
G02X63403Y13109I-279J1374D01*
G03X63880Y12677I398J-40D01*
G37*
G36*
G01X1847352Y13735D02*
G02X1847035Y12168I970J-1012D01*
G03X1846390Y12298I-368J-158D01*
G02X1846707Y13865I-970J1012D01*
G03X1847352Y13735I368J158D01*
G37*
G36*
G01X1869503Y12151D02*
G02X1869308Y13808I-1217J697D01*
G03X1869946Y13883I291J274D01*
G02X1870141Y12226I1217J-697D01*
G03X1869503Y12151I-291J-274D01*
G37*
G36*
G01X1414946Y12458D02*
G02Y13820I-1225J681D01*
G03X1415646I350J194D01*
G02Y12458I1225J-681D01*
G03X1414946I-350J-194D01*
G37*
G36*
G01X25301Y17595D02*
G02X23782Y16791I-241J-1381D01*
G03X23487Y17350I-364J165D01*
G02X25006Y18154I241J1381D01*
G03X25301Y17595I364J-165D01*
G37*
G36*
G01X362320Y25684D02*
Y18914D01*
G03X362707Y18515I400J1D01*
G02X362979Y18482I-44J-1501D01*
G03X363464Y18873I85J391D01*
G01Y25684D01*
X365666D01*
Y18508D01*
X365801Y18462D01*
G02X366394Y18083I-490J-1420D01*
G03X366955Y18067I289J277D01*
G02Y16017I956J-1025D01*
G03X366394Y16001I-272J-293D01*
G02X364276Y15953I-1083J1041D01*
G03X363719Y15947I-275J-290D01*
G02X361476Y17936I-1057J1067D01*
G03X361161Y18582I-316J246D01*
G01X360116D01*
Y25684D01*
X362320D01*
G37*
G36*
G01X1011928D02*
Y18914D01*
G03X1012315Y18515I400J1D01*
G02X1012587Y18482I-44J-1501D01*
G03X1013072Y18873I85J391D01*
G01Y25684D01*
X1015274D01*
Y18508D01*
X1015409Y18462D01*
G02X1016002Y18083I-490J-1420D01*
G03X1016563Y18067I289J277D01*
G02Y16017I956J-1025D01*
G03X1016002Y16001I-272J-293D01*
G02X1013884Y15953I-1083J1041D01*
G03X1013327Y15947I-275J-290D01*
G02X1011084Y17936I-1057J1067D01*
G03X1010769Y18582I-316J246D01*
G01X1009724D01*
Y25684D01*
X1011928D01*
G37*
G36*
G01X560968Y18221D02*
X561048Y18281D01*
Y18582D01*
X560904D01*
Y25684D01*
X563106D01*
Y18582D01*
X562688D01*
Y18281D01*
X562768Y18221D01*
G02X560968I-900J-1202D01*
G37*
G36*
G01X397260Y18214D02*
X397350Y18274D01*
Y18582D01*
X396928D01*
Y25684D01*
X399130D01*
Y18582D01*
X398708D01*
Y18274D01*
X398798Y18214D01*
G02X397260I-769J-1172D01*
G37*
G36*
G01X407300D02*
X407390Y18274D01*
Y18582D01*
X406968D01*
Y25684D01*
X409170D01*
Y18582D01*
X408748D01*
Y18274D01*
X408838Y18214D01*
G02X407300I-769J-1172D01*
G37*
G36*
G01X424032D02*
X424122Y18274D01*
Y18582D01*
X423700D01*
Y25684D01*
X425902D01*
Y18582D01*
X425480D01*
Y18274D01*
X425570Y18214D01*
G02X424032I-769J-1172D01*
G37*
G36*
G01X430725D02*
X430815Y18274D01*
Y18582D01*
X430392D01*
Y25684D01*
X432596D01*
Y18582D01*
X432173D01*
Y18274D01*
X432263Y18214D01*
G02X430725I-769J-1172D01*
G37*
G36*
G01X1056908D02*
X1056998Y18274D01*
Y18582D01*
X1056576D01*
Y25684D01*
X1058778D01*
Y18582D01*
X1058356D01*
Y18274D01*
X1058446Y18214D01*
G02X1056908I-769J-1172D01*
G37*
G36*
G01X1073640D02*
X1073730Y18274D01*
Y18582D01*
X1073308D01*
Y25684D01*
X1075510D01*
Y18582D01*
X1075088D01*
Y18274D01*
X1075178Y18214D01*
G02X1073640I-769J-1172D01*
G37*
G36*
G01X1080333D02*
X1080423Y18274D01*
Y18582D01*
X1080000D01*
Y25684D01*
X1082204D01*
Y18582D01*
X1081781D01*
Y18274D01*
X1081871Y18214D01*
G02X1080333I-769J-1172D01*
G37*
G36*
G01X306886Y18216D02*
X306974Y18276D01*
Y18582D01*
X306574D01*
Y25684D01*
X308776D01*
Y18582D01*
X308376D01*
Y18276D01*
X308464Y18216D01*
G02X306886I-789J-1159D01*
G37*
G36*
G01X313579D02*
X313667Y18276D01*
Y18582D01*
X313266D01*
Y25684D01*
X315470D01*
Y18582D01*
X315069D01*
Y18276D01*
X315157Y18216D01*
G02X313579I-789J-1159D01*
G37*
G36*
G01X320272D02*
X320360Y18276D01*
Y18582D01*
X319960D01*
Y25684D01*
X322162D01*
Y18582D01*
X321762D01*
Y18276D01*
X321850Y18216D01*
G02X320272I-789J-1159D01*
G37*
G36*
G01X323618D02*
X323706Y18276D01*
Y18582D01*
X323306D01*
Y25684D01*
X325508D01*
Y18582D01*
X325108D01*
Y18276D01*
X325196Y18216D01*
G02X323618I-789J-1159D01*
G37*
G36*
G01X330311D02*
X330399Y18276D01*
Y18582D01*
X329998D01*
Y25684D01*
X332202D01*
Y18582D01*
X331801D01*
Y18276D01*
X331889Y18216D01*
G02X330311I-789J-1159D01*
G37*
G36*
G01X333658D02*
X333746Y18276D01*
Y18582D01*
X333346D01*
Y25684D01*
X335548D01*
Y18582D01*
X335148D01*
Y18276D01*
X335236Y18216D01*
G02X333658I-789J-1159D01*
G37*
G36*
G01X340351D02*
X340439Y18276D01*
Y18582D01*
X340038D01*
Y25684D01*
X342242D01*
Y18582D01*
X341841D01*
Y18276D01*
X341929Y18216D01*
G02X340351I-789J-1159D01*
G37*
G36*
G01X343697D02*
X343785Y18276D01*
Y18582D01*
X343384D01*
Y25684D01*
X345588D01*
Y18582D01*
X345187D01*
Y18276D01*
X345275Y18216D01*
G02X343697I-789J-1159D01*
G37*
G36*
G01X350390D02*
X350478Y18276D01*
Y18582D01*
X350078D01*
Y25684D01*
X352280D01*
Y18582D01*
X351880D01*
Y18276D01*
X351968Y18216D01*
G02X350390I-789J-1159D01*
G37*
G36*
G01X353737D02*
X353825Y18276D01*
Y18582D01*
X353424D01*
Y25684D01*
X355626D01*
Y18582D01*
X355227D01*
Y18276D01*
X355315Y18216D01*
G02X353737I-789J-1159D01*
G37*
G36*
G01X403934D02*
X404022Y18276D01*
Y18582D01*
X403620D01*
Y25684D01*
X405824D01*
Y18582D01*
X405424D01*
Y18276D01*
X405512Y18216D01*
G02X403934I-789J-1159D01*
G37*
G36*
G01X420667D02*
X420755Y18276D01*
Y18582D01*
X420354D01*
Y25684D01*
X422556D01*
Y18582D01*
X422157D01*
Y18276D01*
X422245Y18216D01*
G02X420667I-789J-1159D01*
G37*
G36*
G01X956494D02*
X956582Y18276D01*
Y18582D01*
X956182D01*
Y25684D01*
X958384D01*
Y18582D01*
X957984D01*
Y18276D01*
X958072Y18216D01*
G02X956494I-789J-1159D01*
G37*
G36*
G01X963187D02*
X963275Y18276D01*
Y18582D01*
X962874D01*
Y25684D01*
X965078D01*
Y18582D01*
X964677D01*
Y18276D01*
X964765Y18216D01*
G02X963187I-789J-1159D01*
G37*
G36*
G01X969880D02*
X969968Y18276D01*
Y18582D01*
X969568D01*
Y25684D01*
X971770D01*
Y18582D01*
X971370D01*
Y18276D01*
X971458Y18216D01*
G02X969880I-789J-1159D01*
G37*
G36*
G01X973226D02*
X973314Y18276D01*
Y18582D01*
X972914D01*
Y25684D01*
X975116D01*
Y18582D01*
X974716D01*
Y18276D01*
X974804Y18216D01*
G02X973226I-789J-1159D01*
G37*
G36*
G01X979919D02*
X980007Y18276D01*
Y18582D01*
X979606D01*
Y25684D01*
X981810D01*
Y18582D01*
X981409D01*
Y18276D01*
X981497Y18216D01*
G02X979919I-789J-1159D01*
G37*
G36*
G01X983266D02*
X983354Y18276D01*
Y18582D01*
X982954D01*
Y25684D01*
X985156D01*
Y18582D01*
X984756D01*
Y18276D01*
X984844Y18216D01*
G02X983266I-789J-1159D01*
G37*
G36*
G01X989959D02*
X990047Y18276D01*
Y18582D01*
X989646D01*
Y25684D01*
X991850D01*
Y18582D01*
X991449D01*
Y18276D01*
X991537Y18216D01*
G02X989959I-789J-1159D01*
G37*
G36*
G01X993305D02*
X993393Y18276D01*
Y18582D01*
X992992D01*
Y25684D01*
X995196D01*
Y18582D01*
X994795D01*
Y18276D01*
X994883Y18216D01*
G02X993305I-789J-1159D01*
G37*
G36*
G01X999998D02*
X1000086Y18276D01*
Y18582D01*
X999686D01*
Y25684D01*
X1001888D01*
Y18582D01*
X1001488D01*
Y18276D01*
X1001576Y18216D01*
G02X999998I-789J-1159D01*
G37*
G36*
G01X1003345D02*
X1003433Y18276D01*
Y18582D01*
X1003032D01*
Y25684D01*
X1005234D01*
Y18582D01*
X1004835D01*
Y18276D01*
X1004923Y18216D01*
G02X1003345I-789J-1159D01*
G37*
G36*
G01X1053542D02*
X1053630Y18276D01*
Y18582D01*
X1053228D01*
Y25684D01*
X1055432D01*
Y18582D01*
X1055032D01*
Y18276D01*
X1055120Y18216D01*
G02X1053542I-789J-1159D01*
G37*
G36*
G01X1063582D02*
X1063670Y18276D01*
Y18582D01*
X1063268D01*
Y25684D01*
X1065472D01*
Y18582D01*
X1065072D01*
Y18276D01*
X1065160Y18216D01*
G02X1063582I-789J-1159D01*
G37*
G36*
G01X1070275D02*
X1070363Y18276D01*
Y18582D01*
X1069962D01*
Y25684D01*
X1072164D01*
Y18582D01*
X1071765D01*
Y18276D01*
X1071853Y18216D01*
G02X1070275I-789J-1159D01*
G37*
G36*
G01X413972D02*
X414059Y18276D01*
Y18582D01*
X413660D01*
Y25684D01*
X415864D01*
Y18582D01*
X415465D01*
Y18276D01*
X415552Y18216D01*
G02X413972I-790J-1158D01*
G37*
G36*
G01X437396D02*
X437483Y18276D01*
Y18582D01*
X437086D01*
Y25684D01*
X439288D01*
Y18582D01*
X438891D01*
Y18276D01*
X438978Y18216D01*
G02X437396I-791J-1157D01*
G37*
G36*
G01X444089D02*
X444176Y18276D01*
Y18582D01*
X443778D01*
Y25684D01*
X445982D01*
Y18582D01*
X445584D01*
Y18276D01*
X445671Y18216D01*
G02X444089I-791J-1157D01*
G37*
G36*
G01X1087004D02*
X1087091Y18276D01*
Y18582D01*
X1086694D01*
Y25684D01*
X1088896D01*
Y18582D01*
X1088499D01*
Y18276D01*
X1088586Y18216D01*
G02X1087004I-791J-1157D01*
G37*
G36*
G01X1093697D02*
X1093784Y18276D01*
Y18582D01*
X1093386D01*
Y25684D01*
X1095590D01*
Y18582D01*
X1095192D01*
Y18276D01*
X1095279Y18216D01*
G02X1093697I-791J-1157D01*
G37*
G36*
G01X63377Y18524D02*
G02X62881Y16915I823J-1135D01*
G03X62269Y17103I-376J-135D01*
G02X62765Y18712I-823J1135D01*
G03X63377Y18524I376J135D01*
G37*
G36*
G01X1025003Y18760D02*
G02X1023684Y19551I-1263J-610D01*
G03X1024028Y20124I-16J399D01*
G02X1025347Y19333I1263J610D01*
G03X1025003Y18760I16J-399D01*
G37*
G36*
G01X35905Y18708D02*
G02X35882Y20238I-1186J747D01*
G03X36553Y20248I332J223D01*
G02X38615Y20596I1186J-747D01*
G03X39234Y20755I250J312D01*
G02X39654Y19125I1296J-535D01*
G03X39035Y18966I-250J-312D01*
G02X36576Y18718I-1296J535D01*
G03X35905Y18708I-332J-223D01*
G37*
G36*
G01X702306Y18872D02*
G02X700071Y18689I-1186J747D01*
G03X699483Y18700I-299J-266D01*
G02X699519Y20599I-1013J969D01*
G03X700107Y20588I299J266D01*
G02X702291Y20390I1013J-969D01*
G03X702964Y20397I334J220D01*
G02X702979Y18879I1186J-747D01*
G03X702306Y18872I-334J-220D01*
G37*
G36*
G01X1853676Y20417D02*
G02X1850883Y21976I-1441J700D01*
G03X1850644Y22578I-338J214D01*
G02X1850313Y25557I396J1552D01*
G03X1850492Y26087I-182J357D01*
G02X1853336Y27558I1444J693D01*
G03X1854036I350J194D01*
G02X1856876Y27481I1400J-778D01*
G03X1857596I360J175D01*
G02X1860476I1440J-701D01*
G03X1861196I360J175D01*
G02X1864207Y26465I1440J-701D01*
G03X1864483Y26004I392J-78D01*
G02X1865565Y24045I-463J-1534D01*
G03X1865850Y23551I385J-107D01*
G02X1864840Y20519I-399J-1551D01*
G03X1864338Y20342I-152J-370D01*
G02X1861536Y20340I-1402J776D01*
G03X1860836I-350J-194D01*
G02X1857996Y20417I-1400J778D01*
G03X1857276I-360J-175D01*
G02X1854396I-1440J701D01*
G03X1853676I-360J-175D01*
G37*
G36*
G01X1839505Y20731D02*
G02X1836897Y20443I-1405J769D01*
G03X1836301Y20449I-301J-264D01*
G02X1833901Y20494I-1180J1083D01*
G03X1833291I-305J-259D01*
G02Y22570I-1220J1038D01*
G03X1833901I305J259D01*
G02X1836324Y22589I1220J-1038D01*
G03X1836920Y22583I301J264D01*
G02X1839437Y22382I1180J-1083D01*
G03X1840108Y22387I334J220D01*
G02X1840174Y20781I1181J-756D01*
G03X1839505Y20731I-318J-242D01*
G37*
G36*
G01X755559Y23924D02*
G02X755505Y22420I1155J-794D01*
G03X754830Y22445I-345J-202D01*
G02X754884Y23949I-1155J794D01*
G03X755559Y23924I345J202D01*
G37*
G36*
G01X713670Y24408D02*
G02X713617Y22895I1153J-798D01*
G03X712944Y22918I-344J-204D01*
G02X712997Y24431I-1153J798D01*
G03X713670Y24408I344J204D01*
G37*
G36*
G01X1871884Y25563D02*
G02X1869964Y26249I-1284J-563D01*
G03X1870029Y26921I-181J357D01*
G02X1872259Y26123I2314J2953D01*
G03X1871884Y25563I-8J-400D01*
G37*
G36*
G01X69167Y25215D02*
G02X66831Y25218I-1167J777D01*
G03X66165Y25220I-334J-221D01*
G02X63833Y25223I-1165J780D01*
G03X63167I-333J-222D01*
G02X61027Y24990I-1167J777D01*
G03X60473I-277J-288D01*
G02X58490Y26973I-973J1010D01*
G03Y27527I-288J277D01*
G02X60473Y29510I1010J973D01*
G03X61027I277J288D01*
G02X63167Y29277I973J-1010D01*
G03X63833I333J222D01*
G02X66167I1167J-777D01*
G03X66833I333J222D01*
G02X69167I1167J-777D01*
G03X69833I333J222D01*
G02X72167I1167J-777D01*
G03X72833I333J222D01*
G02X75167I1167J-777D01*
G03X75833I333J222D01*
G02X78043Y29436I1167J-777D01*
G03X78709Y29547I298J267D01*
G02X80777Y27833I1291J-547D01*
G03Y27167I222J-333D01*
G02X78835Y25220I-777J-1167D01*
G03X78169Y25218I-332J-223D01*
G02X75833Y25215I-1169J774D01*
G03X75167I-333J-222D01*
G02X72833I-1167J777D01*
G03X72167I-333J-222D01*
G02X69833I-1167J777D01*
G03X69167I-333J-222D01*
G37*
G36*
G01X1837663Y27859D02*
G02X1837514Y25561I1037J-1221D01*
G03X1836958Y25597I-297J-268D01*
G02X1834661Y25829I-1037J1221D01*
G03X1834031I-315J-247D01*
G02X1831458Y25901I-1260J989D01*
G03X1830798Y25896I-328J-229D01*
G02X1830725Y27563I-1162J784D01*
G03X1831382Y27616I310J252D01*
G02X1834031Y27807I1389J-798D01*
G03X1834661I315J247D01*
G02X1837107Y27895I1260J-989D01*
G03X1837663Y27859I297J268D01*
G37*
G36*
G01X643566Y30162D02*
G02X643831Y32385I-5773J1815D01*
G03X644497Y32113I399J26D01*
G02X644277Y30270I933J-1046D01*
G03X643566Y30162I-329J-228D01*
G37*
G36*
G01X1012148Y27300D02*
G02Y28728I-1322J714D01*
G03X1012851I352J190D01*
G02Y27300I1322J-714D01*
G03X1012148I-352J-190D01*
G37*
G36*
G01X1855356Y35523D02*
G02X1855081Y33888I977J-1005D01*
G03X1854444Y33995I-358J-180D01*
G02X1854719Y35630I-977J1005D01*
G03X1855356Y35523I358J180D01*
G37*
G36*
G01X362540Y35228D02*
G02X360100Y34939I-1322J714D01*
G03X359540Y34974I-298J-267D01*
G02X359610Y37023I-921J1057D01*
G03X360171Y37019I283J283D01*
G02X362540Y36656I1047J-1077D01*
G03X363243I352J190D01*
G02Y35228I1322J-714D01*
G03X362540I-351J-190D01*
G37*
G36*
G01X1012148D02*
G02X1009740Y34905I-1321J714D01*
G03X1009177Y34920I-289J-277D01*
G02Y36964I-960J1022D01*
G03X1009740Y36979I274J292D01*
G02X1012148Y36656I1087J-1037D01*
G03X1012851I352J190D01*
G02Y35228I1322J-714D01*
G03X1012148I-352J-190D01*
G37*
G36*
G01X3401Y37588D02*
G02X2221Y36451I199J-1388D01*
G03X1771Y36919I-393J72D01*
G02X2951Y38056I-199J1388D01*
G03X3401Y37588I393J-72D01*
G37*
G36*
G01X1818049Y38126D02*
G02X1816526Y38042I-697J-1217D01*
G03X1816489Y38712I-236J323D01*
G02X1818012Y38796I697J1217D01*
G03X1818049Y38126I236J-323D01*
G37*
G36*
G01X1879863Y38648D02*
G02X1877978Y38508I-866J-1102D01*
G03X1877934Y39098I-291J275D01*
G02X1878027Y41370I866J1102D01*
G03Y42037I-220J334D01*
G02X1879573I773J1170D01*
G03Y41370I220J-333D01*
G02X1879819Y39238I-773J-1169D01*
G03X1879863Y38648I291J-275D01*
G37*
G36*
G01X717821Y39557D02*
G02X715736Y37718I-921J-1057D01*
G03X715097Y37752I-332J-223D01*
G02X712873Y37851I-1074J901D01*
G03X712224Y37862I-328J-228D01*
G02X710054Y39634I-1123J839D01*
G03Y40166I-298J266D01*
G02X712250Y41902I1046J933D01*
G03X712899Y41891I328J228D01*
G02X713154Y42154I1126J-836D01*
G03X713149Y42786I-247J314D01*
G02X713067Y44947I851J1114D01*
G03X712995Y45595I-266J298D01*
G02X714647Y47831I679J1227D01*
G03X715203I278J288D01*
G02X717077Y47896I973J-1009D01*
G03X717615Y47918I257J307D01*
G02X718193Y48263I987J-996D01*
G03X718471Y48718I-115J383D01*
G02X720796Y50005I1379J252D01*
G03X721342Y50011I270J295D01*
G02X723690Y48740I970J-1012D01*
G03X723976Y48280I393J-75D01*
G02X722657Y45894I-373J-1351D01*
G03X722111Y45888I-270J-295D01*
G02X720144Y45914I-970J1012D01*
G03X719580Y45919I-285J-281D01*
G02X717699Y45847I-980J1002D01*
G03X717161Y45825I-257J-307D01*
G02X717105Y45772I-991J991D01*
G03X717222Y45101I265J-299D01*
G02X717628Y42749I-522J-1301D01*
G03X717637Y42141I264J-300D01*
G02X717786Y40126I-895J-1079D01*
G03X717821Y39557I298J-267D01*
G37*
G36*
G01X120981Y45747D02*
X120882Y45689D01*
Y45374D01*
X121374D01*
Y38272D01*
X119172D01*
Y45374D01*
X119664D01*
Y45689D01*
X119565Y45747D01*
G02X120981I708J1210D01*
G37*
G36*
G01X311790Y45742D02*
X311700Y45682D01*
Y45374D01*
X312122D01*
Y38272D01*
X309920D01*
Y45374D01*
X310342D01*
Y45682D01*
X310252Y45742D01*
G02X311790I769J1172D01*
G37*
G36*
G01X325176D02*
X325086Y45682D01*
Y45374D01*
X325508D01*
Y38272D01*
X323306D01*
Y45374D01*
X323728D01*
Y45682D01*
X323638Y45742D01*
G02X325176I769J1172D01*
G37*
G36*
G01X328523D02*
X328433Y45682D01*
Y45374D01*
X328856D01*
Y38272D01*
X326652D01*
Y45374D01*
X327075D01*
Y45682D01*
X326985Y45742D01*
G02X328523I769J1172D01*
G37*
G36*
G01X335215D02*
X335125Y45682D01*
Y45374D01*
X335548D01*
Y38272D01*
X333346D01*
Y45374D01*
X333767D01*
Y45682D01*
X333677Y45742D01*
G02X335215I769J1172D01*
G37*
G36*
G01X338562D02*
X338472Y45682D01*
Y45374D01*
X338894D01*
Y38272D01*
X336692D01*
Y45374D01*
X337114D01*
Y45682D01*
X337024Y45742D01*
G02X338562I769J1172D01*
G37*
G36*
G01X345244Y45743D02*
X345152Y45684D01*
Y45374D01*
X345588D01*
Y38272D01*
X343384D01*
Y45374D01*
X343820D01*
Y45684D01*
X343728Y45743D01*
G02X345244I758J1179D01*
G37*
G36*
G01X348591D02*
X348499Y45684D01*
Y45374D01*
X348934D01*
Y38272D01*
X346732D01*
Y45374D01*
X347167D01*
Y45684D01*
X347075Y45743D01*
G02X348591I758J1179D01*
G37*
G36*
G01X355283D02*
X355191Y45684D01*
Y45374D01*
X355626D01*
Y38272D01*
X353424D01*
Y45374D01*
X353859D01*
Y45684D01*
X353767Y45743D01*
G02X355283I758J1179D01*
G37*
G36*
G01X365661Y45374D02*
X365666D01*
Y38272D01*
X363464D01*
Y45374D01*
X363586D01*
Y45682D01*
X363496Y45742D01*
G02X363196Y46006I767J1174D01*
G03X362587I-305J-258D01*
G02X362287Y45742I-1067J910D01*
G01X362197Y45682D01*
Y45374D01*
X362320D01*
Y38272D01*
X360116D01*
Y45374D01*
X360122D01*
G03X360432Y46027I0J400D01*
G02X362587Y47822I1086J887D01*
G03X363196I305J258D01*
G02X365351Y46027I1069J-908D01*
G03X365661Y45374I310J-253D01*
G37*
G36*
G01X393245Y52306D02*
G02X393835Y52550I555J-507D01*
G01X405011D01*
X407511Y50050D01*
X409411D01*
X410750Y48711D01*
Y48704D01*
G03X411209Y48309I400J0D01*
G02X410997Y45584I207J-1387D01*
G01X410881Y45620D01*
X409111Y43850D01*
X405824D01*
Y38272D01*
X403620D01*
Y43850D01*
X402478D01*
Y38272D01*
X400274D01*
Y43850D01*
X395784D01*
Y38272D01*
X393582D01*
Y43858D01*
X392150Y45289D01*
Y46607D01*
G03X391394Y46789I-400J0D01*
G02X384586Y48428I-3207J1639D01*
G01Y53328D01*
G02X391788I3601J0D01*
G01Y51815D01*
G03X392471Y51532I400J0D01*
G01X393245Y52306D01*
G37*
G36*
G01X415521Y45743D02*
X415429Y45684D01*
Y45374D01*
X415864D01*
Y38272D01*
X413660D01*
Y45374D01*
X414097D01*
Y45684D01*
X414005Y45743D01*
G02X415521I758J1179D01*
G37*
G36*
G01X428907D02*
X428815Y45684D01*
Y45374D01*
X429248D01*
Y38272D01*
X427046D01*
Y45374D01*
X427483D01*
Y45684D01*
X427391Y45743D01*
G02X428907I758J1179D01*
G37*
G36*
G01X435600D02*
X435508Y45684D01*
Y45374D01*
X435942D01*
Y38272D01*
X433738D01*
Y45374D01*
X434176D01*
Y45684D01*
X434084Y45743D01*
G02X435600I758J1179D01*
G37*
G36*
G01X438947D02*
X438855Y45684D01*
Y45374D01*
X439288D01*
Y38272D01*
X437086D01*
Y45374D01*
X437523D01*
Y45684D01*
X437431Y45743D01*
G02X438947I758J1179D01*
G37*
G36*
G01X445638D02*
X445546Y45684D01*
Y45374D01*
X445982D01*
Y38272D01*
X443778D01*
Y45374D01*
X444214D01*
Y45684D01*
X444122Y45743D01*
G02X445638I758J1179D01*
G37*
G36*
G01X770589Y45747D02*
X770490Y45689D01*
Y45374D01*
X770982D01*
Y38272D01*
X768780D01*
Y45374D01*
X769272D01*
Y45689D01*
X769173Y45747D01*
G02X770589I708J1210D01*
G37*
G36*
G01X961398Y45742D02*
X961308Y45682D01*
Y45374D01*
X961730D01*
Y38272D01*
X959528D01*
Y45374D01*
X959950D01*
Y45682D01*
X959860Y45742D01*
G02X961398I769J1172D01*
G37*
G36*
G01X974784D02*
X974694Y45682D01*
Y45374D01*
X975116D01*
Y38272D01*
X972914D01*
Y45374D01*
X973336D01*
Y45682D01*
X973246Y45742D01*
G02X974784I769J1172D01*
G37*
G36*
G01X978131D02*
X978041Y45682D01*
Y45374D01*
X978464D01*
Y38272D01*
X976260D01*
Y45374D01*
X976683D01*
Y45682D01*
X976593Y45742D01*
G02X978131I769J1172D01*
G37*
G36*
G01X984823D02*
X984733Y45682D01*
Y45374D01*
X985156D01*
Y38272D01*
X982954D01*
Y45374D01*
X983375D01*
Y45682D01*
X983285Y45742D01*
G02X984823I769J1172D01*
G37*
G36*
G01X988170D02*
X988080Y45682D01*
Y45374D01*
X988502D01*
Y38272D01*
X986300D01*
Y45374D01*
X986722D01*
Y45682D01*
X986632Y45742D01*
G02X988170I769J1172D01*
G37*
G36*
G01X994852Y45743D02*
X994760Y45684D01*
Y45374D01*
X995196D01*
Y38272D01*
X992992D01*
Y45374D01*
X993428D01*
Y45684D01*
X993336Y45743D01*
G02X994852I758J1179D01*
G37*
G36*
G01X998199D02*
X998107Y45684D01*
Y45374D01*
X998542D01*
Y38272D01*
X996340D01*
Y45374D01*
X996775D01*
Y45684D01*
X996683Y45743D01*
G02X998199I758J1179D01*
G37*
G36*
G01X1004891D02*
X1004799Y45684D01*
Y45374D01*
X1005234D01*
Y38272D01*
X1003032D01*
Y45374D01*
X1003467D01*
Y45684D01*
X1003375Y45743D01*
G02X1004891I758J1179D01*
G37*
G36*
G01X1009923Y46014D02*
G02X1012211Y47953I1203J900D01*
G03X1012788I288J277D01*
G02X1015076Y46014I1085J-1039D01*
G03X1015274Y45393I320J-240D01*
G01Y38272D01*
X1013072D01*
Y45644D01*
G02X1012788Y45875I799J1272D01*
G03X1012211I-288J-277D01*
G02X1011928Y45644I-1084J1040D01*
G01Y38272D01*
X1009724D01*
Y45393D01*
G03X1009923Y46014I-121J381D01*
G37*
G36*
G01X1043145Y52706D02*
G02X1043318Y52847I556J-506D01*
G03X1043333Y53526I-203J344D01*
G02X1045029Y53650I767J1174D01*
G03X1045293Y52950I265J-300D01*
G01X1054311D01*
X1057211Y50050D01*
X1058911D01*
X1060450Y48511D01*
Y48280D01*
X1060674D01*
X1060697Y48285D01*
G02X1060534Y45608I327J-1363D01*
G01X1060414Y45653D01*
X1058711Y43950D01*
X1055432D01*
Y38272D01*
X1053228D01*
Y43950D01*
X1052086D01*
Y38272D01*
X1049882D01*
Y43950D01*
X1045392D01*
Y38272D01*
X1043190D01*
Y44050D01*
X1041650Y45589D01*
Y46406D01*
G03X1040905Y46608I-400J0D01*
G02X1034196Y48428I-3108J1820D01*
G01Y53328D01*
G02X1041398I3601J0D01*
G01Y51925D01*
G03X1042081Y51642I400J0D01*
G01X1043145Y52706D01*
G37*
G36*
G01X1065129Y45743D02*
X1065037Y45684D01*
Y45374D01*
X1065472D01*
Y38272D01*
X1063268D01*
Y45374D01*
X1063705D01*
Y45684D01*
X1063613Y45743D01*
G02X1065129I758J1179D01*
G37*
G36*
G01X1078515D02*
X1078423Y45684D01*
Y45374D01*
X1078856D01*
Y38272D01*
X1076654D01*
Y45374D01*
X1077091D01*
Y45684D01*
X1076999Y45743D01*
G02X1078515I758J1179D01*
G37*
G36*
G01X1085208D02*
X1085116Y45684D01*
Y45374D01*
X1085550D01*
Y38272D01*
X1083346D01*
Y45374D01*
X1083784D01*
Y45684D01*
X1083692Y45743D01*
G02X1085208I758J1179D01*
G37*
G36*
G01X1088555D02*
X1088463Y45684D01*
Y45374D01*
X1088896D01*
Y38272D01*
X1086694D01*
Y45374D01*
X1087131D01*
Y45684D01*
X1087039Y45743D01*
G02X1088555I758J1179D01*
G37*
G36*
G01X1095246D02*
X1095154Y45684D01*
Y45374D01*
X1095590D01*
Y38272D01*
X1093386D01*
Y45374D01*
X1093822D01*
Y45684D01*
X1093730Y45743D01*
G02X1095246I758J1179D01*
G37*
G36*
G01X1825416Y39145D02*
G02X1824999Y40803I-1286J558D01*
G03X1825614Y40958I248J314D01*
G02X1826031Y39300I1286J-558D01*
G03X1825416Y39145I-248J-314D01*
G37*
G36*
G01X1637398Y38350D02*
X1632398D01*
G02X1630896Y39694I0J1512D01*
G03X1630473Y40049I-398J-44D01*
G02X1629531Y40337I-87J1399D01*
G03X1629211Y40150I-122J-159D01*
G02X1629219Y40082I-1497J-211D01*
G01X1629226Y40019D01*
X1629227Y39956D01*
G02Y39911I-1512J-23D01*
G01X1629226Y39910D01*
Y39900D01*
G02X1627725Y38423I-1511J34D01*
G01X1622645Y38389D01*
G02X1622625Y41411I-10J1511D01*
G01X1627704Y41445D01*
G02X1628410Y41277I13J-1512D01*
G03X1628991Y41591I183J355D01*
G02X1631767Y41690I1395J-143D01*
G03X1632211Y41362I394J69D01*
G02X1632398Y41374I190J-1500D01*
G01X1637399D01*
G02X1638910Y39872I-1J-1512D01*
G01Y39777D01*
X1638900Y39693D01*
G02X1637398Y38350I-1502J169D01*
G37*
G36*
G01X1868660Y40718D02*
G02X1867396Y41163I-1041J-939D01*
G03X1867629Y41826I-64J395D01*
G02X1868893Y41381I1041J939D01*
G03X1868660Y40718I64J-395D01*
G37*
G36*
G01X1350135Y39522D02*
G02X1350061Y41113I-1190J742D01*
G03X1350718Y41144I318J243D01*
G02X1350792Y39553I1190J-742D01*
G03X1350135Y39522I-318J-243D01*
G37*
G36*
G01X1856584Y40050D02*
G02X1856393Y41790I-1184J751D01*
G03X1857014Y41858I283J282D01*
G02X1859170Y42118I1184J-750D01*
G03X1859745Y42139I277J288D01*
G02X1859814Y40190I1041J-939D01*
G03X1859239Y40169I-277J-288D01*
G02X1857205Y40118I-1041J939D01*
G03X1856584Y40050I-283J-282D01*
G37*
G36*
G01X59973Y42490D02*
G02X58223Y44667I-972J1010D01*
G03Y45333I-222J333D01*
G02Y47667I777J1167D01*
G03Y48333I-222J333D01*
G02X59973Y50510I778J1167D01*
G03X60527I277J288D01*
G02X62667Y50277I973J-1010D01*
G03X63333I333J222D01*
G02X65667I1167J-777D01*
G03X66333I333J222D01*
G02X68667I1167J-777D01*
G03X69333I333J222D01*
G02X71667I1167J-777D01*
G03X72333I333J222D01*
G02X74667I1167J-777D01*
G03X75333I333J222D01*
G02X77667I1167J-777D01*
G03X78333I333J222D01*
G02X80277Y48333I1167J-777D01*
G03Y47667I222J-333D01*
G02Y45333I-777J-1167D01*
G03Y44667I222J-333D01*
G02X78333Y42723I-777J-1167D01*
G03X77667I-333J-222D01*
G02X75333I-1167J777D01*
G03X74667I-333J-222D01*
G02X72333I-1167J777D01*
G03X71667I-333J-222D01*
G02X69333I-1167J777D01*
G03X68667I-333J-222D01*
G02X66333I-1167J777D01*
G03X65667I-333J-222D01*
G02X63333I-1167J777D01*
G03X62667I-333J-222D01*
G02X60527Y42490I-1167J777D01*
G03X59973I-277J-288D01*
G37*
G36*
G01X657040Y43629D02*
G02X655290Y45806I-972J1010D01*
G03Y46472I-222J333D01*
G02X657040Y48649I778J1167D01*
G03X657594I277J288D01*
G02X659344Y46472I972J-1010D01*
G03Y45806I222J-333D01*
G02X657594Y43629I-778J-1167D01*
G03X657040I-277J-288D01*
G37*
G36*
G01X1378856Y46412D02*
G02X1377714Y45162I254J-1379D01*
G03X1377243Y45592I-398J37D01*
G02X1378385Y46842I-254J1379D01*
G03X1378856Y46412I398J-37D01*
G37*
G36*
G01X1019435Y47600D02*
G02X1019429Y46211I1215J-700D01*
G03X1018734Y46214I-348J-196D01*
G02X1018740Y47603I-1215J700D01*
G03X1019435Y47600I348J196D01*
G37*
G36*
G01X1266336Y46199D02*
G02X1266158Y47939I-1179J758D01*
G03X1266780Y48003I285J280D01*
G02X1266958Y46263I1179J-758D01*
G03X1266336Y46199I-285J-280D01*
G37*
G36*
G01X12467Y48308D02*
G02X10328Y48015I-928J-1181D01*
G03X10270Y48551I-323J236D01*
G02X10187Y48631I931J1049D01*
G03X9632Y48653I-289J-277D01*
G02X9713Y50669I-932J1047D01*
G03X10268Y50647I289J277D01*
G02X12303Y50466I932J-1047D01*
G03X12926Y50459I314J247D01*
G02X12773Y48910I1084J-889D01*
G03X12422Y48913I-176J-94D01*
G02X12378Y48840I-1222J687D01*
G03X12467Y48308I336J-217D01*
G37*
G36*
G01X-8844Y50087D02*
G02X-8845Y51712I-1143J812D01*
G03X-8193I326J232D01*
G02X-8192Y50087I1143J-812D01*
G03X-8844I-326J-232D01*
G37*
G36*
G01X362540Y54128D02*
G02X360135Y53801I-1322J714D01*
G03X359574Y53817I-289J-277D01*
G02Y55867I-956J1025D01*
G03X360135Y55883I272J293D01*
G02X360291Y56024I1083J-1041D01*
G01X360368Y56084D01*
Y56382D01*
X360116D01*
Y63484D01*
X362320D01*
Y56382D01*
X362068D01*
Y56084D01*
X362145Y56024D01*
G02X362540Y55556I-926J-1183D01*
G03X363243I352J190D01*
G02X363638Y56024I1321J-715D01*
G01X363715Y56084D01*
Y56382D01*
X363464D01*
Y63484D01*
X365666D01*
Y56382D01*
X365415D01*
Y56084D01*
X365492Y56024D01*
G02X363243Y54128I-927J-1182D01*
G03X362540I-351J-190D01*
G37*
G36*
G01X1012148D02*
G02X1009743Y53801I-1322J714D01*
G03X1009182Y53817I-289J-277D01*
G02Y55867I-956J1025D01*
G03X1009743Y55883I272J293D01*
G02X1009899Y56024I1083J-1041D01*
G01X1009976Y56084D01*
Y56382D01*
X1009724D01*
Y63484D01*
X1011928D01*
Y56382D01*
X1011676D01*
Y56084D01*
X1011753Y56024D01*
G02X1012148Y55556I-926J-1183D01*
G03X1012851I352J190D01*
G02X1013246Y56024I1321J-715D01*
G01X1013323Y56084D01*
Y56382D01*
X1013072D01*
Y63484D01*
X1015274D01*
Y56382D01*
X1015023D01*
Y56084D01*
X1015100Y56024D01*
G02X1012851Y54128I-927J-1182D01*
G03X1012148I-352J-190D01*
G37*
G36*
G01X397260Y56014D02*
X397350Y56074D01*
Y56382D01*
X396928D01*
Y63484D01*
X399130D01*
Y56382D01*
X398708D01*
Y56074D01*
X398798Y56014D01*
G02X397260I-769J-1172D01*
G37*
G36*
G01X407300D02*
X407390Y56074D01*
Y56382D01*
X406968D01*
Y63484D01*
X409170D01*
Y56382D01*
X408748D01*
Y56074D01*
X408838Y56014D01*
G02X407300I-769J-1172D01*
G37*
G36*
G01X424032D02*
X424122Y56074D01*
Y56382D01*
X423700D01*
Y63484D01*
X425902D01*
Y56382D01*
X425480D01*
Y56074D01*
X425570Y56014D01*
G02X424032I-769J-1172D01*
G37*
G36*
G01X430725D02*
X430815Y56074D01*
Y56382D01*
X430392D01*
Y63484D01*
X432596D01*
Y56382D01*
X432173D01*
Y56074D01*
X432263Y56014D01*
G02X430725I-769J-1172D01*
G37*
G36*
G01X1046868D02*
X1046958Y56074D01*
Y56382D01*
X1046536D01*
Y63484D01*
X1048738D01*
Y56382D01*
X1048316D01*
Y56074D01*
X1048406Y56014D01*
G02X1046868I-769J-1172D01*
G37*
G36*
G01X1056908D02*
X1056998Y56074D01*
Y56382D01*
X1056576D01*
Y63484D01*
X1058778D01*
Y56382D01*
X1058356D01*
Y56074D01*
X1058446Y56014D01*
G02X1056908I-769J-1172D01*
G37*
G36*
G01X1073640D02*
X1073730Y56074D01*
Y56382D01*
X1073308D01*
Y63484D01*
X1075510D01*
Y56382D01*
X1075088D01*
Y56074D01*
X1075178Y56014D01*
G02X1073640I-769J-1172D01*
G37*
G36*
G01X1080333D02*
X1080423Y56074D01*
Y56382D01*
X1080000D01*
Y63484D01*
X1082204D01*
Y56382D01*
X1081781D01*
Y56074D01*
X1081871Y56014D01*
G02X1080333I-769J-1172D01*
G37*
G36*
G01X306886Y56016D02*
X306974Y56076D01*
Y56382D01*
X306574D01*
Y63484D01*
X308776D01*
Y56382D01*
X308376D01*
Y56076D01*
X308464Y56016D01*
G02X306886I-789J-1159D01*
G37*
G36*
G01X313579D02*
X313667Y56076D01*
Y56382D01*
X313266D01*
Y63484D01*
X315470D01*
Y56382D01*
X315069D01*
Y56076D01*
X315157Y56016D01*
G02X313579I-789J-1159D01*
G37*
G36*
G01X320272D02*
X320360Y56076D01*
Y56382D01*
X319960D01*
Y63484D01*
X322162D01*
Y56382D01*
X321762D01*
Y56076D01*
X321850Y56016D01*
G02X320272I-789J-1159D01*
G37*
G36*
G01X323618D02*
X323706Y56076D01*
Y56382D01*
X323306D01*
Y63484D01*
X325508D01*
Y56382D01*
X325108D01*
Y56076D01*
X325196Y56016D01*
G02X323618I-789J-1159D01*
G37*
G36*
G01X330311D02*
X330399Y56076D01*
Y56382D01*
X329998D01*
Y63484D01*
X332202D01*
Y56382D01*
X331801D01*
Y56076D01*
X331889Y56016D01*
G02X330311I-789J-1159D01*
G37*
G36*
G01X333658D02*
X333746Y56076D01*
Y56382D01*
X333346D01*
Y63484D01*
X335548D01*
Y56382D01*
X335148D01*
Y56076D01*
X335236Y56016D01*
G02X333658I-789J-1159D01*
G37*
G36*
G01X340351D02*
X340439Y56076D01*
Y56382D01*
X340038D01*
Y63484D01*
X342242D01*
Y56382D01*
X341841D01*
Y56076D01*
X341929Y56016D01*
G02X340351I-789J-1159D01*
G37*
G36*
G01X343697D02*
X343785Y56076D01*
Y56382D01*
X343384D01*
Y63484D01*
X345588D01*
Y56382D01*
X345187D01*
Y56076D01*
X345275Y56016D01*
G02X343697I-789J-1159D01*
G37*
G36*
G01X350390D02*
X350478Y56076D01*
Y56382D01*
X350078D01*
Y63484D01*
X352280D01*
Y56382D01*
X351880D01*
Y56076D01*
X351968Y56016D01*
G02X350390I-789J-1159D01*
G37*
G36*
G01X353737D02*
X353825Y56076D01*
Y56382D01*
X353424D01*
Y63484D01*
X355626D01*
Y56382D01*
X355227D01*
Y56076D01*
X355315Y56016D01*
G02X353737I-789J-1159D01*
G37*
G36*
G01X403934D02*
X404022Y56076D01*
Y56382D01*
X403620D01*
Y63484D01*
X405824D01*
Y56382D01*
X405424D01*
Y56076D01*
X405512Y56016D01*
G02X403934I-789J-1159D01*
G37*
G36*
G01X413974D02*
X414062Y56076D01*
Y56382D01*
X413660D01*
Y63484D01*
X415864D01*
Y56382D01*
X415464D01*
Y56076D01*
X415552Y56016D01*
G02X413974I-789J-1159D01*
G37*
G36*
G01X420667D02*
X420755Y56076D01*
Y56382D01*
X420354D01*
Y63484D01*
X422556D01*
Y56382D01*
X422157D01*
Y56076D01*
X422245Y56016D01*
G02X420667I-789J-1159D01*
G37*
G36*
G01X956494D02*
X956582Y56076D01*
Y56382D01*
X956182D01*
Y63484D01*
X958384D01*
Y56382D01*
X957984D01*
Y56076D01*
X958072Y56016D01*
G02X956494I-789J-1159D01*
G37*
G36*
G01X963187D02*
X963275Y56076D01*
Y56382D01*
X962874D01*
Y63484D01*
X965078D01*
Y56382D01*
X964677D01*
Y56076D01*
X964765Y56016D01*
G02X963187I-789J-1159D01*
G37*
G36*
G01X969880D02*
X969968Y56076D01*
Y56382D01*
X969568D01*
Y63484D01*
X971770D01*
Y56382D01*
X971370D01*
Y56076D01*
X971458Y56016D01*
G02X969880I-789J-1159D01*
G37*
G36*
G01X973226D02*
X973314Y56076D01*
Y56382D01*
X972914D01*
Y63484D01*
X975116D01*
Y56382D01*
X974716D01*
Y56076D01*
X974804Y56016D01*
G02X973226I-789J-1159D01*
G37*
G36*
G01X979919D02*
X980007Y56076D01*
Y56382D01*
X979606D01*
Y63484D01*
X981810D01*
Y56382D01*
X981409D01*
Y56076D01*
X981497Y56016D01*
G02X979919I-789J-1159D01*
G37*
G36*
G01X983266D02*
X983354Y56076D01*
Y56382D01*
X982954D01*
Y63484D01*
X985156D01*
Y56382D01*
X984756D01*
Y56076D01*
X984844Y56016D01*
G02X983266I-789J-1159D01*
G37*
G36*
G01X989959D02*
X990047Y56076D01*
Y56382D01*
X989646D01*
Y63484D01*
X991850D01*
Y56382D01*
X991449D01*
Y56076D01*
X991537Y56016D01*
G02X989959I-789J-1159D01*
G37*
G36*
G01X993305D02*
X993393Y56076D01*
Y56382D01*
X992992D01*
Y63484D01*
X995196D01*
Y56382D01*
X994795D01*
Y56076D01*
X994883Y56016D01*
G02X993305I-789J-1159D01*
G37*
G36*
G01X999998D02*
X1000086Y56076D01*
Y56382D01*
X999686D01*
Y63484D01*
X1001888D01*
Y56382D01*
X1001488D01*
Y56076D01*
X1001576Y56016D01*
G02X999998I-789J-1159D01*
G37*
G36*
G01X1003345D02*
X1003433Y56076D01*
Y56382D01*
X1003032D01*
Y63484D01*
X1005234D01*
Y56382D01*
X1004835D01*
Y56076D01*
X1004923Y56016D01*
G02X1003345I-789J-1159D01*
G37*
G36*
G01X1053542D02*
X1053630Y56076D01*
Y56382D01*
X1053228D01*
Y63484D01*
X1055432D01*
Y56382D01*
X1055032D01*
Y56076D01*
X1055120Y56016D01*
G02X1053542I-789J-1159D01*
G37*
G36*
G01X1063582D02*
X1063670Y56076D01*
Y56382D01*
X1063268D01*
Y63484D01*
X1065472D01*
Y56382D01*
X1065072D01*
Y56076D01*
X1065160Y56016D01*
G02X1063582I-789J-1159D01*
G37*
G36*
G01X1070275D02*
X1070363Y56076D01*
Y56382D01*
X1069962D01*
Y63484D01*
X1072164D01*
Y56382D01*
X1071765D01*
Y56076D01*
X1071853Y56016D01*
G02X1070275I-789J-1159D01*
G37*
G36*
G01X437396D02*
X437483Y56076D01*
Y56382D01*
X437086D01*
Y63484D01*
X439288D01*
Y56382D01*
X438891D01*
Y56076D01*
X438978Y56016D01*
G02X437396I-791J-1157D01*
G37*
G36*
G01X444089D02*
X444176Y56076D01*
Y56382D01*
X443778D01*
Y63484D01*
X445982D01*
Y56382D01*
X445584D01*
Y56076D01*
X445671Y56016D01*
G02X444089I-791J-1157D01*
G37*
G36*
G01X1087004D02*
X1087091Y56076D01*
Y56382D01*
X1086694D01*
Y63484D01*
X1088896D01*
Y56382D01*
X1088499D01*
Y56076D01*
X1088586Y56016D01*
G02X1087004I-791J-1157D01*
G37*
G36*
G01X1093697D02*
X1093784Y56076D01*
Y56382D01*
X1093386D01*
Y63484D01*
X1095590D01*
Y56382D01*
X1095192D01*
Y56076D01*
X1095279Y56016D01*
G02X1093697I-791J-1157D01*
G37*
G36*
G01X114508Y56436D02*
G02X112892Y55842I-426J-1336D01*
G03X112674Y56434I-339J211D01*
G02X114290Y57028I426J1336D01*
G03X114508Y56436I339J-211D01*
G37*
G36*
G01X1393023Y54549D02*
G02X1391273Y56726I-972J1010D01*
G03Y57392I-222J333D01*
G02X1393023Y59569I778J1167D01*
G03X1393577I277J288D01*
G02X1395523I973J-1010D01*
G03X1396077I277J288D01*
G02X1397827Y57392I972J-1010D01*
G03Y56726I222J-333D01*
G02X1396077Y54549I-778J-1167D01*
G03X1395523I-277J-288D01*
G02X1393577I-973J1010D01*
G03X1393023I-277J-288D01*
G37*
G36*
G01X2629Y57596D02*
G02X1052Y57616I-803J-1149D01*
G03X1060Y58277I-221J333D01*
G02X2637Y58257I803J1149D01*
G03X2629Y57596I221J-333D01*
G37*
G36*
G01X81777Y59667D02*
G02X80223I-777J-1167D01*
G03Y60333I-222J333D01*
G02X81777I777J1167D01*
G03Y59667I222J-333D01*
G37*
G36*
G01X-7239Y59518D02*
G02X-9396Y60971I-1371J292D01*
G03X-9343Y61590I-224J331D01*
G02X-9771Y62657I973J1010D01*
G03X-10237Y63068I-400J16D01*
G02X-11672Y63728I-234J1382D01*
G03X-12369Y63708I-343J-206D01*
G02X-12408Y65082I-1241J652D01*
G03X-11711Y65102I343J206D01*
G02X-10689Y65835I1241J-652D01*
G03X-10449Y66492I-62J395D01*
G02X-9171Y66025I1060J918D01*
G03X-9411Y65368I62J-395D01*
G02X-9069Y64393I-1059J-919D01*
G03X-8603Y63982I400J-16D01*
G02X-6972Y62710I233J-1382D01*
G03X-6449Y62362I398J32D01*
G02X-6662Y59789I439J-1332D01*
G03X-7239Y59518I-186J-354D01*
G37*
G36*
G01X381727Y61396D02*
G02X380164Y61350I-747J-1186D01*
G03X380145Y62014I-233J326D01*
G02X381708Y62060I747J1186D01*
G03X381727Y61396I233J-326D01*
G37*
G36*
G01X1875282Y59842D02*
G02X1875079Y61138I-1326J456D01*
G03X1875777Y61248I320J240D01*
G02X1875980Y59952I1326J-456D01*
G03X1875282Y59842I-320J-240D01*
G37*
G36*
G01X1393350Y64127D02*
G02X1391442Y66175I-1011J971D01*
G03X1391400Y66821I-256J308D01*
G02X1393262Y68858I749J1185D01*
G03X1393906Y68870I318J243D01*
G02X1396023Y69069I1144J-811D01*
G03X1396577I277J288D01*
G02X1398345Y66904I972J-1011D01*
G03X1398342Y66247I227J-330D01*
G02X1396528Y64127I-802J-1149D01*
G03X1395950I-289J-277D01*
G02X1393928I-1011J971D01*
G03X1393350I-289J-277D01*
G37*
G36*
G01X656573Y65090D02*
G02X654823Y67267I-972J1010D01*
G03Y67933I-222J333D01*
G02X656573Y70110I778J1167D01*
G03X657127I277J288D01*
G02X658877Y67933I972J-1010D01*
G03Y67267I222J-333D01*
G02X657127Y65090I-778J-1167D01*
G03X656573I-277J-288D01*
G37*
G36*
G01X1665360Y70935D02*
G02X1663340I-1010J-973D01*
G03Y71489I-288J277D01*
G02X1663233Y71615I1013J969D01*
G03X1662885Y71561I-159J-121D01*
G02X1661123Y70697I-1322J467D01*
G03X1660598Y70311I-125J-380D01*
G02X1659636Y71622I-1402J-20D01*
G03X1660161Y72008I125J380D01*
G02X1660178Y72245I1402J19D01*
G03X1659870Y72443I-198J31D01*
G02X1658127Y72604I-771J1171D01*
G03X1657573I-277J-288D01*
G02Y74624I-973J1010D01*
G03X1658127I277J288D01*
G02X1660500Y73684I973J-1010D01*
G03X1661047Y73332I399J20D01*
G02X1662513Y73059I516J-1304D01*
G03X1663132Y73155I271J294D01*
G02X1665360Y71489I1219J-693D01*
G03Y70935I288J-277D01*
G37*
G36*
G01X1767991Y71341D02*
G02X1767899Y69490I1259J-990D01*
G03X1767268Y69547I-338J-215D01*
G02X1767358Y71346I-1028J953D01*
G03X1767991Y71341I318J242D01*
G37*
G36*
G01X1931270Y69302D02*
G02X1928934Y71490I-1119J1146D01*
G03X1928897Y72050I-303J261D01*
G02X1928674Y72293I1062J1199D01*
G03X1928028Y72288I-321J-239D01*
G02X1927949Y74025I-1138J819D01*
G03X1928592Y74080I301J263D01*
G02X1931043Y74429I1369J-833D01*
G03X1931596Y74441I270J295D01*
G02X1933807Y74496I1134J-1131D01*
G03X1934331Y74483I269J296D01*
G02X1934965Y74802I1019J-1236D01*
G03X1935236Y75350I-96J388D01*
G02X1937806Y77151I1470J637D01*
G03X1938359Y77154I275J291D01*
G02X1940623Y77112I1111J-1154D01*
G03X1941207Y77120I288J277D01*
G02X1943433Y77256I1183J-1080D01*
G03X1943959Y77260I261J303D01*
G02X1946524Y75509I1061J-1200D01*
G03X1946790Y74987I376J-137D01*
G02X1947390Y74665I-440J-1540D01*
G03X1947910Y74666I259J304D01*
G02X1947911Y72230I1041J-1218D01*
G03X1947391Y72229I-259J-304D01*
G02X1945271Y72263I-1041J1218D01*
G03X1944711Y72243I-270J-295D01*
G02X1944641Y72174I-1159J1106D01*
G03X1944663Y71863I136J-147D01*
G02X1942630Y69402I-913J-1316D01*
G03X1942070I-280J-286D01*
G02X1939871Y69363I-1120J1145D01*
G03X1939311Y69343I-270J-295D01*
G02X1937110Y69229I-1161J1104D01*
G03X1936590I-260J-304D01*
G02X1934510I-1040J1218D01*
G03X1933990I-260J-304D01*
G02X1931830Y69302I-1040J1218D01*
G03X1931270I-280J-286D01*
G37*
G36*
G01X1613948Y71562D02*
G02X1613859Y70164I1167J-776D01*
G03X1613167Y70208I-359J-178D01*
G02X1613256Y71606I-1167J776D01*
G03X1613948Y71562I359J178D01*
G37*
G36*
G01X1585945Y70110D02*
G02X1585874Y71675I-1197J730D01*
G03X1586537Y71704I322J238D01*
G02X1586608Y70139I1197J-730D01*
G03X1585945Y70110I-322J-238D01*
G37*
G36*
G01X650973Y71290D02*
G02X649223Y73467I-972J1010D01*
G03Y74133I-222J333D01*
G02X650973Y76310I778J1167D01*
G03X651527I277J288D01*
G02X653277Y74133I972J-1010D01*
G03Y73467I222J-333D01*
G02X651527Y71290I-778J-1167D01*
G03X650973I-277J-288D01*
G37*
G36*
G01X657473D02*
G02X655723Y73467I-972J1010D01*
G03Y74133I-222J333D01*
G02X657473Y76310I778J1167D01*
G03X658027I277J288D01*
G02X659777Y74133I972J-1010D01*
G03Y73467I222J-333D01*
G02X658027Y71290I-778J-1167D01*
G03X657473I-277J-288D01*
G37*
G36*
G01X1592905Y76213D02*
G02X1590493Y74840I-1305J-513D01*
G03X1589907Y74890I-316J-245D01*
G02X1590069Y76786I-945J1036D01*
G03X1590655Y76736I316J245D01*
G02X1591385Y77085I944J-1037D01*
G03X1591695Y77627I-62J395D01*
G02X1593215Y76755I1305J513D01*
G03X1592905Y76213I62J-395D01*
G37*
G36*
G01X80403Y77220D02*
G02X78872Y77105I-678J-1227D01*
G03X78822Y77773I-243J318D01*
G02X78723Y80167I678J1227D01*
G03Y80833I-222J333D01*
G02X80277I777J1167D01*
G03Y80167I222J-333D01*
G02X80353Y77888I-777J-1167D01*
G03X80403Y77220I243J-318D01*
G37*
G36*
G01X1408457Y76508D02*
G02X1406582Y78504I-1157J792D01*
G03X1406729Y79037I-205J343D01*
G02X1406651Y79208I1234J666D01*
G03X1406277I-187J-70D01*
G02X1403617Y80088I-1313J492D01*
G03X1403239Y80598I-385J110D01*
G02X1404431Y82777I25J1402D01*
G03X1405097I333J222D01*
G02X1407431I1167J-777D01*
G03X1408097I333J222D01*
G02X1409588Y80636I1167J-777D01*
G03X1409300Y80126I93J-389D01*
G02X1408682Y78496I-1336J-426D01*
G03X1408535Y77963I205J-343D01*
G02X1408549Y77938I-1216J-697D01*
G03X1408911Y77950I178J91D01*
G02X1409100Y76530I1289J-551D01*
G03X1408457Y76508I-313J-248D01*
G37*
G36*
G01X6314Y78585D02*
G02X4763Y78637I-815J-1141D01*
G03X4786Y79303I-210J341D01*
G02X6337Y79251I815J1141D01*
G03X6314Y78585I210J-341D01*
G37*
G36*
G01X120987Y83824D02*
G03X121299Y83174I312J-250D01*
G01X121374D01*
Y76072D01*
X119172D01*
Y83174D01*
X119192D01*
Y83480D01*
X119105Y83540D01*
G02X120987Y83824I787J1160D01*
G37*
G36*
G01X444050Y86566D02*
G03X444540Y86177I400J1D01*
G02X445807Y83532I340J-1463D01*
G01X445730Y83472D01*
Y83174D01*
X445982D01*
Y76072D01*
X443778D01*
Y83174D01*
X444030D01*
Y83472D01*
X443953Y83532D01*
G02X443383Y84591I927J1182D01*
G03X442702Y84841I-399J-33D01*
G01X439511Y81650D01*
X439288D01*
Y76072D01*
X437086D01*
Y81650D01*
X435942D01*
Y76072D01*
X433738D01*
Y81650D01*
X429248D01*
Y76072D01*
X427046D01*
Y81650D01*
X415864D01*
Y76072D01*
X413660D01*
Y81650D01*
X405824D01*
Y76072D01*
X403620D01*
Y81650D01*
X402478D01*
Y76072D01*
X400274D01*
Y81650D01*
X395784D01*
Y76072D01*
X393582D01*
Y82258D01*
X392350Y83489D01*
Y89611D01*
X396928Y94188D01*
Y101284D01*
X399130D01*
Y95450D01*
X403620D01*
Y101284D01*
X405824D01*
Y95450D01*
X406968D01*
Y101284D01*
X409170D01*
Y95450D01*
X413660D01*
Y101284D01*
X415864D01*
Y95450D01*
X420354D01*
Y101284D01*
X422556D01*
Y95450D01*
X423700D01*
Y101284D01*
X425902D01*
Y95450D01*
X430392D01*
Y101284D01*
X432596D01*
Y95450D01*
X437086D01*
Y101284D01*
X439288D01*
Y95450D01*
X443011D01*
X443096Y95365D01*
G03X443778Y95648I282J283D01*
G01Y101284D01*
X445982D01*
Y94182D01*
X444450D01*
Y91789D01*
X444301Y91640D01*
X444516Y91425D01*
X444619Y91443D01*
G02X444540Y88501I261J-1479D01*
G03X444050Y88112I-90J-390D01*
G01Y86566D01*
G37*
G36*
G01X768120Y84453D02*
G03X767526Y84729I-394J-70D01*
G02X765913Y84877I-702J1214D01*
G03X765271Y84690I-260J-304D01*
G02X764841Y86166I-1341J410D01*
G03X765483Y86353I260J304D01*
G02X768204Y86190I1341J-410D01*
G03X768798Y85914I394J70D01*
G02X770595Y83824I702J-1214D01*
G03X770907Y83174I312J-250D01*
G01X770982D01*
Y76072D01*
X768780D01*
Y83174D01*
X768800D01*
Y83480D01*
X768713Y83540D01*
G02X768120Y84453I787J1160D01*
G37*
G36*
G01X96484Y77755D02*
G02X93632Y77689I-1443J696D01*
G03X92932Y77695I-352J-191D01*
G02X92945Y79243I-1396J786D01*
G03X93645Y79237I352J191D01*
G02X96472Y79171I1396J-786D01*
G03X97190Y79177I358J179D01*
G02X97202Y77761I1443J-696D01*
G03X96484Y77755I-358J-179D01*
G37*
G36*
G01X764202Y79450D02*
G02X762559Y79422I-802J-1150D01*
G03X762548Y80070I-240J320D01*
G02X764191Y80098I802J1150D01*
G03X764202Y79450I240J-320D01*
G37*
G36*
G01X12726Y79724D02*
G02X10804Y79558I-862J-1230D01*
G03X10767Y80158I-282J284D01*
G02X10652Y80257I856J1111D01*
G03X10098I-277J-288D01*
G02X8520Y82532I-972J1010D01*
G03X8543Y83242I-172J361D01*
G02X8187Y83524I681J1226D01*
G03X7583Y83509I-296J-269D01*
G02X7538Y85343I-1083J891D01*
G03X8142Y85358I296J269D01*
G02X10198Y85477I1083J-891D01*
G03X10752I277J288D01*
G02X12330Y83202I972J-1010D01*
G03X12307Y82492I172J-361D01*
G02X12660Y80321I-682J-1225D01*
G03X12726Y79724I295J-269D01*
G37*
G36*
G01X1518409Y78143D02*
G02X1518368Y79500I-1247J641D01*
G03X1519067Y79521I344J204D01*
G02X1519077Y79539I1230J-672D01*
G03X1518914Y80079I-353J188D01*
G02X1520817Y80654I666J1234D01*
G03X1520980Y80114I353J-188D01*
G02X1519108Y78164I-666J-1234D01*
G03X1518409Y78143I-344J-204D01*
G37*
G36*
G01X-10313Y78490D02*
G02X-12501Y78378I-1139J818D01*
G03X-13089Y78389I-299J-266D01*
G02X-15075Y78348I-1013J969D01*
G03X-15629I-277J-288D01*
G02X-17612Y80331I-973J1010D01*
G03Y80885I-288J277D01*
G02X-15629Y82868I1010J973D01*
G03X-15075I277J288D01*
G02X-13053Y82788I973J-1010D01*
G03X-12465Y82777I299J266D01*
G02X-10342Y82665I1013J-969D01*
G03X-9701Y82676I316J244D01*
G02X-9678Y82707I1137J-820D01*
G03X-9733Y83251I-318J243D01*
G02X-7669Y85121I922J1057D01*
G03X-7026Y85109I326J232D01*
G02X-4846Y83347I1114J-852D01*
G03X-4835Y82814I304J-260D01*
G02X-4878Y80857I-1025J-956D01*
G03X-4894Y80302I280J-286D01*
G02X-6954Y78400I-1036J-944D01*
G03X-7538I-292J-273D01*
G02X-9672Y78501I-1024J958D01*
G03X-10313Y78490I-316J-244D01*
G37*
G36*
G01X733908Y81859D02*
G02X733868Y83450I-1174J766D01*
G03X734526Y83467I323J236D01*
G02X734566Y81876I1174J-766D01*
G03X733908Y81859I-323J-236D01*
G37*
G36*
G01X1364500Y92586D02*
X1364000Y92086D01*
Y85586D01*
X1361914Y83500D01*
X1361299D01*
G03X1360900Y83078I0J-400D01*
G02X1358426Y83901I-1400J-78D01*
G01X1358544Y84042D01*
X1358000Y84586D01*
Y84941D01*
G03X1357467Y85318I-400J0D01*
G02X1355598Y86609I-467J1322D01*
G03X1355198Y87000I-400J-9D01*
G01X1351914D01*
X1349414Y84500D01*
X1348927D01*
G03X1348610Y83856I0J-400D01*
G02X1346390I-1110J-856D01*
G03X1346073Y84500I-317J244D01*
G01X1344414D01*
X1342914Y83000D01*
X1339086D01*
X1337500Y84586D01*
Y87914D01*
X1339086Y89500D01*
X1340086D01*
X1340500Y89914D01*
Y91000D01*
X1332851D01*
X1330351Y89000D01*
X1323000D01*
Y99414D01*
X1323729Y100143D01*
X1323738Y100208D01*
G02X1324918Y101388I1387J-207D01*
G01X1324983Y101397D01*
X1329086Y105500D01*
X1340414D01*
X1341914Y104000D01*
X1343201D01*
G03X1343600Y104422I0J400D01*
G02X1344470Y105798I1400J78D01*
G03X1344581Y106470I-151J370D01*
G02X1346030Y106231I919J1059D01*
G03X1345919Y105559I151J-370D01*
G02X1346400Y104422I-919J-1059D01*
G03X1346799Y104000I399J-22D01*
G01X1359914D01*
X1364500Y99414D01*
Y98042D01*
G03X1364700Y97842I200J0D01*
G02Y95038I0J-1402D01*
G03X1364500Y94838I0J-200D01*
G01Y92586D01*
G37*
G36*
G01X99998Y84565D02*
G02X98747Y83325I142J-1395D01*
G03X98122Y83698I-398J44D01*
G02X99631Y85193I-3439J4980D01*
G03X99998Y84565I327J-230D01*
G37*
G36*
G01X1574210Y83318D02*
G02X1574165Y84982I-1150J802D01*
G03X1574809Y85000I315J246D01*
G02X1574854Y83336I1150J-802D01*
G03X1574210Y83318I-315J-246D01*
G37*
G36*
G01X648982Y84439D02*
G02X646223Y84462I-1382J-239D01*
G03X645912Y84928I-393J74D01*
G02X645190Y87273I288J1372D01*
G03Y87827I-288J277D01*
G02X647367Y89577I1010J972D01*
G03X648033I333J222D01*
G02X648721Y90117I1166J-778D01*
G03X648943Y90668I-137J376D01*
G02X648914Y90733I1266J604D01*
G03X648270Y90866I-368J-157D01*
G02X646161Y91070I-966J1016D01*
G03X645628Y91181I-326J-231D01*
G02X646047Y93194I-724J1201D01*
G03X646580Y93083I326J231D01*
G02X648594Y92431I724J-1201D01*
G03X649238Y92298I368J157D01*
G02X651486Y91850I966J-1016D01*
G03X652063Y91672I366J162D01*
G02X651522Y89914I741J-1190D01*
G03X650945Y90092I-366J-162D01*
G02X650683Y89965I-739J1191D01*
G03X650461Y89414I137J-376D01*
G02X650210Y87827I-1261J-614D01*
G03Y87273I288J-277D01*
G02X649337Y84905I-1010J-973D01*
G03X648982Y84439I39J-398D01*
G37*
G36*
G01X1318622Y84134D02*
G02X1316250Y85529I-1322J466D01*
G03X1316227Y86084I-299J266D01*
G02X1316228Y88114I968J1015D01*
G03X1316252Y88669I-275J290D01*
G02X1318267Y88584I1049J931D01*
G03X1318243Y88029I275J-290D01*
G02X1318245Y86169I-1048J-931D01*
G03X1318268Y85614I299J-266D01*
G02X1318278Y85605I-933J-1047D01*
G03X1318615Y85717I140J143D01*
G02X1319222Y84334I1385J-217D01*
G03X1318622Y84134I-222J-333D01*
G37*
G36*
G01X1758640Y84149D02*
G02X1758460Y85705I-1245J644D01*
G03X1759119Y85781I304J260D01*
G02X1759299Y84225I1245J-644D01*
G03X1758640Y84149I-304J-260D01*
G37*
G36*
G01X714182Y87090D02*
G02X712274Y86956I-882J-1090D01*
G03X712233Y87539I-293J272D01*
G02X714330Y89329I882J1090D01*
G03X715030Y89341I347J199D01*
G02X715053Y87983I1238J-658D01*
G03X714353Y87971I-347J-199D01*
G02X714141Y87673I-1239J657D01*
G03X714182Y87090I293J-272D01*
G37*
G36*
G01X707312Y87073D02*
G02X704606Y86976I-1340J-413D01*
G03X704134Y87458I-389J91D01*
G02X705211Y88514I-289J1372D01*
G03X705683Y88032I389J-91D01*
G02X705688Y88033I277J-1374D01*
G03X705989Y88542I-81J392D01*
G02X707613Y87582I1340J413D01*
G03X707312Y87073I81J-392D01*
G37*
G36*
G01X1676511Y87846D02*
G02X1676437Y86108I1062J-916D01*
G03X1675811Y86134I-323J-235D01*
G02X1675885Y87872I-1062J916D01*
G03X1676511Y87846I323J235D01*
G37*
G36*
G01X7750Y87098D02*
G02X7648Y88832I-1150J802D01*
G03X8275Y88869I299J265D01*
G02X10398Y89077I1150J-802D01*
G03X10952I277J288D01*
G02Y87057I973J-1010D01*
G03X10398I-277J-288D01*
G02X8377Y87135I-973J1010D01*
G03X7750Y87098I-299J-265D01*
G37*
G36*
G01X1312558Y92415D02*
G02X1310554Y92409I-999J-984D01*
G03X1310552Y92968I-287J278D01*
G02X1310472Y93057I1002J981D01*
G03X1310152Y93039I-153J-128D01*
G02X1308161Y94950I-1168J775D01*
G03X1308159Y95600I-234J324D01*
G02X1309794Y95606I813J1142D01*
G03X1309796Y94956I234J-324D01*
G02X1309929Y94848I-815J-1140D01*
G03X1310499Y94879I270J295D01*
G02X1312556Y92974I1052J-927D01*
G03X1312558Y92415I287J-278D01*
G37*
G36*
G01X1377332Y92806D02*
G02X1377230Y91313I1132J-827D01*
G03X1376554Y91358I-352J-190D01*
G02X1376656Y92853I-1142J829D01*
G03X1377332Y92806I353J189D01*
G37*
G36*
G01X1455416Y93465D02*
G02X1454081Y92667I-69J-1400D01*
G03X1453740Y93239I-361J172D01*
G02X1455075Y94037I69J1400D01*
G03X1455416Y93465I361J-172D01*
G37*
G36*
G01X692056Y93537D02*
G02X691687Y92008I944J-1037D01*
G03X691044Y92163I-374J-141D01*
G02X691413Y93692I-944J1037D01*
G03X692056Y93537I374J141D01*
G37*
G36*
G01X110302Y92129D02*
G02X110107Y93703I-1245J645D01*
G03X110762Y93784I300J265D01*
G02X110957Y92210I1245J-645D01*
G03X110302Y92129I-300J-265D01*
G37*
G36*
G01X733219Y93291D02*
G02X732024Y94187I-1309J-501D01*
G03X732431Y94729I33J399D01*
G02X733626Y93833I1309J501D01*
G03X733219Y93291I-33J-399D01*
G37*
G36*
G01X1296358Y95487D02*
G02X1294804I-777J-1167D01*
G03Y96153I-222J333D01*
G02X1296358I777J1167D01*
G03Y95487I222J-333D01*
G37*
G36*
G01X1693483Y93884D02*
G02X1693432Y95418I-1198J728D01*
G03X1694102Y95440I328J229D01*
G02X1696313Y95681I1198J-728D01*
G03X1696868Y95659I289J277D01*
G02X1696787Y93643I932J-1047D01*
G03X1696232Y93665I-289J-277D01*
G02X1694153Y93906I-932J1047D01*
G03X1693483Y93884I-328J-229D01*
G37*
G36*
G01X1573433Y96756D02*
G02X1571776Y96784I-848J-1117D01*
G03X1571787Y97429I-231J327D01*
G02X1573444Y97401I848J1117D01*
G03X1573433Y96756I231J-327D01*
G37*
G36*
G01X1746712Y97034D02*
G02X1745151Y95238I-221J-1384D01*
G03X1744487Y95404I-382J-118D01*
G02X1743575Y97800I-987J996D01*
G03X1743989Y98277I22J399D01*
G02X1746462Y97678I1375J273D01*
G03X1746712Y97034I313J-249D01*
G37*
G36*
G01X1289548Y96543D02*
G02Y98097I-1167J777D01*
G03X1290214I333J222D01*
G02Y96543I1167J-777D01*
G03X1289548I-333J-222D01*
G37*
G36*
G01X1945567Y98870D02*
G02X1945553Y97453I1203J-720D01*
G03X1944863Y97460I-347J-199D01*
G02X1944877Y98877I-1203J720D01*
G03X1945567Y98870I347J199D01*
G37*
G36*
G01X1723995Y99775D02*
G02X1722633I-681J-1225D01*
G03Y100475I-194J350D01*
G02Y102925I681J1225D01*
G03Y103625I-194J350D01*
G02X1722089Y104169I681J1225D01*
G03X1721389I-350J-194D01*
G02X1718939I-1225J681D01*
G03X1718239I-350J-194D01*
G02Y105531I-1225J681D01*
G03X1718939I350J194D01*
G02X1719483Y106075I1225J-681D01*
G03Y106775I-194J350D01*
G02X1721389Y108681I681J1225D01*
G03X1722089I350J194D01*
G02X1723995Y106775I1225J-681D01*
G03Y106075I194J-350D01*
G02Y103625I-681J-1225D01*
G03Y102925I194J-350D01*
G02Y100475I-681J-1225D01*
G03Y99775I194J-350D01*
G37*
G36*
G01X1736595Y102925D02*
G02X1735233I-681J-1225D01*
G03Y103625I-194J350D01*
G02Y106075I681J1225D01*
G03Y106775I-194J350D01*
G02X1736595I681J1225D01*
G03Y106075I194J-350D01*
G02Y103625I-681J-1225D01*
G03Y102925I194J-350D01*
G37*
G36*
G01X1269667Y101323D02*
G02X1267570Y103149I-1167J777D01*
G03X1267592Y103726I-266J299D01*
G02X1269724Y105538I1008J975D01*
G03X1270366I321J239D01*
G02X1272465Y103692I1124J-839D01*
G03X1272467Y103115I278J-288D01*
G02X1270333Y101323I-967J-1015D01*
G03X1269667I-333J-222D01*
G37*
G36*
G01X1875618Y103538D02*
G02X1874255Y104598I-1360J-342D01*
G03X1874641Y105096I-2J400D01*
G02X1876004Y104036I1360J342D01*
G03X1875618Y103538I2J-400D01*
G37*
G36*
G01X74915Y103760D02*
G02Y106240I-2115J1240D01*
G03X75606I346J202D01*
G02X79837Y106239I2115J-1240D01*
G03X80527I345J202D01*
G02X84758Y106240I2116J-1239D01*
G03X85449I345J202D01*
G02X89679I2115J-1240D01*
G03X90370I346J202D01*
G02X94600I2115J-1240D01*
G03X95291I345J202D01*
G02X99522Y106239I2115J-1240D01*
G03X100212I345J202D01*
G02X104443Y106240I2116J-1239D01*
G03X105134I345J202D01*
G02Y103760I2115J-1240D01*
G03X104443I-345J-202D01*
G02X100212Y103761I-2115J1240D01*
G03X99522I-345J-202D01*
G02X95291Y103760I-2116J1239D01*
G03X94600I-345J-202D01*
G02X90370I-2115J1240D01*
G03X89679I-345J-202D01*
G02X85449I-2115J1240D01*
G03X84758I-345J-202D01*
G02X80527Y103761I-2115J1240D01*
G03X79837I-345J-202D01*
G02X75606Y103760I-2116J1239D01*
G03X74915I-345J-202D01*
G37*
G36*
G01X121118Y107644D02*
G02X119537Y107824I-921J-1057D01*
G03X119612Y108478I-188J353D01*
G02X121193Y108298I921J1057D01*
G03X121118Y107644I188J-353D01*
G37*
G36*
G01X1392517Y107705D02*
G02X1392488Y109327I-1158J791D01*
G03X1393140Y109339I322J237D01*
G02X1393502Y109702I1157J-792D01*
G03X1393504Y110359I-227J329D01*
G02X1395106Y110352I806J1147D01*
G03X1395104Y109695I227J-329D01*
G02X1393169Y107717I-806J-1147D01*
G03X1392517Y107705I-322J-237D01*
G37*
G36*
G01X1452447Y110885D02*
G02X1451038Y110235I-215J-1385D01*
G03X1450758Y110840I-341J210D01*
G02X1452167Y111490I215J1385D01*
G03X1452447Y110885I341J-210D01*
G37*
G36*
G01X1512424Y120143D02*
G02X1515446Y120153I1511J0D01*
G01Y116258D01*
X1515437Y116174D01*
G02X1514779Y115089I-1502J169D01*
G03X1514753Y114445I224J-332D01*
G02X1513046Y114477I-874J-1096D01*
G03X1513044Y115122I-237J322D01*
G02X1512424Y116343I892J1221D01*
G01Y120143D01*
G37*
G36*
G01X1258565Y115056D02*
G02X1257135I-715J-1206D01*
G03Y115744I-204J344D01*
G02X1258565I715J1206D01*
G03Y115056I204J-344D01*
G37*
G36*
G01X619388Y115330D02*
G02X618655Y114188I666J-1234D01*
G03X618066Y114566I-399J26D01*
G02X618799Y115708I-666J1234D01*
G03X619388Y115330I399J-26D01*
G37*
G36*
G01X1286893Y117099D02*
G02X1285339I-777J-1167D01*
G03Y117765I-222J333D01*
G02X1286893I777J1167D01*
G03Y117099I222J-333D01*
G37*
G36*
G01X1398444Y117893D02*
G02X1397340Y117114I156J-1393D01*
G03X1396936Y117687I-360J175D01*
G02X1398040Y118466I-156J1393D01*
G03X1398444Y117893I360J-175D01*
G37*
G36*
G01X1727145Y118675D02*
G02X1725783I-681J-1225D01*
G03Y119375I-194J350D01*
G02X1725238Y119919I680J1226D01*
G03X1724539I-350J-194D01*
G02X1722632Y121826I-1225J682D01*
G03Y122525I-194J350D01*
G02X1722089Y123069I683J1224D01*
G03X1721389I-350J-194D01*
G02Y124431I-1225J681D01*
G03X1722089I350J194D01*
G02X1722633Y124975I1225J-681D01*
G03Y125675I-194J350D01*
G02Y128125I681J1225D01*
G03Y128825I-194J350D01*
G02Y131275I681J1225D01*
G03Y131975I-194J350D01*
G02X1724539Y133881I681J1225D01*
G03X1725239I350J194D01*
G02Y132519I1225J-681D01*
G03X1724539I-350J-194D01*
G02X1723995Y131975I-1225J681D01*
G03Y131275I194J-350D01*
G02Y128825I-681J-1225D01*
G03Y128125I194J-350D01*
G02Y125675I-681J-1225D01*
G03Y124975I194J-350D01*
G02X1724539Y124431I-681J-1225D01*
G03X1725239I350J194D01*
G02X1727145Y122525I1225J-681D01*
G03Y121825I194J-350D01*
G02Y119375I-681J-1225D01*
G03Y118675I194J-350D01*
G37*
G36*
G01X1737139Y116769D02*
G02Y118131I-1225J681D01*
G03X1737839I350J194D01*
G02X1738383Y118675I1225J-681D01*
G03Y119375I-194J350D01*
G02Y121825I681J1225D01*
G03Y122525I-194J350D01*
G02X1737838Y123070I681J1226D01*
G03X1737138I-350J-194D01*
G02Y124430I-1226J680D01*
G03X1737838I350J194D01*
G02X1738383Y124975I1226J-681D01*
G03Y125675I-194J350D01*
G02Y128125I681J1225D01*
G03Y128825I-194J350D01*
G02X1740289Y130731I681J1225D01*
G03X1740989I350J194D01*
G02Y129369I1225J-681D01*
G03X1740289I-350J-194D01*
G02X1739745Y128825I-1225J681D01*
G03Y128125I194J-350D01*
G02Y125675I-681J-1225D01*
G03Y124975I194J-350D01*
G02X1740289Y124431I-681J-1225D01*
G03X1740989I350J194D01*
G02X1743439I1225J-681D01*
G03X1744139I350J194D01*
G02Y123069I1225J-681D01*
G03X1743439I-350J-194D01*
G02X1742895Y122525I-1225J681D01*
G03Y121825I194J-350D01*
G02X1740989Y119919I-681J-1225D01*
G03X1740289I-350J-194D01*
G02X1739745Y119375I-1225J681D01*
G03Y118675I194J-350D01*
G02X1737839Y116769I-681J-1225D01*
G03X1737139I-350J-194D01*
G37*
G36*
G01X1677567Y121263D02*
G02X1676205I-681J-1225D01*
G03Y121963I-194J350D01*
G02X1677567I681J1225D01*
G03Y121263I194J-350D01*
G37*
G36*
G01X1554838Y121420D02*
G02X1554273Y122169I-1337J-421D01*
G03X1554545Y122454I111J167D01*
G02X1554398Y122705I1130J830D01*
G03X1553883Y122911I-364J-164D01*
G02X1554631Y124787I-530J1298D01*
G03X1555146Y124581I364J164D01*
G02X1556219Y124576I530J-1298D01*
G03X1556757Y124830I155J369D01*
G02X1557557Y123134I1343J-403D01*
G03X1557019Y122880I-155J-369D01*
G02X1555321Y121927I-1343J403D01*
G03X1554838Y121420I-102J-387D01*
G37*
G36*
G01X1928184Y121747D02*
G02X1926314Y122480I-1292J-544D01*
G03X1926518Y123000I-165J365D01*
G02X1926888Y124600I1292J544D01*
G03X1926912Y125180I-263J301D01*
G02X1927962Y127557I1006J976D01*
G03X1928366Y128041I13J400D01*
G02X1928815Y129394I1370J296D01*
G03X1928820Y129994I-262J302D01*
G02X1930677Y129980I936J1043D01*
G03X1930672Y129380I262J-302D01*
G02X1929692Y126936I-936J-1043D01*
G03X1929288Y126452I-13J-400D01*
G02X1928840Y125100I-1370J-296D01*
G03X1928816Y124520I263J-301D01*
G02X1928388Y122267I-1006J-976D01*
G03X1928184Y121747I165J-365D01*
G37*
G36*
G01X1401422Y122341D02*
G02X1399879Y122837I-1122J-841D01*
G03X1400078Y123459I-121J381D01*
G02X1399817Y124532I1122J841D01*
G03X1399418Y124998I-394J66D01*
G02X1400783Y126168I-18J1402D01*
G03X1401182Y125702I394J-66D01*
G02X1401621Y122963I18J-1402D01*
G03X1401422Y122341I121J-381D01*
G37*
G36*
G01X1392867Y122173D02*
G02X1390923Y124117I-1167J777D01*
G03Y124783I-222J333D01*
G02Y127117I777J1167D01*
G03Y127783I-222J333D01*
G02X1392867Y129727I777J1167D01*
G03X1393533I333J222D01*
G02X1395477Y127783I1167J-777D01*
G03Y127117I222J-333D01*
G02Y124783I-777J-1167D01*
G03Y124117I222J-333D01*
G02X1393533Y122173I-777J-1167D01*
G03X1392867I-333J-222D01*
G37*
G36*
G01X1525319Y122826D02*
G02X1524803Y124449I-1319J474D01*
G03X1525409Y124642I229J328D01*
G02X1525925Y123019I1319J-474D01*
G03X1525319Y122826I-229J-328D01*
G37*
G36*
G01X3938Y126754D02*
G03X5205Y127157I-2J2199D01*
G02X9264Y125823I1488J-2314D01*
G03X10004Y125805I374J143D01*
G02Y123881I2201J-962D01*
G03X9264Y123863I-366J-161D01*
G02X5221Y122519I-2571J980D01*
G03X3967Y122932I-1283J-1786D01*
G01X3936D01*
G03X2669Y122529I2J-2199D01*
G02X2653Y127167I-1488J2314D01*
G03X3907Y126754I1283J1786D01*
G01X3938D01*
G37*
G36*
G01X1864351Y125131D02*
G02X1864331Y123808I1226J-680D01*
G03X1863626Y123819I-355J-183D01*
G02X1863646Y125142I-1226J680D01*
G03X1864351Y125131I355J183D01*
G37*
G36*
G01X1643312Y124259D02*
G02Y125621I-1225J681D01*
G03X1644012I350J194D01*
G02Y124259I1225J-681D01*
G03X1643312I-350J-194D01*
G37*
G36*
G01X1857797Y127786D02*
G02X1856243I-777J-1167D01*
G03Y128452I-222J333D01*
G02X1857797I777J1167D01*
G03Y127786I222J-333D01*
G37*
G36*
G01X1513634Y127666D02*
G02X1513388Y125945I966J-1016D01*
G03X1512766Y126034I-346J-201D01*
G02X1513012Y127755I-966J1016D01*
G03X1513634Y127666I346J201D01*
G37*
G36*
G01X1473905Y130098D02*
G02X1472295I-805J-1148D01*
G03Y130752I-230J327D01*
G02X1473905I805J1148D01*
G03Y130098I230J-327D01*
G37*
G36*
G01X1678067Y130863D02*
G02X1676705I-681J-1225D01*
G03Y131563I-194J350D01*
G02X1678067I681J1225D01*
G03Y130863I194J-350D01*
G37*
G36*
G01X1861800Y131977D02*
G02X1860194Y131952I-785J-1162D01*
G03X1860184Y132607I-234J324D01*
G02X1859998Y134780I785J1162D01*
G03Y135358I-277J289D01*
G02X1861940I971J1011D01*
G03Y134780I277J-289D01*
G02X1861790Y132632I-971J-1011D01*
G03X1861800Y131977I234J-324D01*
G37*
G36*
G01X1608070Y132487D02*
G02X1606565Y132587I-831J-1129D01*
G03X1606610Y133260I-192J351D01*
G02X1606216Y133707I831J1129D01*
G03X1605517I-349J-195D01*
G02X1603611Y135613I-1225J681D01*
G03Y136313I-194J350D01*
G02X1605517Y138220I681J1225D01*
G03X1606216I350J194D01*
G02X1608666Y138219I1225J-682D01*
G03X1609366I350J194D01*
G02X1609910Y138763I1225J-681D01*
G03Y139463I-194J350D01*
G02X1609894Y141905I681J1226D01*
G03X1609906Y142592I-199J347D01*
G02X1611342Y142566I740J1191D01*
G03X1611330Y141879I199J-347D01*
G02X1611816Y141369I-739J-1191D01*
G03X1612516I350J194D01*
G02X1614422Y139463I1225J-681D01*
G03Y138763I194J-350D01*
G02X1614423Y136313I-681J-1225D01*
G03Y135614I194J-350D01*
G02X1612516Y133708I-682J-1225D01*
G03X1611816I-350J-194D01*
G02X1609366I-1225J681D01*
G03X1608666I-350J-194D01*
G02X1608115Y133160I-1225J681D01*
G03X1608070Y132487I192J-351D01*
G37*
G36*
G01X1746868Y132851D02*
G02X1745510I-679J-1227D01*
G03Y133550I-194J350D01*
G02X1746868I679J1227D01*
G03Y132851I194J-350D01*
G37*
G36*
G01X1531353Y133302D02*
G02X1530076Y134073I-1252J-631D01*
G03X1530426Y134653I-7J400D01*
G02X1530308Y135583I1252J631D01*
G03X1529813Y136054I-391J85D01*
G02X1530819Y137109I-364J1354D01*
G03X1531314Y136638I391J-85D01*
G02X1531703Y133882I364J-1354D01*
G03X1531353Y133302I7J-400D01*
G37*
G36*
G01X1324193Y132546D02*
G02Y134100I-1167J777D01*
G03X1324859I333J222D01*
G02Y132546I1167J-777D01*
G03X1324193I-333J-222D01*
G37*
G36*
G01X1262697Y134362D02*
G02X1262517Y132923I1101J-868D01*
G03X1261838Y133008I-365J-163D01*
G02X1262018Y134447I-1101J868D01*
G03X1262697Y134362I365J163D01*
G37*
G36*
G01X1621265Y133707D02*
G02Y135069I-1225J681D01*
G03X1621965I350J194D01*
G02Y133707I1225J-681D01*
G03X1621265I-350J-194D01*
G37*
G36*
G01X1590927Y135783D02*
G02X1588569Y134355I-1047J-932D01*
G03X1588067Y134592I-374J-142D01*
G02X1588931Y136417I-447J1329D01*
G03X1589433Y136180I374J142D01*
G02X1589549Y136213I441J-1331D01*
G03X1589753Y136868I-95J389D01*
G02X1591850Y138729I1047J932D01*
G03X1592450I300J265D01*
G02Y136871I1050J-929D01*
G03X1591850I-300J-265D01*
G02X1591131Y136438I-1050J929D01*
G03X1590927Y135783I95J-389D01*
G37*
G36*
G01X1695917Y137013D02*
G02X1694555I-681J-1225D01*
G03Y137713I-194J350D01*
G02X1695917I681J1225D01*
G03Y137013I194J-350D01*
G37*
G36*
G01X1739745Y137575D02*
G02X1738383I-681J-1225D01*
G03Y138275I-194J350D01*
G02X1737839Y138819I681J1225D01*
G03X1737139I-350J-194D01*
G02Y140181I-1225J681D01*
G03X1737839I350J194D01*
G02X1738383Y140725I1225J-681D01*
G03Y141425I-194J350D01*
G02Y143875I681J1225D01*
G03Y144575I-194J350D01*
G02X1740289Y146481I681J1225D01*
G03X1740989I350J194D01*
G02X1742895Y144575I1225J-681D01*
G03Y143875I194J-350D01*
G02X1743439Y143331I-681J-1225D01*
G03X1744139I350J194D01*
G02Y141969I1225J-681D01*
G03X1743439I-350J-194D01*
G02X1740989I-1225J681D01*
G03X1740289I-350J-194D01*
G02X1739745Y141425I-1225J681D01*
G03Y140725I194J-350D01*
G02Y138275I-681J-1225D01*
G03Y137575I194J-350D01*
G37*
G36*
G01X1568792Y137816D02*
G02X1567154Y137824I-825J-1134D01*
G03X1567157Y138473I-232J326D01*
G02X1568795Y138465I825J1134D01*
G03X1568792Y137816I232J-326D01*
G37*
G36*
G01X1513514Y139046D02*
G02X1513185Y137327I911J-1065D01*
G03X1512571Y137444I-354J-187D01*
G02X1512900Y139163I-911J1065D01*
G03X1513514Y139046I354J187D01*
G37*
G36*
G01X1721389Y138819D02*
G02Y140181I-1225J681D01*
G03X1722089I350J194D01*
G02X1722633Y140725I1225J-681D01*
G03Y141425I-194J350D01*
G02X1722650Y143885I681J1225D01*
G03X1722639Y144595I-190J352D01*
G02X1722070Y145116I626J1255D01*
G03X1721381Y145105I-341J-209D01*
G02X1721358Y146534I-1217J695D01*
G03X1722047Y146545I341J209D01*
G02X1724519Y146475I1217J-695D01*
G03X1725229Y146464I358J179D01*
G02X1725209Y145175I1235J-664D01*
G03X1724499Y145186I-358J-179D01*
G02X1723928Y144615I-1235J664D01*
G03X1723939Y143905I190J-352D01*
G02X1723995Y141425I-625J-1255D01*
G03Y140725I194J-350D01*
G02X1722089Y138819I-681J-1225D01*
G03X1721389I-350J-194D01*
G37*
G36*
G01X1621265Y140006D02*
G02Y141368I-1225J681D01*
G03X1621965I350J194D01*
G02Y140006I1225J-681D01*
G03X1621265I-350J-194D01*
G37*
G36*
G01X1952235Y142296D02*
G02X1950569Y141828I-535J-1296D01*
G03X1950399Y142434I-323J236D01*
G02X1952065Y142902I535J1296D01*
G03X1952235Y142296I323J-236D01*
G37*
G36*
G01X1240805Y142936D02*
G02X1239229Y142929I-783J-1163D01*
G03X1239227Y143591I-226J330D01*
G02X1240803Y143598I783J1163D01*
G03X1240805Y142936I226J-330D01*
G37*
G36*
G01X1822623Y142854D02*
G02X1822532Y144188I-1275J583D01*
G03X1823234Y144236I338J214D01*
G02X1823325Y142902I1275J-583D01*
G03X1822623Y142854I-338J-214D01*
G37*
G36*
G01X1608134Y145056D02*
G02X1606717Y145038I-693J-1219D01*
G03X1606708Y145728I-206J342D01*
G02X1608634Y147615I693J1219D01*
G03X1609342Y147624I352J190D01*
G02X1609910Y148212I1248J-638D01*
G03Y148912I-194J350D01*
G02X1609909Y151362I681J1225D01*
G03Y152061I-194J350D01*
G02X1609366Y152605I683J1224D01*
G03X1608666I-350J-194D01*
G02X1606760Y154511I-1225J681D01*
G03Y155211I-194J350D01*
G02Y157661I681J1225D01*
G03Y158360I-195J350D01*
G02Y160810I682J1225D01*
G03Y161509I-194J350D01*
G02X1608666Y163416I681J1226D01*
G03X1609366I350J194D01*
G02X1609910Y163960I1225J-681D01*
G03Y164660I-194J350D01*
G02X1611816Y166566I681J1225D01*
G03X1612516I350J194D01*
G02X1614966I1225J-681D01*
G03X1615666I350J194D01*
G02X1618116I1225J-681D01*
G03X1618816I350J194D01*
G02X1619294Y167071I1225J-681D01*
G03X1619286Y167753I-213J339D01*
G02X1620753Y167770I720J1203D01*
G03X1620761Y167088I213J-339D01*
G02X1618816Y165204I-720J-1203D01*
G03X1618116I-350J-194D01*
G02X1617572Y164659I-1226J680D01*
G03Y163960I194J-350D01*
G02X1617571Y161510I-682J-1225D01*
G03Y160810I194J-350D01*
G02X1618115Y160266I-681J-1225D01*
G03X1618815I350J194D01*
G02X1621265Y160267I1225J-681D01*
G03X1621964I350J194D01*
G02X1622452Y160778I1225J-682D01*
G03X1622465Y161449I-211J340D01*
G02X1622606Y163856I785J1162D01*
G03X1622611Y164564I-184J355D01*
G02X1624447Y166569I665J1234D01*
G03X1625127Y166588I334J220D01*
G02X1627564Y166565I1212J-704D01*
G03X1628264I350J194D01*
G02X1630171Y164659I1225J-681D01*
G03Y163960I194J-350D01*
G02X1630170Y161510I-682J-1225D01*
G03Y160810I194J-350D01*
G02X1628264Y158904I-681J-1225D01*
G03X1627564I-350J-194D01*
G02X1625114I-1225J681D01*
G03X1624414I-350J-194D01*
G02X1621964Y158903I-1225J681D01*
G03X1621265I-349J-194D01*
G02X1618815Y158904I-1225J682D01*
G03X1618115I-350J-194D01*
G02X1615665Y158903I-1225J681D01*
G03X1614966I-349J-194D01*
G02X1614423Y158360I-1225J682D01*
G03Y157661I194J-349D01*
G02X1614422Y155211I-682J-1225D01*
G03Y154511I194J-350D01*
G02X1614423Y152061I-681J-1225D01*
G03Y151362I194J-350D01*
G02X1614966Y150818I-683J-1224D01*
G03X1615666I350J194D01*
G02Y149456I1225J-681D01*
G03X1614966I-350J-194D01*
G02X1614422Y148912I-1225J681D01*
G03Y148212I194J-350D01*
G02X1612516Y146306I-681J-1225D01*
G03X1611816I-350J-194D01*
G02X1609358Y146319I-1225J681D01*
G03X1608650Y146310I-352J-190D01*
G02X1608125Y145746I-1249J637D01*
G03X1608134Y145056I206J-342D01*
G37*
G36*
G01X1937365Y144773D02*
G02X1935661Y145312I-1178J-760D01*
G03X1935828Y145926I-151J371D01*
G02X1935705Y146112I1272J975D01*
G03X1935056Y146178I-348J-197D01*
G02X1935166Y147879I-1056J922D01*
G03X1935818Y147861I332J222D01*
G02X1937581Y145372I1282J-961D01*
G03X1937365Y144773I120J-382D01*
G37*
G36*
G01X1621265Y146306D02*
G02Y147668I-1225J681D01*
G03X1621965I350J194D01*
G02Y146306I1225J-681D01*
G03X1621265I-350J-194D01*
G37*
G36*
G01X1600850Y149794D02*
G02X1599487Y149780I-669J-1232D01*
G03X1599480Y150479I-198J348D01*
G02X1600843Y150493I669J1232D01*
G03X1600850Y149794I198J-348D01*
G37*
G36*
G01X1595532Y149735D02*
G02X1594240Y150084I-967J-1015D01*
G03X1594423Y150763I-93J389D01*
G02X1595715Y150414I967J1015D01*
G03X1595532Y149735I93J-389D01*
G37*
G36*
G01X1715242Y148118D02*
G02Y149782I-1128J832D01*
G03X1715886I322J238D01*
G02Y148118I1128J-832D01*
G03X1715242I-322J-238D01*
G37*
G36*
G01X1542460Y150283D02*
G02X1540828Y150010I-629J-1253D01*
G03X1540722Y150647I-286J280D01*
G02X1542354Y150920I629J1253D01*
G03X1542460Y150283I286J-280D01*
G37*
G36*
G01X1914684Y148614D02*
G02X1914504Y150391I-1292J767D01*
G03X1915135Y150441I296J269D01*
G02X1917581Y150267I1175J-765D01*
G03X1918286Y150228I363J169D01*
G02X1918213Y148909I1198J-728D01*
G03X1917508Y148948I-363J-169D01*
G02X1915312Y148691I-1198J728D01*
G03X1914684Y148614I-284J-281D01*
G37*
G36*
G01X1578563Y150675D02*
G02X1577117Y150760I-793J-1156D01*
G03X1577157Y151444I-186J354D01*
G02X1576957Y153590I793J1156D01*
G03X1576901Y154201I-283J282D01*
G02X1578693Y154363I799J1152D01*
G03X1578749Y153752I283J-282D01*
G02X1578603Y151359I-799J-1152D01*
G03X1578563Y150675I186J-354D01*
G37*
G36*
G01X1829274Y151006D02*
G02X1827889Y151287I-933J-1046D01*
G03X1828026Y151964I-129J379D01*
G02X1829411Y151683I933J1046D01*
G03X1829274Y151006I129J-379D01*
G37*
G36*
G01X1626991Y151377D02*
G02X1625666Y151366I-652J-1241D01*
G03X1625661Y152071I-192J351D01*
G02X1625150Y152530I653J1241D01*
G03X1624459Y152482I-332J-224D01*
G02X1621948Y152468I-1259J618D01*
G03X1621260Y152513I-357J-180D01*
G02X1620815Y152094I-1160J787D01*
G03Y151406I204J-344D01*
G02X1619385I-715J-1206D01*
G03Y152094I-204J344D01*
G02X1621352Y153932I715J1206D01*
G03X1622040Y153887I357J180D01*
G02X1624363Y153882I1160J-787D01*
G03X1625054Y153930I332J224D01*
G02X1627554Y153964I1259J-618D01*
G03X1628259Y153959I354J187D01*
G02X1630714Y153968I1230J-673D01*
G03X1631413I350J194D01*
G02X1633863Y153967I1225J-682D01*
G03X1634563I350J194D01*
G02Y152605I1225J-681D01*
G03X1633863I-350J-194D01*
G02X1631413Y152604I-1225J681D01*
G03X1630714I-349J-194D01*
G02X1628248Y152634I-1225J682D01*
G03X1627543Y152639I-354J-187D01*
G02X1626986Y152082I-1230J673D01*
G03X1626991Y151377I192J-351D01*
G37*
G36*
G01X1655367Y151363D02*
G02X1654005I-681J-1225D01*
G03Y152063I-194J350D01*
G02X1654003Y154513I681J1226D01*
G03Y155211I-194J349D01*
G02X1653461Y155754I684J1224D01*
G03X1652762I-349J-194D01*
G02X1650311I-1225J681D01*
G03X1649611I-350J-194D01*
G02X1649066Y155209I-1226J681D01*
G03X1649068Y154509I194J-349D01*
G02X1647713Y154506I-675J-1229D01*
G03X1647711Y155206I-194J349D01*
G02X1647705Y157661I675J1229D01*
G03Y158360I-194J350D01*
G02X1647162Y158904I683J1224D01*
G03X1646462I-350J-194D01*
G02X1644012I-1225J681D01*
G03X1643312I-350J-194D01*
G02X1640862Y158903I-1225J681D01*
G03X1640163I-349J-194D01*
G02X1637713Y158904I-1225J682D01*
G03X1637013I-350J-194D01*
G02X1635107Y160810I-1225J681D01*
G03Y161510I-194J350D01*
G02Y163960I681J1225D01*
G03Y164660I-194J350D01*
G02X1637014Y166566I681J1225D01*
G03X1637713I350J194D01*
G02X1640163I1225J-682D01*
G03X1640862I350J194D01*
G02X1643313I1225J-681D01*
G03X1644012I349J195D01*
G02X1646462I1225J-682D01*
G03X1647161I350J195D01*
G02X1649612I1225J-681D01*
G03X1650311I350J194D01*
G02X1652218Y164659I1225J-682D01*
G03Y163960I194J-350D01*
G02X1652761Y163417I-682J-1225D01*
G03X1653460I350J194D01*
G02X1655910Y163416I1225J-682D01*
G03X1656610I350J194D01*
G02X1657153Y163960I1226J-680D01*
G03Y164659I-194J350D01*
G02X1659060Y166566I682J1225D01*
G03X1659759I350J194D01*
G02X1661666Y164660I1226J-681D01*
G03Y163960I194J-350D01*
G02Y161510I-681J-1225D01*
G03Y160810I194J-350D01*
G02Y158360I-681J-1225D01*
G03Y157660I194J-350D01*
G02X1662210Y157117I-680J-1226D01*
G03X1662909I350J195D01*
G02X1664816Y155211I1225J-681D01*
G03Y154512I194J-349D01*
G02X1663453Y154511I-681J-1226D01*
G03Y155210I-194J350D01*
G02X1662909Y155754I681J1225D01*
G03X1662210I-350J-195D01*
G02X1659759I-1225J681D01*
G03X1659060I-349J-194D01*
G02X1658518Y155212I-1225J683D01*
G03Y154513I195J-349D01*
G02X1656611Y152607I-682J-1225D01*
G03X1655911I-350J-194D01*
G02X1655367Y152063I-1225J681D01*
G03Y151363I194J-350D01*
G37*
G36*
G01X1906106Y151138D02*
G02X1904426Y151404I-1014J-968D01*
G03X1904526Y152032I-190J352D01*
G02X1906206Y151766I1014J968D01*
G03X1906106Y151138I190J-352D01*
G37*
G36*
G01X1493400Y154196D02*
G02X1491916Y153632I-331J-1362D01*
G03X1491682Y154248I-329J227D01*
G02X1493166Y154812I331J1362D01*
G03X1493400Y154196I329J-227D01*
G37*
G36*
G01X1263621Y155695D02*
G02X1263522Y154039I1079J-895D01*
G03X1262879Y154078I-336J-217D01*
G02X1262978Y155734I-1079J895D01*
G03X1263621Y155695I336J217D01*
G37*
G36*
G01X1808218Y163430D02*
G02X1806662I-778J-1400D01*
G03Y164130I-194J350D01*
G02Y166930I778J1400D01*
G03Y167630I-194J350D01*
G02X1808218I778J1400D01*
G03Y166930I194J-350D01*
G02Y164130I-778J-1400D01*
G03Y163430I194J-350D01*
G37*
G36*
G01X-14373Y161787D02*
G02X-14902Y163024I-1395J135D01*
G03X-14256Y163300I248J315D01*
G02X-13727Y162063I1395J-135D01*
G03X-14373Y161787I-248J-315D01*
G37*
G36*
G01X1455114Y164296D02*
G02X1453485Y164634I-1044J-936D01*
G03X1453616Y165264I-167J363D01*
G02X1455245Y164926I1044J936D01*
G03X1455114Y164296I167J-363D01*
G37*
G36*
G01X1929290Y171119D02*
G02X1929132Y169372I1010J-972D01*
G03X1928510Y169428I-333J-221D01*
G02X1928668Y171175I-1010J972D01*
G03X1929290Y171119I333J221D01*
G37*
G36*
G01X1452032Y171551D02*
G02X1450714Y171560I-667J-1233D01*
G03X1450719Y172266I-185J354D01*
G02X1450374Y174469I667J1233D01*
G03X1450369Y175027I-289J276D01*
G02X1450089Y176595I996J987D01*
G03X1449904Y177118I-364J165D01*
G02X1451808Y177791I628J1254D01*
G03X1451993Y177268I364J-165D01*
G02X1452377Y175044I-628J-1254D01*
G03X1452382Y174486I289J-276D01*
G02X1452037Y172257I-996J-987D01*
G03X1452032Y171551I185J-354D01*
G37*
G36*
G01X1675688Y171990D02*
G02X1675669Y173359I-1233J668D01*
G03X1676367Y173368I346J200D01*
G02X1676386Y171999I1233J-668D01*
G03X1675688Y171990I-346J-200D01*
G37*
G36*
G01X1623864Y173803D02*
G02X1623715Y172303I1102J-867D01*
G03X1623044Y172370I-357J-180D01*
G02X1623193Y173870I-1102J867D01*
G03X1623864Y173803I357J180D01*
G37*
G36*
G01X1929349Y174614D02*
G02X1927318Y176518I-1131J829D01*
G03X1927325Y177125I-257J307D01*
G02X1929149Y177104I924J1054D01*
G03X1929142Y176497I257J-307D01*
G02X1929302Y176332I-923J-1055D01*
G03X1929934Y176349I309J253D01*
G02X1930489Y176798I1130J-830D01*
G03X1930617Y177437I-164J365D01*
G02X1932215Y177118I1022J959D01*
G03X1932087Y176479I164J-365D01*
G02X1929981Y174631I-1022J-959D01*
G03X1929349Y174614I-309J-253D01*
G37*
G36*
G01X1720013Y177316D02*
G02X1718316Y177397I-913J-1316D01*
G03X1718371Y178058I-195J349D01*
G02X1720021Y177979I879J1092D01*
G03X1720013Y177316I220J-334D01*
G37*
G36*
G01X1752390Y178036D02*
X1757391D01*
G02X1758902Y176535I0J-1512D01*
G01Y176440D01*
X1758892Y176356D01*
G02X1757390Y175014I-1502J169D01*
G01X1752390D01*
G02X1751337Y175442I1J1511D01*
G03X1750706Y175345I-279J-287D01*
G02X1750451Y177213I-1411J759D01*
G03X1751086Y177288I289J276D01*
G02X1752390Y178036I1304J-763D01*
G37*
G36*
G01X1884675Y177325D02*
G02X1883084Y177255I-745J-1188D01*
G03X1883055Y177912I-242J318D01*
G02X1884957Y179892I745J1188D01*
G03X1885534Y179803I330J226D01*
G02X1885243Y177908I866J-1103D01*
G03X1884666Y177997I-330J-226D01*
G02X1884646Y177982I-851J1114D01*
G03X1884675Y177325I242J-318D01*
G37*
G36*
G01X63421Y177506D02*
G02X62786Y176279I766J-1174D01*
G03X62168Y176599I-400J-15D01*
G02X62803Y177826I-766J1174D01*
G03X63421Y177506I400J15D01*
G37*
G36*
G01X1489739Y177922D02*
G02X1488381Y177890I-650J-1242D01*
G03X1488364Y178590I-202J345D01*
G02X1489722Y178622I650J1242D01*
G03X1489739Y177922I202J-345D01*
G37*
G36*
G01X1227947Y178203D02*
G02X1226003Y180147I-1167J777D01*
G03Y180813I-222J333D01*
G02X1225919Y183086I777J1167D01*
G03X1225948Y183692I-246J315D01*
G02X1227775Y183602I966J1016D01*
G03X1227746Y182996I246J-315D01*
G02X1227947Y182757I-966J-1016D01*
G03X1228613I333J222D01*
G02X1230947I1167J-777D01*
G03X1231613I333J222D01*
G02X1233557Y180813I1167J-777D01*
G03Y180147I222J-333D01*
G02X1231613Y178203I-777J-1167D01*
G03X1230947I-333J-222D01*
G02X1228613I-1167J777D01*
G03X1227947I-333J-222D01*
G37*
G36*
G01X1597025Y179619D02*
G02Y180981I-1225J681D01*
G03X1597725I350J194D01*
G02Y179619I1225J-681D01*
G03X1597025I-350J-194D01*
G37*
G36*
G01X1855682Y182846D02*
G02X1854144Y182808I-740J-1191D01*
G03X1854128Y183476I-228J329D01*
G02X1855666Y183514I740J1191D01*
G03X1855682Y182846I228J-329D01*
G37*
G36*
G01X87704Y182904D02*
G02X86355Y182989I-752J-1183D01*
G03X86399Y183689I-170J362D01*
G02X87748Y183604I752J1183D01*
G03X87704Y182904I170J-362D01*
G37*
G36*
G01X767754Y183850D02*
G02X765216Y182837I-1386J-214D01*
G03X764664Y182940I-328J-229D01*
G02X762508Y184389I-783J1163D01*
G03X762239Y184851I-391J81D01*
G02X761777Y185103I428J1335D01*
G03X761242Y185079I-254J-309D01*
G02X759160Y186949I-984J999D01*
G03X759122Y187489I-313J249D01*
G02X759037Y187575I954J1028D01*
G03X758734Y187570I-149J-133D01*
G02X756760Y187384I-1080J894D01*
G03X756226Y187363I-255J-308D01*
G02X754226Y187408I-978J1005D01*
G03X753662Y187428I-292J-273D01*
G02X751706Y187475I-954J1027D01*
G03X751142Y187482I-286J-280D01*
G02X749159Y187515I-975J1008D01*
G03X748561Y187488I-287J-278D01*
G02X746453Y187402I-1092J880D01*
G03X745889Y187417I-290J-276D01*
G02X743856Y187534I-961J1021D01*
G03X743227Y187511I-305J-258D01*
G02X741097Y187344I-1136J822D01*
G03X740491Y187298I-283J-282D01*
G02X737962Y188013I-1132J827D01*
G03X737509Y188377I-399J-32D01*
G02X737404Y188367I-185J1389D01*
G03X737028Y187967I24J-399D01*
G02X734269Y187614I-1402J-2D01*
G03X733811Y187908I-387J-100D01*
G02X732641Y188233I-247J1380D01*
G03X732106Y188226I-264J-301D01*
G02X732078Y190311I-951J1030D01*
G03X732613Y190318I264J301D01*
G02X734921Y189639I951J-1030D01*
G03X735379Y189345I387J100D01*
G02X735541Y189364I244J-1380D01*
G03X735917Y189764I-24J399D01*
G02X736450Y190866I1402J2D01*
G03X736498Y191449I-248J314D01*
G02X738938Y192406I1038J943D01*
G03X739405Y192016I400J4D01*
G02X740525Y189546I236J-1382D01*
G03X740463Y188989I253J-310D01*
G02X740499Y188941I-1103J-865D01*
G03X740840Y188967I163J116D01*
G02X743163Y189237I1251J-634D01*
G03X743792Y189260I305J258D01*
G02X745944Y189404I1136J-822D01*
G03X746508Y189389I290J276D01*
G02X748477Y189343I961J-1021D01*
G03X749075Y189370I287J278D01*
G02X751169Y189470I1091J-880D01*
G03X751733Y189463I286J280D01*
G02X753730Y189415I975J-1008D01*
G03X754294Y189395I292J273D01*
G02X756142Y189448I954J-1027D01*
G03X756676Y189469I255J308D01*
G02X758581Y189516I978J-1005D01*
G03X759120Y189526I264J300D01*
G02X760987Y189580I964J-1018D01*
G03X761531Y189606I258J306D01*
G02X763513Y189628I1002J-980D01*
G03X764062Y189619I279J286D01*
G02X766074Y189493I945J-1036D01*
G03X766622Y189435I304J259D01*
G02X768495Y187360I854J-1112D01*
G03X768543Y186768I291J-274D01*
G02X768047Y184298I-851J-1114D01*
G03X767754Y183850I102J-387D01*
G37*
G36*
G01X1643138Y183981D02*
G02X1640433Y184087I-1338J419D01*
G03X1639869Y184358I-390J-89D01*
G02X1640658Y185686I-611J1262D01*
G03X1640976Y185534I200J10D01*
G02X1641128Y185630I823J-1135D01*
G03X1641274Y186196I-192J351D01*
G02X1643844Y187149I1183J752D01*
G03X1644283Y186809I396J58D01*
G02X1643722Y184206I150J-1394D01*
G03X1643138Y183981I-203J-345D01*
G37*
G36*
G01X1703257Y188180D02*
G02X1701704Y188154I-757J-1180D01*
G03X1701693Y188820I-227J329D01*
G02X1703246Y188846I757J1180D01*
G03X1703257Y188180I227J-329D01*
G37*
G36*
G01X1709077Y188435D02*
G02X1708544Y186943I823J-1135D01*
G03X1707923Y187165I-387J-102D01*
G02X1708456Y188657I-823J1135D01*
G03X1709077Y188435I387J102D01*
G37*
G36*
G01X726687Y189694D02*
G02X726618Y188021I1089J-883D01*
G03X725977Y188047I-330J-226D01*
G02X726046Y189720I-1089J883D01*
G03X726687Y189694I330J226D01*
G37*
G36*
G01X1945242Y191496D02*
G02X1943626Y191653I-942J-1296D01*
G03X1943713Y192323I-169J363D01*
G02X1945285Y192170I898J1077D01*
G03X1945242Y191496I192J-351D01*
G37*
G36*
G01X1264031Y192350D02*
G02X1261842Y190662I-951J-1030D01*
G03X1261189Y190740I-354J-187D01*
G02X1258828Y191177I-1049J930D01*
G03X1258177Y191325I-374J-141D01*
G02X1255826Y192116I-967J1015D01*
G03X1255404Y192451I-395J-64D01*
G02X1254628Y192625I-94J1399D01*
G03X1254099Y192497I-196J-349D01*
G02X1251543Y193067I-1169J773D01*
G03X1251134Y193409I-396J-58D01*
G02X1249691Y194909I-45J1401D01*
G03X1249354Y195333I-399J29D01*
G02X1248169Y196692I217J1385D01*
G03X1247777Y197084I-400J-8D01*
G02X1246401Y198520I26J1402D01*
G03X1246021Y198930I-400J11D01*
G02X1244688Y200354I69J1400D01*
G03X1244309Y200760I-400J7D01*
G02X1242987Y202316I71J1400D01*
G03X1242636Y202758I-398J45D01*
G02X1242119Y205375I164J1392D01*
G03X1242207Y206008I-194J350D01*
G02X1241812Y206781I990J993D01*
G03X1241202Y207056I-395J-63D01*
G02X1239442Y209213I-750J1184D01*
G03Y209767I-288J277D01*
G02Y211713I1010J973D01*
G03Y212267I-288J277D01*
G02Y214213I1010J973D01*
G03Y214767I-288J277D01*
G02X1239446Y216717I1010J973D01*
G03X1239457Y217263I-287J279D01*
G02X1241506Y217223I1043J937D01*
G03X1241495Y216677I287J-279D01*
G02X1241462Y214767I-1043J-937D01*
G03Y214213I288J-277D01*
G02Y212267I-1010J-973D01*
G03Y211713I288J-277D01*
G02Y209767I-1010J-973D01*
G03Y209213I288J-277D01*
G02X1241836Y208461I-1011J-972D01*
G03X1242446Y208186I395J63D01*
G02X1244589Y207161I750J-1184D01*
G03X1244992Y206807I397J46D01*
G02X1246416Y205371I22J-1402D01*
G03X1246772Y204964I400J-10D01*
G02X1248021Y203529I-152J-1394D01*
G03X1248392Y203118I400J-12D01*
G02X1248785Y203032I-100J-1398D01*
G03X1249304Y203272I142J374D01*
G02X1252027Y202824I1321J-468D01*
G03X1252405Y202430I400J5D01*
G02X1252469Y202425I-77J-1400D01*
G03X1252908Y202827I39J398D01*
G02X1255088Y204006I1402J13D01*
G03X1255643Y204117I222J333D01*
G02X1256982Y204731I1167J-777D01*
G03X1257426Y205064I49J397D01*
G02X1258739Y206240I1384J-224D01*
G03X1259117Y206684I-20J400D01*
G02X1260386Y208236I1393J156D01*
G03X1260734Y208747I-36J398D01*
G02X1262016Y210541I1346J393D01*
G03X1262382Y211052I-18J399D01*
G02X1265099Y211149I1346J392D01*
G03X1265481Y210665I391J-84D01*
G02X1266852Y209289I-31J-1402D01*
G03X1267244Y208897I400J8D01*
G02X1268620Y207521I-26J-1402D01*
G03X1269012Y207129I400J8D01*
G02X1270388Y205753I-26J-1402D01*
G03X1270780Y205361I400J8D01*
G02X1272156Y203985I-26J-1402D01*
G03X1272548Y203593I400J8D01*
G02X1272678Y200798I-26J-1402D01*
G03X1272325Y200360I45J-398D01*
G02X1270974Y198819I-1395J-140D01*
G03X1270602Y198309I13J-400D01*
G02X1269325Y196523I-1348J-386D01*
G03X1268947Y196079I20J-400D01*
G02X1267382Y194532I-1393J-156D01*
G03X1266941Y194218I-50J-397D01*
G02X1264803Y193336I-1371J292D01*
G03X1264242Y193208I-219J-335D01*
G02X1264022Y192929I-1202J722D01*
G03X1264031Y192350I280J-285D01*
G37*
G36*
G01X706309Y191605D02*
G02X705545Y192886I-1402J32D01*
G03X706127Y193233I182J356D01*
G02X707720Y194589I1402J-33D01*
G03X708135Y195158I54J396D01*
G02X710728Y196211I1264J605D01*
G03X711280Y195978I379J128D01*
G02X712356Y196035I606J-1264D01*
G03X712855Y196250I133J377D01*
G02X715433Y196217I1282J-568D01*
G03X715953Y195999I370J153D01*
G02X715184Y194165I527J-1299D01*
G03X714664Y194383I-370J-153D01*
G02X713667Y194361I-527J1299D01*
G03X713168Y194146I-133J-377D01*
G02X710558Y194266I-1282J568D01*
G03X710006Y194499I-379J-128D01*
G02X709209Y194374I-607J1264D01*
G03X708794Y193805I-54J-396D01*
G02X706891Y191952I-1265J-605D01*
G03X706309Y191605I-182J-356D01*
G37*
G36*
G01X698454Y194415D02*
G02X696900Y194323I-708J-1210D01*
G03X696860Y194987I-242J319D01*
G02X698414Y195079I708J1210D01*
G03X698454Y194415I242J-319D01*
G37*
G36*
G01X98575Y195729D02*
G02X97147Y195683I-675J-1229D01*
G03X97125Y196371I-214J337D01*
G02X97155Y198845I675J1229D01*
G03Y199555I-184J355D01*
G02X98445I645J1245D01*
G03Y198845I184J-355D01*
G02X98553Y196417I-645J-1245D01*
G03X98575Y195729I214J-337D01*
G37*
G36*
G01X1630836Y196158D02*
G02X1630732Y196162I2J1402D01*
G03X1630314Y195670I-29J-399D01*
G02X1629054Y196742I-1364J-326D01*
G03X1629472Y197234I29J399D01*
G02X1632121Y197000I1364J326D01*
G03X1632340Y196724I184J-79D01*
G02X1632363Y196727I193J-1387D01*
G03X1632691Y197196I-65J395D01*
G02X1634296Y196071I1378J258D01*
G03X1633968Y195602I65J-395D01*
G02X1631226Y195666I-1378J-258D01*
G03X1630837Y196158I-389J92D01*
G01X1630836D01*
G37*
G36*
G01X105535Y196906D02*
G02X104105I-715J-1206D01*
G03Y197594I-204J344D01*
G02X105535I715J1206D01*
G03Y196906I204J-344D01*
G37*
G36*
G01X1731771Y195558D02*
G02X1731397Y196835I-1371J292D01*
G03X1732076Y197045I285J281D01*
G02X1733563Y198288I1487J-268D01*
G01X1738564D01*
G02X1740074Y196786I-1J-1512D01*
G01Y196691D01*
X1740065Y196607D01*
G02X1738563Y195264I-1502J168D01*
G01X1733563D01*
G02X1732456Y195747I1J1512D01*
G03X1731771Y195558I-294J-272D01*
G37*
G36*
G01X607489Y199401D02*
G02X605767Y199172I-716J-1205D01*
G03X605684Y199795I-287J279D01*
G02X605006Y201146I716J1205D01*
G03X604573Y201586I-398J41D01*
G02X605847Y202837I-120J1397D01*
G03X606280Y202397I398J-41D01*
G02X607406Y200024I120J-1397D01*
G03X607489Y199401I287J-279D01*
G37*
G36*
G01X799413Y200497D02*
G02X798046Y199727I-113J-1397D01*
G03X797694Y200305I-358J178D01*
G02X799100Y201098I23J1602D01*
G03X799413Y200497I345J-202D01*
G37*
G36*
G01X1894193Y200047D02*
G02X1893186Y201414I-1402J22D01*
G03X1893698Y201792I112J384D01*
G02X1894569Y203068I1402J-22D01*
G03X1894683Y203737I-152J370D01*
G02X1896145Y203487I932J1048D01*
G03X1896031Y202818I152J-370D01*
G02X1894705Y200425I-931J-1048D01*
G03X1894193Y200047I-112J-384D01*
G37*
G36*
G01X579220Y203377D02*
G02X578123Y202280I277J-1374D01*
G03X577652Y202751I-392J79D01*
G02X578749Y203848I-277J1374D01*
G03X579220Y203377I392J-79D01*
G37*
G36*
G01X1403833Y206100D02*
G02X1402555Y205885I-433J-1334D01*
G03X1402437Y206584I-241J319D01*
G02X1403715Y206799I433J1334D01*
G03X1403833Y206100I241J-319D01*
G37*
G36*
G01X562584Y206877D02*
G02X561487Y205780I277J-1374D01*
G03X561016Y206251I-392J79D01*
G02X562113Y207348I-277J1374D01*
G03X562584Y206877I392J-79D01*
G37*
G36*
G01X1955487Y214076D02*
G03X1955651Y214607I-193J350D01*
G02X1956220Y216466I1250J634D01*
G03Y217166I-194J350D01*
G02X1957582I681J1225D01*
G03Y216466I194J-350D01*
G02X1958147Y214599I-681J-1225D01*
G03X1958308Y214067I356J-183D01*
G02X1959541Y212715I-1418J-2532D01*
G03X1960200Y212606I365J163D01*
G02X1959928Y209839I1690J-1563D01*
G03X1959260Y209861I-341J-209D01*
G02X1957697Y208747I-2371J1673D01*
G01X1957552Y208706D01*
Y204492D01*
X1946598D01*
Y213346D01*
X1954623D01*
G02X1955487Y214076I2269J-1809D01*
G37*
G36*
G01X1330337Y207982D02*
G02X1330256Y209998I-1013J969D01*
G03X1330811Y210020I266J299D01*
G02X1332952Y209883I1013J-969D01*
G03X1333596I322J238D01*
G02Y208219I1128J-832D01*
G03X1332952I-322J-238D01*
G02X1330892Y208004I-1128J832D01*
G03X1330337Y207982I-266J-299D01*
G37*
G36*
G01X1884653Y211688D02*
G02X1882947I-853J-1113D01*
G03Y212323I-243J317D01*
G02X1885092Y213981I853J1113D01*
G03X1885791Y213912I368J155D01*
G02X1885660Y212580I1161J-787D01*
G03X1884961Y212649I-368J-155D01*
G02X1884653Y212323I-1160J788D01*
G03Y211688I243J-318D01*
G37*
G36*
G01X565773Y212929D02*
G02X564656Y211694I278J-1374D01*
G03X564178Y212126I-398J40D01*
G02X565295Y213361I-278J1374D01*
G03X565773Y212929I398J-40D01*
G37*
G36*
G01X174500Y210839D02*
G02X172195Y213060I-1200J1061D01*
G03Y213640I-275J290D01*
G02Y215960I1105J1160D01*
G03Y216540I-275J290D01*
G02X174636Y218584I1105J1160D01*
G03X175236Y218505I334J220D01*
G02X177852Y217706I1064J-1197D01*
G03X178451Y217467I387J100D01*
G02X180500Y217169I849J-1359D01*
G03X181100I300J265D01*
G02Y215047I1200J-1061D01*
G03X180500I-300J-265D01*
G02X180405Y214948I-1202J1059D01*
G03Y214368I275J-290D01*
G02X178469Y211839I-1105J-1159D01*
G03X177869Y211577I-208J-342D01*
G02X175100Y210839I-1569J323D01*
G03X174500I-300J-265D01*
G37*
G36*
G01X1848935Y212284D02*
G02Y213608I-1236J662D01*
G03X1849640I353J189D01*
G02Y212284I1236J-662D01*
G03X1848935I-352J-189D01*
G37*
G36*
G01X116300Y214684D02*
G02X114751Y214669I-763J-1176D01*
G03X114744Y215336I-224J331D01*
G02X116293Y215351I763J1176D01*
G03X116300Y214684I224J-331D01*
G37*
G36*
G01X765908D02*
G02X764359Y214669I-763J-1176D01*
G03X764352Y215336I-224J331D01*
G02X765901Y215351I763J1176D01*
G03X765908Y214684I224J-331D01*
G37*
G36*
G01X1220270Y214898D02*
G02X1218893Y216271I-1402J-29D01*
G03X1219300Y216679I7J400D01*
G02X1219317Y216923I1402J25D01*
G03X1218979Y217097I-198J31D01*
G02X1219396Y218228I-979J1003D01*
G03X1219996Y217919I398J37D01*
G02X1220677Y215306I706J-1211D01*
G03X1220270Y214898I-7J-400D01*
G37*
G36*
G01X1331241Y215723D02*
G02Y217277I-1167J777D01*
G03X1331907I333J222D01*
G02X1334241I1167J-777D01*
G03X1334907I333J222D01*
G02Y215723I1167J-777D01*
G03X1334241I-333J-222D01*
G02X1331907I-1167J777D01*
G03X1331241I-333J-222D01*
G37*
G36*
G01X580354Y218161D02*
G02X579257Y219258I-1374J-277D01*
G03X579728Y219729I79J392D01*
G02X580825Y218632I1374J277D01*
G03X580354Y218161I-79J-392D01*
G37*
G36*
G01X743908Y222185D02*
G02X741579Y220827I-971J-1011D01*
G03X741024Y221091I-388J-99D01*
G02X739426Y221393I-587J1273D01*
G03X738848I-289J-277D01*
G02X736866Y223375I-1011J971D01*
G03Y223953I-277J289D01*
G02X738848Y225935I971J1011D01*
G03X739426I289J277D01*
G02X739696Y226154I1011J-971D01*
G03X739665Y226850I-212J339D01*
G02X741685Y228317I635J1250D01*
G03X742262Y228023I395J62D01*
G02X743690Y225617I635J-1250D01*
G03X743699Y224951I226J-330D01*
G02X743908Y222763I-762J-1177D01*
G03Y222185I277J-289D01*
G37*
G36*
G01X642709Y222556D02*
G02X640382Y222440I-1109J-1156D01*
G03Y222960I-304J260D01*
G02Y225040I1218J1040D01*
G03Y225560I-304J260D01*
G02Y227640I1218J1040D01*
G03Y228160I-304J260D01*
G02Y230240I1218J1040D01*
G03Y230760I-304J260D01*
G02X642760Y232905I1218J1040D01*
G03X643340I290J275D01*
G02X645740Y232814I1160J-1105D01*
G03X646360I310J253D01*
G02X648840I1240J-1014D01*
G03X649460I310J253D01*
G02X651918Y230760I1240J-1014D01*
G03Y230240I304J-260D01*
G02Y228160I-1218J-1040D01*
G03Y227640I304J-260D01*
G02X652239Y227044I-1218J-1040D01*
G03X652849Y226824I385J111D01*
G02X652903Y224140I901J-1324D01*
G03X652294Y223840I-211J-340D01*
G02X649460Y222986I-1594J160D01*
G03X648840I-310J-253D01*
G02X646360I-1240J1014D01*
G03X645740I-310J-253D01*
G02X643340Y222895I-1240J1014D01*
G03X642760I-290J-275D01*
G02X642709Y222844I-1158J1107D01*
G03Y222556I139J-144D01*
G37*
G36*
G01X1904069Y226851D02*
G02X1901981Y226861I-1049J-1075D01*
G03X1901999Y227420I-277J289D01*
G02X1902167Y229471I1033J948D01*
G03X1902139Y230121I-247J315D01*
G02X1903772Y230191I768J1173D01*
G03X1903800Y229541I247J-315D01*
G02X1904056Y227410I-768J-1173D01*
G03X1904069Y226851I292J-273D01*
G37*
G36*
G01X1398440Y226716D02*
G02X1395924Y225485I-1229J-675D01*
G03X1395407Y225697I-367J-159D01*
G02X1396168Y227553I-526J1300D01*
G03X1396685Y227341I367J159D01*
G02X1397063Y227435I524J-1300D01*
G03X1397371Y228025I-43J398D01*
G02X1399574Y229708I1229J675D01*
G03X1400233Y229871I279J287D01*
G02X1400591Y228427I1332J-436D01*
G03X1399932Y228264I-279J-287D01*
G02X1398748Y227306I-1332J436D01*
G03X1398440Y226716I43J-398D01*
G37*
G36*
G01X602200Y227570D02*
G02X602143Y225908I1100J-870D01*
G03X601500Y225930I-330J-226D01*
G02X601557Y227592I-1100J870D01*
G03X602200Y227570I330J226D01*
G37*
G36*
G01X775868Y228446D02*
G02X774497Y228458I-697J-1330D01*
G03X774503Y229170I-180J358D01*
G02X775874Y229158I697J1330D01*
G03X775868Y228446I180J-358D01*
G37*
G36*
G01X1279850Y230736D02*
G02X1278675Y229922I99J-1398D01*
G03X1278283Y230488I-363J167D01*
G02X1276858Y232344I-100J1398D01*
G03X1276513Y232873I-378J130D01*
G02X1275240Y234465I115J1397D01*
G03X1274912Y234915I-396J56D01*
G02X1276542Y236101I242J1381D01*
G03X1276870Y235651I396J-56D01*
G02X1277953Y233812I-242J-1381D01*
G03X1278298Y233283I378J-130D01*
G02X1279458Y231302I-115J-1397D01*
G03X1279850Y230736I363J-167D01*
G37*
G36*
G01X1390390Y233662D02*
G03X1391024Y233338I400J1D01*
G02X1390489Y232633I876J-1220D01*
G03X1390113Y233170I-376J137D01*
G01X1388388D01*
Y242172D01*
X1390390D01*
Y239320D01*
G03X1391037Y239005I400J0D01*
G02Y236795I863J-1105D01*
G03X1390390Y236480I-247J-315D01*
G01Y233662D01*
G37*
G36*
G01X1837228Y234063D02*
G02X1835822Y233596I-328J-1363D01*
G03X1835608Y234241I-307J256D01*
G02X1837014Y234708I328J1363D01*
G03X1837228Y234063I307J-256D01*
G37*
G36*
G01X1735168Y232256D02*
G02X1734900Y233771I-1288J553D01*
G03X1735559Y233888I291J274D01*
G02X1738014Y234111I1288J-554D01*
G03X1738680I333J222D01*
G02X1740447Y234601I1167J-777D01*
G03X1741013Y234900I171J362D01*
G02X1741153Y235327I1385J-218D01*
G03X1740972Y235871I-355J184D01*
G02X1740632Y236092I696J1443D01*
G03X1740108Y236086I-259J-305D01*
G02X1737864Y236200I-1064J1198D01*
G03X1737310Y236234I-295J-271D01*
G02X1735427Y236290I-911J1066D01*
G03X1734873I-277J-288D01*
G02Y238310I-973J1010D01*
G03X1735427I277J288D01*
G02X1737323Y238355I973J-1010D01*
G03X1737878Y238382I264J301D01*
G02X1740080Y238506I1166J-1098D01*
G03X1740604Y238512I259J305D01*
G02X1742733Y238511I1064J-1198D01*
G03X1743260Y238507I266J299D01*
G02X1745469Y238399I1048J-1212D01*
G03X1746052Y238403I290J276D01*
G02X1746066Y236210I1175J-1089D01*
G03X1745483Y236206I-290J-276D01*
G02X1744132Y235703I-1175J1089D01*
G03X1743713Y235167I-44J-398D01*
G02X1741798Y233414I-1315J-486D01*
G03X1741232Y233115I-171J-362D01*
G02X1738680Y232557I-1385J219D01*
G03X1738014I-333J-222D01*
G02X1735827Y232373I-1167J777D01*
G03X1735168Y232256I-291J-274D01*
G37*
G36*
G01X126246Y235654D02*
G02X124199Y233687I-683J-1338D01*
G03X123515Y233758I-363J-168D01*
G02X121399Y236085I-1284J958D01*
G03X121479Y236704I-208J342D01*
G02X123805Y238907I1153J1112D01*
G03X124391I293J272D01*
G02X126255Y236371I1173J-1091D01*
G03X126246Y235654I173J-361D01*
G37*
G36*
G01X1316888Y242172D02*
X1318890D01*
Y239171D01*
G03X1319512Y238838I400J0D01*
G02Y236504I777J-1167D01*
G03X1318890Y236171I-222J-333D01*
G01Y233170D01*
X1316888D01*
Y236495D01*
G03X1316180Y236750I-400J0D01*
G02X1314081Y236682I-1080J895D01*
G03X1313390Y236408I-291J-275D01*
G01Y233170D01*
X1311388D01*
Y242172D01*
X1313390D01*
Y238882D01*
G03X1314081Y238608I400J1D01*
G02X1316180Y238540I1019J-963D01*
G03X1316888Y238795I308J255D01*
G01Y242172D01*
G37*
G36*
G01X1324390D02*
Y239320D01*
G03X1325037Y239005I400J0D01*
G02Y236795I863J-1105D01*
G03X1324390Y236480I-247J-315D01*
G01Y233170D01*
X1322388D01*
Y242172D01*
X1324390D01*
G37*
G36*
G01X1329890D02*
Y239320D01*
G03X1330537Y239005I400J0D01*
G02Y236795I863J-1105D01*
G03X1329890Y236480I-247J-315D01*
G01Y233170D01*
X1327888D01*
Y242172D01*
X1329890D01*
G37*
G36*
G01X1335390D02*
Y239320D01*
G03X1336037Y239005I400J0D01*
G02Y236795I863J-1105D01*
G03X1335390Y236480I-247J-315D01*
G01Y235589D01*
X1335482Y235530D01*
G02X1335573Y235364I-109J-168D01*
G02Y235328I-2100J-18D01*
G02X1335482Y235162I-200J2D01*
G01X1335390Y235103D01*
Y233170D01*
X1333388D01*
Y242172D01*
X1335390D01*
G37*
G36*
G01X1340890D02*
Y239320D01*
G03X1341537Y239005I400J0D01*
G02Y236795I863J-1105D01*
G03X1340890Y236480I-247J-315D01*
G01Y233170D01*
X1338888D01*
Y242172D01*
X1340890D01*
G37*
G36*
G01X1346390D02*
Y239320D01*
G03X1347037Y239005I400J0D01*
G02Y236795I863J-1105D01*
G03X1346390Y236480I-247J-315D01*
G01Y233170D01*
X1344388D01*
Y242172D01*
X1346390D01*
G37*
G36*
G01X1351890D02*
Y239320D01*
G03X1352537Y239005I400J0D01*
G02Y236795I863J-1105D01*
G03X1351890Y236480I-247J-315D01*
G01Y233170D01*
X1349888D01*
Y242172D01*
X1351890D01*
G37*
G36*
G01X1357390Y234314D02*
G03X1357680Y233929I400J0D01*
G02X1357825Y233739I-55J-192D01*
G02Y233703I-2100J-18D01*
G02X1357680Y233513I-200J2D01*
G03X1357393Y233170I111J-384D01*
G01X1355388D01*
Y242172D01*
X1357390D01*
Y239320D01*
G03X1358037Y239005I400J0D01*
G02Y236795I863J-1105D01*
G03X1357390Y236480I-247J-315D01*
G01Y234314D01*
G37*
G36*
G01X1362890Y242172D02*
Y239320D01*
G03X1363537Y239005I400J0D01*
G02Y236795I863J-1105D01*
G03X1362890Y236480I-247J-315D01*
G01Y233170D01*
X1360888D01*
Y242172D01*
X1362890D01*
G37*
G36*
G01X1368390D02*
Y239320D01*
G03X1369037Y239005I400J0D01*
G02Y236795I863J-1105D01*
G03X1368390Y236480I-247J-315D01*
G01Y233170D01*
X1366388D01*
Y242172D01*
X1368390D01*
G37*
G36*
G01X1373890D02*
Y239320D01*
G03X1374537Y239005I400J0D01*
G02Y236795I863J-1105D01*
G03X1373890Y236480I-247J-315D01*
G01Y233170D01*
X1371888D01*
Y242172D01*
X1373890D01*
G37*
G36*
G01X1379390D02*
Y239320D01*
G03X1380037Y239005I400J0D01*
G02Y236795I863J-1105D01*
G03X1379390Y236480I-247J-315D01*
G01Y233170D01*
X1377388D01*
Y242172D01*
X1379390D01*
G37*
G36*
G01X1384890D02*
Y239444D01*
G03X1385524Y239120I400J1D01*
G02Y236680I876J-1220D01*
G03X1384890Y236356I-234J-325D01*
G01Y233170D01*
X1382888D01*
Y242172D01*
X1384890D01*
G37*
G36*
G01X1608415Y241546D02*
G02X1607183Y242777I-1566J-336D01*
G03X1607662Y243223I83J391D01*
G02X1608861Y242026I1389J192D01*
G03X1608415Y241546I-55J-396D01*
G37*
G36*
G01X1667018Y243217D02*
G02X1665659Y243210I-673J-1230D01*
G03X1665656Y243909I-196J349D01*
G02X1667015Y243916I673J1230D01*
G03X1667018Y243217I196J-349D01*
G37*
G36*
G01X1682647Y243237D02*
G02X1682508Y241656I1082J-892D01*
G03X1681851Y241714I-348J-196D01*
G02X1680454Y243971I-1082J891D01*
G03X1680674Y244614I-90J390D01*
G02X1682786Y246455I1086J886D01*
G03X1683397Y246484I293J272D01*
G02X1683483Y244676I1112J-853D01*
G03X1682872Y244647I-293J-272D01*
G02X1682075Y244134I-1113J853D01*
G03X1681855Y243491I90J-390D01*
G02X1681990Y243295I-1083J-890D01*
G03X1682647Y243237I348J196D01*
G37*
G36*
G01X128755Y242876D02*
G02X128442Y244539I-1255J625D01*
G03X129069Y244657I269J296D01*
G02X129382Y242994I1255J-625D01*
G03X128755Y242876I-269J-296D01*
G37*
G36*
G01X778282Y242932D02*
G02X778000Y244483I-1282J568D01*
G03X778650Y244601I285J281D01*
G02X778932Y243050I1282J-568D01*
G03X778282Y242932I-285J-281D01*
G37*
G36*
G01X1437365Y245552D02*
G02X1436078Y244616I35J-1402D01*
G03X1435690Y245148I-377J132D01*
G02X1436977Y246084I-35J1402D01*
G03X1437365Y245552I377J-132D01*
G37*
G36*
G01X116289Y246548D02*
G02X114740Y246533I-763J-1176D01*
G03X114733Y247200I-224J331D01*
G02X116282Y247215I763J1176D01*
G03X116289Y246548I224J-331D01*
G37*
G36*
G01X765908Y246684D02*
G02X764359Y246669I-763J-1176D01*
G03X764352Y247336I-224J331D01*
G02X765901Y247351I763J1176D01*
G03X765908Y246684I224J-331D01*
G37*
G36*
G01X849482Y245366D02*
G02X847064Y247467I-1200J1061D01*
G03Y247987I-304J260D01*
G02X847099Y250107I1218J1040D01*
G03Y250647I-295J270D01*
G02X846842Y251026I1184J1079D01*
G03X846196Y251130I-360J-175D01*
G02X846594Y252679I-1146J1120D01*
G03X846952Y252620I193J53D01*
G02X847064Y252767I1328J-896D01*
G03Y253287I-304J260D01*
G02X849482Y255388I1218J1040D01*
G03X850082I300J265D01*
G02X852482I1200J-1061D01*
G03X853082I300J265D01*
G02X855482I1200J-1061D01*
G03X856082I300J265D01*
G02X858500Y253287I1200J-1061D01*
G03Y252767I304J-260D01*
G02X858465Y250647I-1218J-1040D01*
G03Y250107I295J-270D01*
G02X858500Y247987I-1183J-1080D01*
G03Y247467I304J-260D01*
G02X856082Y245366I-1218J-1040D01*
G03X855482I-300J-265D01*
G02X853082I-1200J1061D01*
G03X852482I-300J-265D01*
G02X850082I-1200J1061D01*
G03X849482I-300J-265D01*
G37*
G36*
G01X1663900Y249338D02*
G02X1662940Y248226I424J-1336D01*
G03X1662424Y248672I-395J65D01*
G02X1663384Y249784I-424J1336D01*
G03X1663900Y249338I395J-65D01*
G37*
G36*
G01X718606Y249173D02*
G02X718591Y250691I-1186J747D01*
G03X719264Y250697I335J219D01*
G02X721584Y250774I1186J-747D01*
G03X722239Y250786I323J236D01*
G02X724545Y250809I1161J-786D01*
G03X725195Y250805I326J231D01*
G02X725183Y249170I1133J-826D01*
G03X724533Y249174I-326J-231D01*
G02X722266Y249176I-1133J826D01*
G03X721611Y249164I-323J-236D01*
G02X719279Y249179I-1161J786D01*
G03X718606Y249173I-335J-219D01*
G37*
G36*
G01X658864Y249391D02*
G02X658783Y251062I-1164J781D01*
G03X659424Y251093I309J254D01*
G02X659505Y249422I1164J-781D01*
G03X658864Y249391I-309J-254D01*
G37*
G36*
G01X1500777Y249858D02*
G02X1500262Y251528I-1305J512D01*
G03X1500860Y251712I226J330D01*
G02X1501375Y250042I1305J-512D01*
G03X1500777Y249858I-226J-330D01*
G37*
G36*
G01X1588322Y250980D02*
G02X1587633Y252491I-1372J287D01*
G03X1588220Y252759I195J349D01*
G02X1588909Y251248I1372J-287D01*
G03X1588322Y250980I-195J-349D01*
G37*
G36*
G01X1440096Y254445D02*
G02X1438370Y253545I-396J-1345D01*
G03X1438104Y254055I-379J127D01*
G02X1437463Y256344I396J1345D01*
G03X1437308Y256987I-296J269D01*
G02X1438837Y257356I492J1313D01*
G03X1438992Y256713I296J-269D01*
G02X1439830Y254955I-492J-1313D01*
G03X1440096Y254445I379J-127D01*
G37*
G36*
G01X1859705Y253139D02*
G02X1859613Y254436I-1285J561D01*
G03X1860320Y254486I340J210D01*
G02X1862690Y254813I1285J-561D01*
G03X1863289Y254791I309J254D01*
G02X1863220Y252937I1016J-966D01*
G03X1862621Y252959I-309J-254D01*
G02X1860412Y253189I-1016J966D01*
G03X1859705Y253139I-340J-210D01*
G37*
G36*
G01X749809Y253142D02*
G02X749663Y255019I-1109J858D01*
G03X750254Y255065I275J291D01*
G02X752491Y255039I1109J-858D01*
G03X753135I322J238D01*
G02Y253375I1128J-832D01*
G03X752491I-322J-238D01*
G02X750400Y253188I-1128J832D01*
G03X749809Y253142I-275J-291D01*
G37*
G36*
G01X1671347Y255991D02*
G02X1669766Y255613I-525J-1300D01*
G03X1669615Y256247I-301J263D01*
G02X1669027Y256694I525J1300D01*
G03X1668478Y256777I-318J-243D01*
G02X1666532Y258743I-811J1144D01*
G03X1666377Y259340I-324J234D01*
G02X1668103Y259788I591J1271D01*
G03X1668258Y259191I324J-234D01*
G02X1668780Y258773I-590J-1272D01*
G03X1669329Y258690I318J243D01*
G02X1671196Y256625I810J-1144D01*
G03X1671347Y255991I301J-263D01*
G37*
G36*
G01X1621068Y255879D02*
G02X1619424Y255874I-819J-1138D01*
G03X1619422Y256522I-236J323D01*
G02X1621066Y256527I819J1138D01*
G03X1621068Y255879I236J-323D01*
G37*
G36*
G01X1309929Y256611D02*
G02X1309831Y254805I1021J-961D01*
G03X1309221Y254839I-319J-241D01*
G02X1306892Y256305I-1021J961D01*
G03X1306534Y256849I-373J144D01*
G02X1307893Y257745I51J1401D01*
G03X1308251Y257201I373J-144D01*
G02X1309319Y256645I-51J-1401D01*
G03X1309929Y256611I319J241D01*
G37*
G36*
G01X1592716Y258175D02*
G02X1590523Y255841I-1118J-1147D01*
G03X1590003Y255856I-269J-297D01*
G02X1587961Y255884I-1004J1248D01*
G03X1587442Y255883I-259J-305D01*
G02X1585039Y256252I-1043J1216D01*
G03X1584369Y256267I-340J-211D01*
G02X1581977Y258363I-1323J903D01*
G03X1581983Y258953I-267J298D01*
G02X1584496Y260867I1095J1169D01*
G03X1585166Y260808I354J186D01*
G02X1587478Y261035I1264J-984D01*
G03X1587998Y261032I262J303D01*
G02X1590015Y261071I1033J-1225D01*
G03X1590534Y261094I246J315D01*
G02X1592722Y258754I1094J-1170D01*
G03X1592716Y258175I273J-292D01*
G37*
G36*
G01X643632Y262228D02*
G02X641968I-832J-1128D01*
G03Y262872I-238J322D01*
G02X642408Y265346I832J1128D01*
G03X642583Y266008I-112J384D01*
G02X642443Y267787I1008J974D01*
G03X642279Y268382I-328J230D01*
G02X644003Y268856I576J1278D01*
G03X644167Y268261I328J-230D01*
G02X643983Y265637I-576J-1278D01*
G03X643808Y264975I112J-384D01*
G02X643632Y262872I-1008J-975D01*
G03Y262228I238J-322D01*
G37*
G36*
G01X445821Y262562D02*
G02X444136Y262342I-698J-1216D01*
G03X444054Y262972I-282J284D01*
G02X443931Y265325I698J1216D01*
G03X443855Y266017I-234J325D01*
G02X445229Y266168I554J1288D01*
G03X445305Y265476I234J-325D01*
G02X445739Y263192I-553J-1288D01*
G03X445821Y262562I282J-284D01*
G37*
G36*
G01X1087254Y263369D02*
G02X1084819Y263312I-1193J-1069D01*
G03X1084807Y263831I-310J252D01*
G02X1087551Y265303I1193J1069D01*
G03X1087913Y265247I193J51D01*
G02X1088053Y265432I1184J-751D01*
G03X1088031Y265987I-299J266D01*
G02X1090047Y266068I969J1013D01*
G03X1090069Y265513I299J-266D01*
G02X1090267Y265277I-969J-1014D01*
G03X1090933I333J222D01*
G02X1091255Y265619I1167J-777D01*
G03X1091299Y266218I-241J319D01*
G02X1093145Y266081I1001J982D01*
G03X1093101Y265482I241J-319D01*
G02X1090933Y263723I-1001J-982D01*
G03X1090267I-333J-222D01*
G02X1087763Y264079I-1167J777D01*
G03X1087397Y264117I-191J-60D01*
G02X1087242Y263888I-1399J780D01*
G03X1087254Y263369I310J-252D01*
G37*
G36*
G01X440857Y264577D02*
G02X439243Y265001I-1093J-878D01*
G03X439407Y265622I-148J371D01*
G02X441021Y265198I1093J878D01*
G03X440857Y264577I148J-371D01*
G37*
G36*
G01X424225Y263565D02*
G02X421854Y263681I-1133J1132D01*
G03X421274Y263721I-309J-254D01*
G02X418988Y263837I-1086J1178D01*
G03X418390I-299J-265D01*
G02X415989Y263839I-1200J1062D01*
G03X415389I-300J-265D01*
G02X412988Y263838I-1201J1060D01*
G03X412388I-300J-265D01*
G02X409750Y264193I-1200J1061D01*
G03X409032I-359J-176D01*
G02X406394Y263838I-1438J706D01*
G03X405794I-300J-265D01*
G02Y265960I-1200J1061D01*
G03X406394I300J265D01*
G02X409032Y265605I1200J-1061D01*
G03X409750I359J176D01*
G02X412388Y265960I1438J-706D01*
G03X412988I300J265D01*
G02X415389Y265959I1200J-1061D01*
G03X415989I300J265D01*
G02X418390Y265961I1201J-1060D01*
G03X418988I299J265D01*
G02X421426Y265915I1199J-1062D01*
G03X422006Y265875I309J254D01*
G02X424215Y265840I1086J-1178D01*
G03X424778Y265842I280J285D01*
G02X424788Y263567I1133J-1133D01*
G03X424225Y263565I-280J-285D01*
G37*
G36*
G01X392061Y264122D02*
G02Y265676I-1167J777D01*
G03X392727I333J222D01*
G02Y264122I1167J-777D01*
G03X392061I-333J-222D01*
G37*
G36*
G01X398561D02*
G02Y265676I-1167J777D01*
G03X399227I333J222D01*
G02Y264122I1167J-777D01*
G03X398561I-333J-222D01*
G37*
G36*
G01X1041669D02*
G02Y265676I-1167J777D01*
G03X1042335I333J222D01*
G02Y264122I1167J-777D01*
G03X1041669I-333J-222D01*
G37*
G36*
G01X1048169D02*
G02Y265676I-1167J777D01*
G03X1048835I333J222D01*
G02Y264122I1167J-777D01*
G03X1048169I-333J-222D01*
G37*
G36*
G01X451230Y266487D02*
G02X450517Y264930I653J-1241D01*
G03X449941Y265194I-390J-90D01*
G02X450654Y266751I-653J1241D01*
G03X451230Y266487I390J90D01*
G37*
G36*
G01X1096538Y267024D02*
G02X1094862I-838J-1124D01*
G03Y267666I-239J321D01*
G02X1096538I838J1124D01*
G03Y267024I239J-321D01*
G37*
G36*
G01X126206Y267673D02*
G02X124199Y265687I-643J-1357D01*
G03X123515Y265758I-363J-168D01*
G02X121349Y268053I-1284J958D01*
G03X121409Y268673I-220J334D01*
G02X123704Y270907I1122J1143D01*
G03X124290I293J272D01*
G02X126194Y268391I1173J-1091D01*
G03X126206Y267673I183J-356D01*
G37*
G36*
G01X1481323Y266622D02*
G02X1479417Y268529I-1225J682D01*
G03Y269229I-194J350D01*
G02X1478873Y269773I681J1225D01*
G03X1478173I-350J-194D01*
G02X1475723I-1225J681D01*
G03X1475023I-350J-194D01*
G02X1472573Y269772I-1225J681D01*
G03X1471874I-349J-194D01*
G02X1469967Y271679I-1225J682D01*
G03Y272378I-194J350D01*
G02X1469968Y274828I682J1225D01*
G03Y275528I-194J350D01*
G02X1469967Y277978I681J1225D01*
G03Y278677I-194J350D01*
G02X1469968Y281127I682J1225D01*
G03Y281827I-194J350D01*
G02Y284277I681J1225D01*
G03Y284977I-194J350D01*
G02X1471874Y286884I681J1225D01*
G03X1472573I350J194D01*
G02X1473116Y287427I1225J-682D01*
G03Y288126I-194J350D01*
G02X1475023Y290032I682J1225D01*
G03X1475723I350J194D01*
G02X1477630Y288126I1225J-681D01*
G03Y287427I194J-350D01*
G02X1478173Y286883I-683J-1224D01*
G03X1478873I350J194D01*
G02X1481323Y286884I1225J-681D01*
G03X1482022I350J194D01*
G02X1482565Y287427I1225J-682D01*
G03Y288126I-194J350D01*
G02X1483929I682J1225D01*
G03Y287427I194J-350D01*
G02X1484472Y286883I-683J-1224D01*
G03X1485172I350J194D01*
G02X1487622Y286884I1225J-681D01*
G03X1488321I350J194D01*
G02Y285520I1225J-682D01*
G03X1487622I-349J-194D01*
G02X1487078Y284977I-1224J683D01*
G03Y284277I194J-350D01*
G02X1485172Y282371I-681J-1225D01*
G03X1484472I-350J-194D01*
G02X1483928Y281827I-1225J681D01*
G03Y281127I194J-350D01*
G02X1482566I-681J-1225D01*
G03Y281827I-194J350D01*
G02X1482022Y282370I680J1226D01*
G03X1481323I-349J-194D01*
G02X1479417Y284277I-1225J682D01*
G03Y284977I-194J350D01*
G02X1478873Y285521I681J1225D01*
G03X1478173I-350J-194D01*
G02X1475723I-1225J681D01*
G03X1475023I-350J-194D01*
G02X1474479Y284977I-1225J681D01*
G03Y284277I194J-350D01*
G02Y281827I-681J-1225D01*
G03Y281127I194J-350D01*
G02X1475023Y280583I-681J-1225D01*
G03X1475723I350J194D01*
G02X1477630Y278677I1225J-681D01*
G03Y277978I194J-350D01*
G02X1478173Y277434I-683J-1224D01*
G03X1478873I350J194D01*
G02X1480779Y275528I1225J-681D01*
G03Y274828I194J-350D01*
G02X1481323Y274285I-680J-1226D01*
G03X1482022I350J194D01*
G02X1483929Y272378I1225J-682D01*
G03Y271679I194J-350D01*
G02X1484472Y271135I-683J-1224D01*
G03X1485172I350J194D01*
G02Y269773I1225J-681D01*
G03X1484472I-350J-194D01*
G02X1483928Y269229I-1225J681D01*
G03Y268529I194J-350D01*
G02X1482022Y266622I-681J-1225D01*
G03X1481323I-349J-194D01*
G37*
G36*
G01X653393Y271818D02*
G02X651851Y271716I-694J-1218D01*
G03X651807Y272382I-242J318D01*
G02X653349Y272484I694J1218D01*
G03X653393Y271818I242J-318D01*
G37*
G36*
G01X710700Y273831D02*
G02X709004Y273683I-751J-1184D01*
G03X708949Y274316I-269J295D01*
G02X708692Y276474I751J1184D01*
G03X708670Y277051I-288J278D01*
G02X708511Y277217I930J1049D01*
G03X707889I-311J-252D01*
G02Y278983I-1089J883D01*
G03X708511I311J252D01*
G02X710608Y277126I1090J-882D01*
G03X710630Y276549I288J-278D01*
G02X710645Y274464I-930J-1049D01*
G03X710700Y273831I269J-295D01*
G37*
G36*
G01X1624564Y272426D02*
G02X1624542Y274148I-1117J847D01*
G03X1625174Y274156I313J249D01*
G02X1625196Y272434I1117J-847D01*
G03X1624564Y272426I-313J-249D01*
G37*
G36*
G01X755577Y274494D02*
G02X754007Y274540I-819J-1138D01*
G03X754027Y275202I-214J338D01*
G02X755597Y275156I819J1138D01*
G03X755577Y274494I214J-338D01*
G37*
G36*
G01X128755Y274876D02*
G02X128442Y276539I-1255J625D01*
G03X129069Y276657I269J296D01*
G02X129382Y274994I1255J-625D01*
G03X128755Y274876I-269J-296D01*
G37*
G36*
G01X116300Y278684D02*
G02X114751Y278669I-763J-1176D01*
G03X114744Y279336I-224J331D01*
G02X116293Y279351I763J1176D01*
G03X116300Y278684I224J-331D01*
G37*
G36*
G01X765908D02*
G02X764359Y278669I-763J-1176D01*
G03X764352Y279336I-224J331D01*
G02X765901Y279351I763J1176D01*
G03X765908Y278684I224J-331D01*
G37*
G36*
G01X750187Y280386D02*
G02X748558Y280793I-1087J-886D01*
G03X748713Y281414I-155J369D01*
G02X750342Y281007I1087J886D01*
G03X750187Y280386I155J-369D01*
G37*
G36*
G01X690825Y282220D02*
G02X689271I-777J-1167D01*
G03Y282886I-222J333D01*
G02X690825I777J1167D01*
G03Y282220I222J-333D01*
G37*
G36*
G01X1495494Y282261D02*
G02X1495450Y280598I1106J-861D01*
G03X1494806Y280615I-328J-229D01*
G02X1494850Y282278I-1106J861D01*
G03X1495494Y282261I328J229D01*
G37*
G36*
G01X1405610Y282190D02*
G02X1402952Y282162I-1324J-461D01*
G03X1402465Y282671I-380J124D01*
G02X1403191Y283152I-373J1351D01*
G03X1403465Y282866I157J-124D01*
G02X1403822Y283052I820J-1138D01*
G03X1404068Y283561I-132J378D01*
G02X1405856Y282699I1324J461D01*
G03X1405610Y282190I132J-378D01*
G37*
G36*
G01X684678Y281366D02*
G02X684620Y282940I-1188J744D01*
G03X685282Y282964I323J236D01*
G02X685340Y281390I1188J-744D01*
G03X684678Y281366I-323J-236D01*
G37*
G36*
G01X59894Y282265D02*
G02X59782Y283892I-1194J735D01*
G03X60431Y283936I309J254D01*
G02X60965Y284438I1194J-735D01*
G03X61026Y285104I-188J353D01*
G02X62560Y284963I874J1096D01*
G03X62499Y284297I188J-353D01*
G02X60543Y282309I-874J-1096D01*
G03X59894Y282265I-309J-254D01*
G37*
G36*
G01X766364Y284716D02*
G02X765442Y285696I-1357J-353D01*
G03X765953Y286177I124J380D01*
G02X765923Y286323I1357J355D01*
G03X765406Y286644I-395J-60D01*
G02X766367Y288187I-426J1336D01*
G03X766884Y287866I395J60D01*
G02X766875Y285197I426J-1336D01*
G03X766364Y284716I-124J-380D01*
G37*
G36*
G01X656121Y285442D02*
G02X654689Y285967I-1121J-842D01*
G03X654921Y286597I-88J390D01*
G02X656353Y286072I1121J842D01*
G03X656121Y285442I88J-390D01*
G37*
G36*
G01X1357775Y285582D02*
G02X1357735Y284295I1225J-682D01*
G03X1357025Y284318I-361J-172D01*
G02X1357065Y285605I-1225J682D01*
G03X1357775Y285582I361J172D01*
G37*
G36*
G01X1116937Y288227D02*
G02X1115684Y287313I62J-1401D01*
G03X1115292Y287851I-375J139D01*
G02X1116545Y288765I-62J1401D01*
G03X1116937Y288227I375J-139D01*
G37*
G36*
G01X465845Y293836D02*
G02X464680Y292661I221J-1384D01*
G03X464221Y293116I-396J60D01*
G02X465386Y294291I-221J1384D01*
G03X465845Y293836I396J-60D01*
G37*
G36*
G01X1048213Y293855D02*
G02X1048209Y291958I1289J-951D01*
G03X1047565Y291959I-322J-237D01*
G02X1047569Y293856I-1289J951D01*
G03X1048213Y293855I322J237D01*
G37*
G36*
G01X412461Y292127D02*
G02Y293681I-1167J777D01*
G03X413127I333J222D01*
G02Y292127I1167J-777D01*
G03X412461I-333J-222D01*
G37*
G36*
G01X419661D02*
G02Y293681I-1167J777D01*
G03X420327I333J222D01*
G02Y292127I1167J-777D01*
G03X419661I-333J-222D01*
G37*
G36*
G01X426861D02*
G02Y293681I-1167J777D01*
G03X427527I333J222D01*
G02Y292127I1167J-777D01*
G03X426861I-333J-222D01*
G37*
G36*
G01X434061D02*
G02Y293681I-1167J777D01*
G03X434727I333J222D01*
G02Y292127I1167J-777D01*
G03X434061I-333J-222D01*
G37*
G36*
G01X441261D02*
G02Y293681I-1167J777D01*
G03X441927I333J222D01*
G02Y292127I1167J-777D01*
G03X441261I-333J-222D01*
G37*
G36*
G01X1062069D02*
G02Y293681I-1167J777D01*
G03X1062735I333J222D01*
G02Y292127I1167J-777D01*
G03X1062069I-333J-222D01*
G37*
G36*
G01X1069269D02*
G02Y293681I-1167J777D01*
G03X1069935I333J222D01*
G02Y292127I1167J-777D01*
G03X1069269I-333J-222D01*
G37*
G36*
G01X1076469D02*
G02Y293681I-1167J777D01*
G03X1077135I333J222D01*
G02Y292127I1167J-777D01*
G03X1076469I-333J-222D01*
G37*
G36*
G01X1083669D02*
G02Y293681I-1167J777D01*
G03X1084335I333J222D01*
G02Y292127I1167J-777D01*
G03X1083669I-333J-222D01*
G37*
G36*
G01X1090869D02*
G02Y293681I-1167J777D01*
G03X1091535I333J222D01*
G02Y292127I1167J-777D01*
G03X1090869I-333J-222D01*
G37*
G36*
G01X1321162Y296032D02*
G02X1320246Y295063I438J-1332D01*
G03X1319735Y295546I-387J103D01*
G02X1320651Y296515I-438J1332D01*
G03X1321162Y296032I387J-103D01*
G37*
G36*
G01X1475023Y294968D02*
G02X1473116Y296874I-1225J681D01*
G03Y297573I-194J350D01*
G02X1472573Y298116I682J1225D01*
G03X1471874I-349J-194D01*
G02X1469968Y300023I-1225J682D01*
G03Y300723I-194J350D01*
G02Y303173I681J1225D01*
G03Y303873I-194J350D01*
G02X1469967Y306323I681J1225D01*
G03Y307022I-194J350D01*
G02X1469968Y309472I682J1225D01*
G03Y310172I-194J350D01*
G02X1469967Y312622I681J1225D01*
G03Y313321I-194J350D01*
G02X1471874Y315228I682J1225D01*
G03X1472573I350J194D01*
G02X1474480Y313321I1225J-682D01*
G03Y312622I194J-350D01*
G02X1475023Y312078I-683J-1224D01*
G03X1475723I350J194D01*
G02X1478173I1225J-681D01*
G03X1478873I350J194D01*
G02X1479416Y312622I1226J-680D01*
G03Y313321I-194J350D01*
G02X1481323Y315228I682J1225D01*
G03X1482022I350J194D01*
G02X1484472Y315227I1225J-682D01*
G03X1485172I350J194D01*
G02X1485715Y315771I1226J-680D01*
G03Y316470I-194J349D01*
G02X1487621Y318377I681J1226D01*
G03X1488321I350J194D01*
G02Y317015I1225J-681D01*
G03X1487621I-350J-194D01*
G02X1487078Y316471I-1226J680D01*
G03Y315772I194J-349D01*
G02X1485172Y313865I-681J-1226D01*
G03X1484472I-350J-194D01*
G02X1483929Y313321I-1226J680D01*
G03Y312622I194J-350D01*
G02X1482022Y310715I-682J-1225D01*
G03X1481323I-349J-194D01*
G02X1480779Y310172I-1224J683D01*
G03Y309472I194J-350D01*
G02X1478873Y307566I-681J-1225D01*
G03X1478173I-350J-194D01*
G02X1477630Y307022I-1226J680D01*
G03Y306323I194J-350D01*
G02X1475723Y304417I-682J-1225D01*
G03X1475023I-350J-194D01*
G02X1474479Y303873I-1225J681D01*
G03Y303173I194J-350D01*
G02Y300723I-681J-1225D01*
G03Y300023I194J-350D01*
G02X1475023Y299479I-681J-1225D01*
G03X1475723I350J194D01*
G02X1478173I1225J-681D01*
G03X1478873I350J194D01*
G02X1479417Y300023I1225J-681D01*
G03Y300723I-194J350D01*
G02X1481323Y302630I681J1225D01*
G03X1482022I350J194D01*
G02X1482566Y303173I1224J-683D01*
G03Y303873I-194J350D01*
G02X1484472Y305779I681J1225D01*
G03X1485172I350J194D01*
G02X1485715Y306323I1226J-680D01*
G03Y307022I-194J350D01*
G02X1487622Y308929I682J1225D01*
G03X1488321I350J194D01*
G02X1488865Y309472I1224J-683D01*
G03Y310172I-194J350D01*
G02X1490777Y312067I681J1225D01*
G03X1491478Y312062I352J191D01*
G02X1492031Y312608I1223J-685D01*
G03Y313312I-190J352D01*
G02X1493864Y315321I665J1234D01*
G03X1494531I334J221D01*
G02X1496328Y313293I1168J-775D01*
G03X1496317Y312584I179J-357D01*
G02X1494496Y310555I-666J-1234D01*
G03X1493841Y310561I-330J-226D01*
G02X1491469Y310706I-1141J815D01*
G03X1490768Y310711I-352J-191D01*
G02X1490227Y310172I-1222J686D01*
G03Y309472I194J-350D01*
G02X1488321Y307565I-681J-1225D01*
G03X1487622I-349J-194D01*
G02X1487079Y307022I-1225J682D01*
G03Y306323I194J-350D01*
G02X1487078Y303873I-682J-1225D01*
G03Y303173I194J-350D01*
G02X1487622Y302630I-680J-1226D01*
G03X1488321I350J194D01*
G02Y301266I1225J-682D01*
G03X1487622I-349J-194D01*
G02X1487078Y300723I-1224J683D01*
G03Y300023I194J-350D01*
G02X1487079Y297573I-681J-1225D01*
G03Y296874I194J-349D01*
G02X1485715I-682J-1225D01*
G03Y297573I-194J350D01*
G02X1485172Y298117I683J1224D01*
G03X1484472I-350J-194D01*
G02X1482022Y298116I-1225J681D01*
G03X1481323I-349J-194D01*
G02X1480780Y297573I-1225J682D01*
G03Y296874I194J-349D01*
G02X1478873Y294968I-682J-1225D01*
G03X1478173I-350J-194D01*
G02X1475723I-1225J681D01*
G03X1475023I-350J-194D01*
G37*
G36*
G01X1115777Y297174D02*
G02X1114706Y295993I319J-1365D01*
G03X1114219Y296435I-397J52D01*
G02X1115290Y297616I-319J1365D01*
G03X1115777Y297174I397J-52D01*
G37*
G36*
G01X59608Y298174D02*
G02X57670Y298249I-1008J-974D01*
G03X57692Y298826I-266J299D01*
G02X57830Y300900I1008J975D01*
G03X57808Y301543I-248J313D01*
G02X59470Y301600I792J1157D01*
G03X59492Y300957I248J-313D01*
G02X59630Y298751I-792J-1157D01*
G03X59608Y298174I266J-299D01*
G37*
G36*
G01X672778Y298889D02*
G02X672637Y297518I1144J-810D01*
G03X671944Y297589I-367J-160D01*
G02X669711Y297517I-1144J811D01*
G03X669089I-311J-252D01*
G02Y299283I-1089J883D01*
G03X669711I311J252D01*
G02X672085Y298960I1089J-883D01*
G03X672778Y298889I367J160D01*
G37*
G36*
G01X126357Y299591D02*
G02X124199Y297687I-794J-1275D01*
G03X123515Y297758I-363J-168D01*
G02X121403Y300088I-1284J958D01*
G03X121503Y300687I-206J342D01*
G02X123904Y302807I1228J1029D01*
G03X124490I293J272D01*
G02X126388Y300287I1173J-1091D01*
G03X126357Y299591I181J-357D01*
G37*
G36*
G01X1357046Y305262D02*
Y302266D01*
G03X1357683Y301944I400J0D01*
G02X1357118Y300945I831J-1129D01*
G03X1356720Y301382I-398J37D01*
G01X1355042D01*
Y310386D01*
X1357046D01*
Y308118D01*
G03X1357689Y307801I400J0D01*
G02Y305579I855J-1111D01*
G03X1357046Y305262I-243J-317D01*
G37*
G36*
G01X1367842Y305702D02*
Y302662D01*
G03X1368481Y302342I400J0D01*
G02X1367922Y301323I839J-1123D01*
G03X1367523Y301752I-399J29D01*
G01X1365838D01*
Y305549D01*
G03X1365129Y305802I-400J0D01*
G02X1363189Y305579I-1085J888D01*
G03X1362546Y305262I-243J-317D01*
G01Y302266D01*
G03X1363183Y301944I400J0D01*
G02X1362618Y300945I831J-1129D01*
G03X1362220Y301382I-398J37D01*
G01X1360542D01*
Y310386D01*
X1362546D01*
Y308118D01*
G03X1363189Y307801I400J0D01*
G02X1365129Y307578I855J-1111D01*
G03X1365838Y307831I309J253D01*
G01Y310756D01*
X1367842D01*
Y308558D01*
G03X1368485Y308241I400J0D01*
G02Y306019I855J-1111D01*
G03X1367842Y305702I-243J-317D01*
G37*
G36*
G01X1373023Y301752D02*
X1371338D01*
Y310756D01*
X1373342D01*
Y308558D01*
G03X1373985Y308241I400J0D01*
G02Y306019I855J-1111D01*
G03X1373342Y305702I-243J-317D01*
G01Y302662D01*
G03X1373981Y302342I400J0D01*
G02X1373422Y301323I839J-1123D01*
G03X1373023Y301752I-399J29D01*
G37*
G36*
G01X1335385Y302354D02*
G02X1334839Y301190I855J-1111D01*
G01X1334832Y301382D01*
X1332738D01*
Y310386D01*
X1334742D01*
Y308188D01*
G03X1335385Y307871I400J0D01*
G02Y305649I855J-1111D01*
G03X1334742Y305332I-243J-317D01*
G01Y302671D01*
G03X1335385Y302354I400J0D01*
G37*
G36*
G01X1340885D02*
G02X1340339Y301190I855J-1111D01*
G01X1340332Y301382D01*
X1338238D01*
Y310386D01*
X1340242D01*
Y308188D01*
G03X1340885Y307871I400J0D01*
G02Y305649I855J-1111D01*
G03X1340242Y305332I-243J-317D01*
G01Y302671D01*
G03X1340885Y302354I400J0D01*
G37*
G36*
G01X1378801Y301932D02*
X1377046D01*
Y310936D01*
X1379050D01*
Y308738D01*
G03X1379693Y308421I400J0D01*
G02Y306199I855J-1111D01*
G03X1379050Y305882I-243J-317D01*
G01Y302851D01*
G03X1379705Y302543I400J0D01*
G02X1379200Y301518I896J-1078D01*
G03X1378801Y301932I-400J14D01*
G37*
G36*
G01X1384301D02*
X1382546D01*
Y310936D01*
X1384550D01*
Y308738D01*
G03X1385193Y308421I400J0D01*
G02Y306199I855J-1111D01*
G03X1384550Y305882I-243J-317D01*
G01Y302851D01*
G03X1385205Y302543I400J0D01*
G02X1384700Y301518I896J-1078D01*
G03X1384301Y301932I-400J14D01*
G37*
G36*
G01X1401538Y306202D02*
Y303598D01*
G03X1402169Y303272I400J1D01*
G02X1401535Y302052I868J-1226D01*
G01Y302252D01*
X1399536D01*
Y311256D01*
X1401538D01*
Y309058D01*
G03X1402182Y308741I400J0D01*
G02Y306519I855J-1111D01*
G03X1401538Y306202I-244J-317D01*
G37*
G36*
G01X1418365Y303094D02*
G02X1417820Y301905I855J-1111D01*
G03X1417421Y302282I-399J-23D01*
G01X1415718D01*
Y311286D01*
X1417722D01*
Y308932D01*
G03X1418390Y308636I400J0D01*
G02Y306560I943J-1038D01*
G03X1417722Y306264I-268J-296D01*
G01Y303411D01*
G03X1418365Y303094I400J0D01*
G37*
G36*
G01X1391280Y303162D02*
G02X1390733Y302050I855J-1111D01*
G01Y302252D01*
X1388634D01*
Y311256D01*
X1390636D01*
Y309058D01*
G03X1391280Y308741I400J0D01*
G02Y306519I855J-1111D01*
G03X1390636Y306202I-244J-317D01*
G01Y303479D01*
G03X1391280Y303162I400J0D01*
G37*
G36*
G01X1396780D02*
G02X1396233Y302050I855J-1111D01*
G01Y302252D01*
X1394134D01*
Y311256D01*
X1396136D01*
Y309058D01*
G03X1396780Y308741I400J0D01*
G02Y306519I855J-1111D01*
G03X1396136Y306202I-244J-317D01*
G01Y303479D01*
G03X1396780Y303162I400J0D01*
G37*
G36*
G01X4973Y301570D02*
G02Y303124I-1167J777D01*
G03X5639I333J222D01*
G02Y301570I1167J-777D01*
G03X4973I-333J-222D01*
G37*
G36*
G01X1346787Y307871D02*
G02Y305649I855J-1111D01*
G03X1346144Y305332I-243J-317D01*
G01Y301382D01*
X1344140D01*
Y310386D01*
X1346144D01*
Y308188D01*
G03X1346787Y307871I400J0D01*
G37*
G36*
G01X1352287D02*
G02Y305649I855J-1111D01*
G03X1351644Y305332I-243J-317D01*
G01Y301382D01*
X1349640D01*
Y310386D01*
X1351644D01*
Y308188D01*
G03X1352287Y307871I400J0D01*
G37*
G36*
G01X848882Y305666D02*
G02X846464Y307767I-1200J1061D01*
G03Y308287I-304J260D01*
G02X846499Y310407I1218J1040D01*
G03Y310947I-295J270D01*
G02X846225Y311362I1184J1079D01*
G03X845549Y311447I-364J-166D01*
G02X845757Y313115I-1249J1003D01*
G03X846433Y313030I364J166D01*
G02X846464Y313067I1243J-1010D01*
G03Y313587I-304J260D01*
G02X848882Y315688I1218J1040D01*
G03X849482I300J265D01*
G02X851882I1200J-1061D01*
G03X852482I300J265D01*
G02X854882I1200J-1061D01*
G03X855482I300J265D01*
G02X857900Y313587I1200J-1061D01*
G03Y313067I304J-260D01*
G02X857865Y310947I-1218J-1040D01*
G03Y310407I295J-270D01*
G02X857900Y308287I-1183J-1080D01*
G03Y307767I304J-260D01*
G02X855482Y305666I-1218J-1040D01*
G03X854882I-300J-265D01*
G02X852482I-1200J1061D01*
G03X851882I-300J-265D01*
G02X849482I-1200J1061D01*
G03X848882I-300J-265D01*
G37*
G36*
G01X1506795Y307781D02*
G02X1505065Y307774I-861J-1107D01*
G03X1505063Y308403I-248J314D01*
G02X1506793Y308410I861J1107D01*
G03X1506795Y307781I248J-314D01*
G37*
G36*
G01X777591Y306631D02*
G02X777150Y308191I-1321J469D01*
G03X777779Y308369I252J311D01*
G02X778220Y306809I1321J-469D01*
G03X777591Y306631I-252J-311D01*
G37*
G36*
G01X128755Y306876D02*
G02X128442Y308539I-1255J625D01*
G03X129069Y308657I269J296D01*
G02X129382Y306994I1255J-625D01*
G03X128755Y306876I-269J-296D01*
G37*
G36*
G01X1104766Y308814D02*
G02X1102437Y307365I-1010J-972D01*
G03X1101882Y307587I-376J-136D01*
G02X1099937Y308365I-626J1254D01*
G03X1099382Y308587I-376J-136D01*
G02X1097553Y309122I-626J1254D01*
G03X1096875Y309136I-343J-205D01*
G02X1094573Y309072I-1173J768D01*
G03X1093919Y309058I-322J-237D01*
G02X1091553Y309122I-1163J783D01*
G03X1090875Y309136I-343J-205D01*
G02X1090905Y310623I-1173J767D01*
G03X1091583Y310609I343J205D01*
G02X1093885Y310673I1173J-768D01*
G03X1094539Y310687I322J237D01*
G02X1096905Y310623I1163J-783D01*
G03X1097583Y310609I343J205D01*
G02X1100075Y310317I1173J-768D01*
G03X1100630Y310095I376J136D01*
G02X1101805Y310131I626J-1254D01*
G03X1102359Y310464I156J368D01*
G02X1104766Y309368I1397J-123D01*
G03Y308814I288J-277D01*
G37*
G36*
G01X116300Y310684D02*
G02X114751Y310669I-763J-1176D01*
G03X114744Y311336I-224J331D01*
G02X116293Y311351I763J1176D01*
G03X116300Y310684I224J-331D01*
G37*
G36*
G01X765908D02*
G02X764359Y310669I-763J-1176D01*
G03X764352Y311336I-224J331D01*
G02X765901Y311351I763J1176D01*
G03X765908Y310684I224J-331D01*
G37*
G36*
G01X377166Y310554D02*
G02X377121Y309128I1411J-758D01*
G03X376405Y309151I-364J-167D01*
G02X376450Y310577I-1411J758D01*
G03X377166Y310554I364J167D01*
G37*
G36*
G01X369925Y310765D02*
G02X369890Y308978I1312J-920D01*
G03X369226Y308991I-336J-216D01*
G02X369261Y310778I-1312J920D01*
G03X369925Y310765I336J216D01*
G37*
G36*
G01X441282Y309097D02*
G02Y310585I-1188J744D01*
G03X441960I339J213D01*
G02Y309097I1188J-744D01*
G03X441282I-339J-213D01*
G37*
G36*
G01X412461Y309127D02*
G02Y310681I-1167J777D01*
G03X413127I333J222D01*
G02Y309127I1167J-777D01*
G03X412461I-333J-222D01*
G37*
G36*
G01X419661D02*
G02Y310681I-1167J777D01*
G03X420327I333J222D01*
G02Y309127I1167J-777D01*
G03X419661I-333J-222D01*
G37*
G36*
G01X426861D02*
G02Y310681I-1167J777D01*
G03X427527I333J222D01*
G02Y309127I1167J-777D01*
G03X426861I-333J-222D01*
G37*
G36*
G01X434061D02*
G02Y310681I-1167J777D01*
G03X434727I333J222D01*
G02Y309127I1167J-777D01*
G03X434061I-333J-222D01*
G37*
G36*
G01X1062069D02*
G02Y310681I-1167J777D01*
G03X1062735I333J222D01*
G02Y309127I1167J-777D01*
G03X1062069I-333J-222D01*
G37*
G36*
G01X1069269D02*
G02Y310681I-1167J777D01*
G03X1069935I333J222D01*
G02Y309127I1167J-777D01*
G03X1069269I-333J-222D01*
G37*
G36*
G01X1076469D02*
G02Y310681I-1167J777D01*
G03X1077135I333J222D01*
G02Y309127I1167J-777D01*
G03X1076469I-333J-222D01*
G37*
G36*
G01X1083669D02*
G02Y310681I-1167J777D01*
G03X1084335I333J222D01*
G02Y309127I1167J-777D01*
G03X1083669I-333J-222D01*
G37*
G36*
G01X77011Y310638D02*
G02X74355Y309826I-1385J-221D01*
G03X73684Y309910I-362J-170D01*
G02X73871Y311392I-1084J890D01*
G03X74542Y311308I362J170D01*
G02X75699Y311818I1083J-890D01*
G03X76115Y312280I21J399D01*
G02X76713Y313660I1385J220D01*
G03X76668Y314348I-225J331D01*
G02X78087Y314440I631J1252D01*
G03X78132Y313752I225J-331D01*
G02X77427Y311100I-632J-1252D01*
G03X77011Y310638I-21J-399D01*
G37*
G36*
G01X766382Y316635D02*
G02X765182Y317754I-1375J-272D01*
G03X765625Y318228I50J397D01*
G02X765973Y319454I1375J272D01*
G03X765913Y320051I-293J272D01*
G02X767759Y320235I819J1138D01*
G03X767819Y319638I293J-272D01*
G02X766825Y317109I-819J-1138D01*
G03X766382Y316635I-50J-397D01*
G37*
G36*
G01X76830Y321972D02*
G02X76259Y320391I770J-1172D01*
G03X75657Y320608I-382J-117D01*
G02X73796Y320899I-770J1172D01*
G03X73178Y320903I-311J-252D01*
G02X73191Y322681I-1078J897D01*
G03X73809Y322677I311J252D01*
G02X76228Y322189I1078J-897D01*
G03X76830Y321972I382J117D01*
G37*
G36*
G01X94042Y324546D02*
G02X93615Y323004I896J-1078D01*
G03X92982Y323179I-377J-132D01*
G02X93409Y324721I-896J1078D01*
G03X94042Y324546I377J132D01*
G37*
G36*
G01X688114Y326341D02*
G02X686563Y326393I-815J-1141D01*
G03X686586Y327059I-210J341D01*
G02X688137Y327007I815J1141D01*
G03X688114Y326341I210J-341D01*
G37*
G36*
G01X637524Y328453D02*
G02X635905Y327850I-381J-1453D01*
G03X635691Y328459I-330J226D01*
G02X636069Y331202I409J1341D01*
G03X636420Y331777I-8J400D01*
G02X637712Y330988I1261J613D01*
G03X637361Y330413I8J-400D01*
G02X637286Y329053I-1261J-613D01*
G03X637524Y328453I339J-213D01*
G37*
G36*
G01X195992Y326582D02*
G02X193556Y326623I-1200J1061D01*
G03X192957Y326643I-308J-254D01*
G02X190464Y326847I-1165J1100D01*
G03X189837Y326893I-332J-224D01*
G02X187593Y329173I-1184J1079D01*
G03Y329773I-265J300D01*
G02X187561Y332145I1061J1201D01*
G03X187557Y332734I-273J293D01*
G02X187430Y332862I1072J1190D01*
G03X186830I-300J-265D01*
G02X184441Y334997I-1199J1062D01*
G03X184375Y335592I-297J268D01*
G02X184064Y335880I924J1309D01*
G03X183465Y335900I-308J-254D01*
G02X181100Y335939I-1165J1100D01*
G03X180500I-300J-265D01*
G02X178100I-1200J1061D01*
G03X177500I-300J-265D01*
G02X175100I-1200J1061D01*
G03X174500I-300J-265D01*
G02X172195Y338160I-1200J1061D01*
G03Y338740I-275J290D01*
G02X172558Y341320I1105J1160D01*
G03Y342028I-186J354D01*
G02X174500Y344509I742J1420D01*
G03X175100I300J265D01*
G02X177500I1200J-1061D01*
G03X178100I300J265D01*
G02X180500I1200J-1061D01*
G03X181100I300J265D01*
G02X183536Y344468I1200J-1061D01*
G03X184135Y344448I308J254D01*
G02X186500Y344409I1165J-1100D01*
G03X187100I300J265D01*
G02X189536Y344368I1200J-1061D01*
G03X190135Y344348I308J254D01*
G02X192114Y341868I1165J-1100D01*
G03Y341180I204J-344D01*
G02X190064Y338780I-815J-1380D01*
G03X189465Y338800I-308J-254D01*
G02X189361Y338700I-1161J1104D01*
G03Y338100I265J-300D01*
G02X189489Y335826I-1061J-1200D01*
G03X189555Y335231I297J-268D01*
G02X189723Y332751I-925J-1308D01*
G03X189727Y332162I273J-293D01*
G02X189715Y329773I-1073J-1189D01*
G03Y329173I265J-300D01*
G02X189982Y328869I-1060J-1201D01*
G03X190609Y328823I332J224D01*
G02X193028Y328763I1183J-1080D01*
G03X193627Y328743I308J254D01*
G02X195992Y328704I1165J-1100D01*
G03X196592I300J265D01*
G02Y326582I1200J-1061D01*
G03X195992I-300J-265D01*
G37*
G36*
G01X1514594Y328782D02*
G02X1513308Y328680I-545J-1292D01*
G03X1513252Y329388I-211J340D01*
G02X1514538Y329490I545J1292D01*
G03X1514594Y328782I211J-340D01*
G37*
G36*
G01X126430Y331542D02*
G02X124199Y329687I-867J-1226D01*
G03X123515Y329758I-363J-168D01*
G02X121500Y332142I-1284J958D01*
G03X121600Y332781I-182J356D01*
G02X124009Y334882I1131J1134D01*
G03X124562Y334799I319J241D01*
G02X126429Y332195I938J-1299D01*
G03X126430Y331542I232J-326D01*
G37*
G36*
G01X1106728Y335132D02*
G02X1104994Y335070I-828J-1132D01*
G03X1104972Y335698I-258J305D01*
G02X1106706Y335760I828J1132D01*
G03X1106728Y335132I258J-305D01*
G37*
G36*
G01X451673Y334540D02*
G02X449473Y334871I-973J1010D01*
G03X448830Y334949I-350J-194D01*
G02X449027Y336579I-1030J951D01*
G03X449670Y336501I350J194D01*
G02X451673Y336560I1030J-951D01*
G03X452227I277J288D01*
G02Y334540I973J-1010D01*
G03X451673I-277J-288D01*
G37*
G36*
G01X69546Y336983D02*
G02X67743Y337379I-1128J-833D01*
G03X67872Y337967I-193J350D01*
G02X67735Y338195I1128J833D01*
G03X67025Y338218I-361J-172D01*
G02X64643Y338108I-1225J682D01*
G03X64000Y338130I-330J-226D01*
G02X64057Y339792I-1100J870D01*
G03X64700Y339770I330J226D01*
G02X67065Y339505I1100J-870D01*
G03X67775Y339482I361J172D01*
G02X70167Y339577I1225J-682D01*
G03X70833I333J222D01*
G02X73073Y339702I1167J-777D01*
G03X73695Y339713I307J257D01*
G02X73727Y337948I1105J-863D01*
G03X73105Y337937I-307J-257D01*
G02X70833Y338023I-1105J863D01*
G03X70167I-333J-222D01*
G02X69675Y337571I-1167J777D01*
G03X69546Y336983I193J-350D01*
G37*
G36*
G01X1409740Y336269D02*
G02X1408622Y337811I-1392J167D01*
G03X1409097Y338155I78J392D01*
G02X1409130Y338332I1392J-168D01*
G03X1408866Y338568I-194J49D01*
G02X1409775Y339789I-490J1314D01*
G03X1410244Y339368I399J-27D01*
G02X1410215Y336613I245J-1380D01*
G03X1409740Y336269I-78J-392D01*
G37*
G36*
G01X1101253Y337632D02*
G02X1101084Y336002I1047J-932D01*
G03X1100438Y336069I-347J-199D01*
G02X1100607Y337699I-1047J932D01*
G03X1101253Y337632I347J199D01*
G37*
G36*
G01X1483734Y337311D02*
G02X1482776Y338273I-1348J-385D01*
G03X1483272Y338767I112J384D01*
G02X1483219Y339088I1348J387D01*
G03X1482768Y339466I-399J-18D01*
G02X1483986Y340920I-183J1390D01*
G03X1484437Y340542I399J18D01*
G02X1484230Y337805I183J-1390D01*
G03X1483734Y337311I-112J-384D01*
G37*
G36*
G01X53874Y338591D02*
G02X52942Y338875I-849J-1116D01*
G03X53248Y339502I-23J399D01*
G02X55802Y340299I1152J798D01*
G03X56224Y339900I400J0D01*
G02X57463Y339283I76J-1400D01*
G03X58162Y339350I331J224D01*
G02X58289Y338017I1290J-550D01*
G03X57590Y337950I-331J-224D01*
G02X54898Y338501I-1290J550D01*
G03X54476Y338900I-400J0D01*
G02X54045Y338944I-75J1400D01*
G03X53874Y338591I-50J-194D01*
G37*
G36*
G01X1488712Y338646D02*
G02X1487060Y338620I-808J-1146D01*
G03X1487050Y339266I-240J319D01*
G02X1488702Y339292I808J1146D01*
G03X1488712Y338646I240J-319D01*
G37*
G36*
G01X99363Y339304D02*
G02X97886Y339236I-684J-1224D01*
G03X97855Y339915I-226J330D01*
G02X99332Y339983I684J1224D01*
G03X99363Y339304I226J-330D01*
G37*
G36*
G01X399315Y337564D02*
G02Y339118I-1167J777D01*
G03X399981I333J222D01*
G02X402121Y339351I1167J-777D01*
G03X402675I277J288D01*
G02Y337331I973J-1010D01*
G03X402121I-277J-288D01*
G02X399981Y337564I-973J1010D01*
G03X399315I-333J-222D01*
G37*
G36*
G01X1048923D02*
G02Y339118I-1167J777D01*
G03X1049589I333J222D01*
G02X1051885Y339173I1167J-777D01*
G03X1052539Y339187I322J237D01*
G02X1054735Y339352I1163J-783D01*
G03X1055382Y339433I295J270D01*
G02X1055534Y337681I1410J-760D01*
G03X1054883Y337649I-314J-248D01*
G02X1052573Y337572I-1181J755D01*
G03X1051919Y337558I-322J-237D01*
G02X1049589Y337564I-1163J783D01*
G03X1048923I-333J-222D01*
G37*
G36*
G01X418263Y339420D02*
G02X418240Y337812I1137J-820D01*
G03X417585Y337821I-331J-225D01*
G02X415475Y337631I-1137J820D01*
G03X414921I-277J-288D01*
G02X412781Y337864I-973J1010D01*
G03X412115I-333J-222D01*
G02Y339418I-1167J777D01*
G03X412781I333J222D01*
G02X414921Y339651I1167J-777D01*
G03X415475I277J288D01*
G02X417608Y339429I973J-1010D01*
G03X418263Y339420I331J225D01*
G37*
G36*
G01X128370Y338700D02*
G02X127731Y340196I-1370J299D01*
G03X128330Y340452I208J341D01*
G02X128969Y338956I1370J-299D01*
G03X128370Y338700I-208J-341D01*
G37*
G36*
G01X1564167Y340223D02*
G02Y341777I-1167J777D01*
G03X1564833I333J222D01*
G02Y340223I1167J-777D01*
G03X1564167I-333J-222D01*
G37*
G36*
G01X116300Y342684D02*
G02X114751Y342669I-763J-1176D01*
G03X114744Y343336I-224J331D01*
G02X116293Y343351I763J1176D01*
G03X116300Y342684I224J-331D01*
G37*
G36*
G01X765908D02*
G02X764359Y342669I-763J-1176D01*
G03X764352Y343336I-224J331D01*
G02X765901Y343351I763J1176D01*
G03X765908Y342684I224J-331D01*
G37*
G36*
G01X50027Y344982D02*
G02X48007I-1010J-973D01*
G03Y345536I-288J277D01*
G02X48048Y347522I1010J973D01*
G03X48070Y348077I-277J289D01*
G02X48097Y349971I1047J932D01*
G03X48091Y350526I-291J274D01*
G02X48312Y352675I1000J983D01*
G03X48314Y353339I-222J333D01*
G02X49879Y353334I786J1161D01*
G03X49877Y352670I222J-333D01*
G02X50336Y352153I-786J-1161D01*
G03X50960Y352040I355J184D01*
G02X50557Y350596I940J-1041D01*
G03X50207Y350660I-191J-57D01*
G02X50111Y350547I-1115J850D01*
G03X50117Y349992I291J-274D01*
G02X50086Y347996I-1000J-983D01*
G03X50064Y347441I277J-289D01*
G02X50244Y347187I-1047J-933D01*
G03X50889Y347111I350J194D01*
G02X50696Y345486I1034J-947D01*
G03X50051Y345562I-350J-194D01*
G02X50027Y345536I-1042J938D01*
G03Y344982I288J-277D01*
G37*
G36*
G01X102884Y347278D02*
G02X101000Y347391I-1004J-978D01*
G03X101036Y347982I-251J312D01*
G02X101165Y350055I1004J978D01*
G03X101169Y350676I-250J312D01*
G02X101336Y352959I891J1082D01*
G03X101358Y353630I-207J343D01*
G02X102884Y353580I802J1150D01*
G03X102862Y352909I207J-343D01*
G02X102935Y350664I-802J-1150D01*
G03X102931Y350043I250J-312D01*
G02X102920Y347869I-891J-1083D01*
G03X102884Y347278I251J-312D01*
G37*
G36*
G01X1331530Y347307D02*
G02X1331474Y345600I1083J-890D01*
G03X1330840Y345621I-325J-233D01*
G02X1330896Y347328I-1083J890D01*
G03X1331530Y347307I325J233D01*
G37*
G36*
G01X65595Y349131D02*
G02X65121Y347275I755J-1181D01*
G03X64555Y347419I-350J-193D01*
G02X62757Y347664I-755J1181D01*
G03X62113Y347597I-298J-267D01*
G02X61943Y349236I-1213J702D01*
G03X62587Y349303I298J267D01*
G02X65029Y349275I1213J-703D01*
G03X65595Y349131I350J193D01*
G37*
G36*
G01X1644113Y349711D02*
G02X1642615Y349988I-963J-1019D01*
G03X1642737Y350648I-153J370D01*
G02X1644235Y350371I963J1019D01*
G03X1644113Y349711I153J-370D01*
G37*
G36*
G01X1338882Y350962D02*
G02X1338203Y349606I715J-1206D01*
G03X1337601Y349907I-398J-43D01*
G02X1338280Y351263I-715J1206D01*
G03X1338882Y350962I398J43D01*
G37*
G36*
G01X1588979Y351651D02*
G02X1588978Y350340I1239J-656D01*
G03X1588271I-354J-187D01*
G02X1588272Y351651I-1239J656D01*
G03X1588979I354J187D01*
G37*
G36*
G01X696449Y352760D02*
G02X695006Y352697I-659J-1460D01*
G03X694996Y353401I-195J349D01*
G02X694719Y355697I648J1243D01*
G03X694731Y356287I-264J300D01*
G02X696625Y356247I969J1013D01*
G03X696613Y355657I264J-300D01*
G02X696398Y353462I-969J-1013D01*
G03X696449Y352760I215J-337D01*
G37*
G36*
G01X1508004Y354215D02*
G02X1506340Y354241I-850J-1115D01*
G03X1506350Y354885I-232J326D01*
G02X1506271Y357050I850J1115D01*
G03Y357650I-265J300D01*
G02X1508129I929J1050D01*
G03Y357050I265J-300D01*
G02X1508014Y354859I-929J-1050D01*
G03X1508004Y354215I232J-326D01*
G37*
G36*
G01X1539469Y360376D02*
G02X1537451Y360293I-969J-1013D01*
G03X1537428Y360848I-299J266D01*
G02X1537462Y362906I969J1013D01*
G03X1537418Y363536I-267J298D01*
G02X1539135Y363655I782J1164D01*
G03X1539179Y363025I267J-298D01*
G02X1539446Y360931I-782J-1164D01*
G03X1539469Y360376I299J-266D01*
G37*
G36*
G01X1343883Y360683D02*
G02X1343419Y359074I848J-1116D01*
G03X1342802Y359252I-375J-141D01*
G02X1343266Y360861I-848J1116D01*
G03X1343883Y360683I375J141D01*
G37*
G36*
G01X102517Y361294D02*
G02X100999Y361304I-767J-1174D01*
G03X101003Y361976I-215J337D01*
G02X102521Y361966I767J1174D01*
G03X102517Y361294I215J-337D01*
G37*
G36*
G01X1357712Y360037D02*
G02X1357659Y361417I-1246J643D01*
G03X1358354Y361443I340J210D01*
G02X1358407Y360063I1246J-643D01*
G03X1357712Y360037I-340J-210D01*
G37*
G36*
G01X1608786Y360618D02*
G02X1608339Y361947I-1374J277D01*
G03X1608996Y362167I265J300D01*
G02X1609443Y360838I1374J-277D01*
G03X1608786Y360618I-265J-300D01*
G37*
G36*
G01X60254Y363533D02*
G02X59542Y362141I680J-1226D01*
G03X58951Y362443I-397J-48D01*
G02X59663Y363835I-680J1226D01*
G03X60254Y363533I397J48D01*
G37*
G36*
G01X679038Y364209D02*
G02X677514Y363539I-308J-1368D01*
G03X677255Y364128I-347J199D01*
G02X678779Y364798I308J1368D01*
G03X679038Y364209I347J-199D01*
G37*
G36*
G01X174671Y362220D02*
G02X172670Y364668I-1200J1061D01*
G03X172655Y365369I-200J346D01*
G02X172339Y367987I745J1418D01*
G03Y368587I-265J300D01*
G02X174600Y370848I1061J1200D01*
G03X175200I300J265D01*
G02X177600I1200J-1061D01*
G03X178200I300J265D01*
G02X180600I1200J-1061D01*
G03X181200I300J265D01*
G02X183600I1200J-1061D01*
G03X184200I300J265D01*
G02X186600I1200J-1061D01*
G03X187200I300J265D01*
G02X189461Y368587I1200J-1061D01*
G03Y367987I265J-300D01*
G02X189201Y365400I-1061J-1200D01*
G03X189216Y364699I200J-346D01*
G02X187271Y362220I-745J-1418D01*
G03X186671I-300J-265D01*
G02X184271I-1200J1061D01*
G03X183671I-300J-265D01*
G02X181271I-1200J1061D01*
G03X180671I-300J-265D01*
G02X178271I-1200J1061D01*
G03X177671I-300J-265D01*
G02X175271I-1200J1061D01*
G03X174671I-300J-265D01*
G37*
G36*
G01X1381129Y371450D02*
G02X1379271I-929J-1050D01*
G03Y372050I-265J300D01*
G02X1378921Y372526I929J1050D01*
G03X1378233Y372599I-365J-164D01*
G02X1377889Y372267I-1131J828D01*
G03X1377862Y371625I224J-331D01*
G02X1375667Y370041I-883J-1089D01*
G03X1375083Y370239I-374J-142D01*
G02X1373399Y372466I-739J1192D01*
G03X1373369Y373082I-270J296D01*
G02X1375689Y374773I899J1203D01*
G03X1376297Y374575I378J129D01*
G02X1378382Y374002I806J-1147D01*
G03X1379070Y373929I365J164D01*
G02X1381129Y372050I1131J-829D01*
G03Y371450I265J-300D01*
G37*
G36*
G01X128750Y371148D02*
G02X128552Y372417I-1330J442D01*
G03X129255Y372527I323J236D01*
G02X129453Y371258I1330J-442D01*
G03X128750Y371148I-323J-236D01*
G37*
G36*
G01X764923Y374919D02*
G02X763374Y374904I-763J-1176D01*
G03X763367Y375571I-224J331D01*
G02X764916Y375586I763J1176D01*
G03X764923Y374919I224J-331D01*
G37*
G36*
G01X744900Y373222D02*
G02Y374778I-1400J778D01*
G03X745600I350J194D01*
G02X748400I1400J-778D01*
G03X749100I350J194D01*
G02X751900I1400J-778D01*
G03X752600I350J194D01*
G02Y373222I1400J-778D01*
G03X751900I-350J-194D01*
G02X749100I-1400J778D01*
G03X748400I-350J-194D01*
G02X745600I-1400J778D01*
G03X744900I-350J-194D01*
G37*
G36*
G01X1333536Y375536D02*
G02X1331725Y375503I-886J-1086D01*
G03X1331714Y376114I-264J301D01*
G02X1331623Y376195I886J1087D01*
G03X1331090Y376217I-279J-287D01*
G02X1329151Y376370I-890J1083D01*
G03X1328574Y376392I-299J-266D01*
G02X1326551Y376470I-974J1008D01*
G03X1325974Y376492I-299J-266D01*
G02X1323787Y376797I-974J1008D01*
G03X1323143Y376864I-346J-200D01*
G02X1320807Y377258I-1043J936D01*
G03X1320186Y377413I-369J-155D01*
G02X1320673Y378784I-886J1087D01*
G03X1321022Y378697I196J41D01*
G02X1321181Y378859I1077J-898D01*
G03X1321171Y379471I-262J302D01*
G02X1323113Y381479I883J1089D01*
G03X1323738Y381506I302J263D01*
G02X1324095Y381849I1135J-824D01*
G03Y382515I-222J333D01*
G02X1326062Y384424I777J1167D01*
G03X1326711Y384384I339J212D01*
G02X1328875Y384400I1089J-884D01*
G03X1329531Y384464I306J257D01*
G02X1329981Y384952I1226J-679D01*
G03Y385618I-222J333D01*
G02Y387952I777J1167D01*
G03Y388618I-222J333D01*
G02X1331535I777J1167D01*
G03Y387952I222J-333D01*
G02Y385618I-777J-1167D01*
G03Y384952I222J-333D01*
G02X1329683Y382885I-777J-1167D01*
G03X1329027Y382821I-306J-257D01*
G02X1328475Y382271I-1227J679D01*
G03X1328453Y381583I192J-351D01*
G02X1328666Y381416I-755J-1182D01*
G03X1329219Y381417I276J290D01*
G02X1331148Y381430I971J-1011D01*
G03X1331715Y381451I273J292D01*
G02X1331790Y379479I1033J-948D01*
G03X1331223Y379458I-273J-292D01*
G02X1330905Y379200I-1033J948D01*
G03X1330907Y378511I204J-344D01*
G02X1331177Y378305I-709J-1209D01*
G03X1331710Y378283I279J287D01*
G02X1333525Y376147I890J-1083D01*
G03X1333536Y375536I264J-301D01*
G37*
G36*
G01X1446261Y374114D02*
G02X1446234Y375724I-1161J786D01*
G03X1446889Y375736I323J236D01*
G02X1446916Y374126I1161J-786D01*
G03X1446261Y374114I-323J-236D01*
G37*
G36*
G01X1631819Y376659D02*
G02X1629911Y376593I-919J-1059D01*
G03X1629862Y377201I-283J283D01*
G02X1629557Y379511I938J1299D01*
G03X1629414Y380126I-310J252D01*
G02X1631156Y380607I586J1274D01*
G03X1631349Y380005I330J-226D01*
G02X1631825Y377269I-549J-1505D01*
G03X1631819Y376659I256J-308D01*
G37*
G36*
G01X752559Y380778D02*
G02X752489Y379058I1315J-915D01*
G03X751815Y379085I-346J-201D01*
G02X749100Y379222I-1315J915D01*
G03X748400I-350J-194D01*
G02X745600I-1400J778D01*
G03X744900I-350J-194D01*
G02Y380778I-1400J778D01*
G03X745600I350J194D01*
G02X748400I1400J-778D01*
G03X749100I350J194D01*
G02X751885Y380805I1400J-778D01*
G03X752559Y380778I346J201D01*
G37*
G36*
G01X766290Y380798D02*
G02X764936Y381765I-1333J-435D01*
G03X765310Y382289I-6J400D01*
G02X766009Y383974I1333J435D01*
G03X766122Y384602I-181J357D01*
G02X767789Y384300I1033J948D01*
G03X767676Y383672I181J-357D01*
G02X766664Y381322I-1033J-948D01*
G03X766290Y380798I6J-400D01*
G37*
G36*
G01X117981Y382436D02*
G02X117232Y381078I648J-1243D01*
G03X116648Y381400I-399J-33D01*
G02X115528Y383963I-649J1243D01*
G03X115764Y384490I-135J377D01*
G02X117535Y383696I1299J526D01*
G03X117299Y383169I135J-377D01*
G02X117397Y382758I-1299J-527D01*
G03X117981Y382436I399J33D01*
G37*
G36*
G01X1457707Y385768D02*
G02X1456192Y385728I-726J-1199D01*
G03X1456174Y386401I-225J331D01*
G02X1457689Y386441I726J1199D01*
G03X1457707Y385768I225J-331D01*
G37*
G36*
G01X744900Y385222D02*
G02Y386778I-1400J778D01*
G03X745600I350J194D01*
G02X748400I1400J-778D01*
G03X749100I350J194D01*
G02X751900I1400J-778D01*
G03X752600I350J194D01*
G02Y385222I1400J-778D01*
G03X751900I-350J-194D01*
G02X749100I-1400J778D01*
G03X748400I-350J-194D01*
G02X745600I-1400J778D01*
G03X744900I-350J-194D01*
G37*
G36*
G01X680301Y386975D02*
G02X678638Y386895I-777J-1167D01*
G03X678607Y387538I-253J310D01*
G02X680270Y387618I777J1167D01*
G03X680301Y386975I253J-310D01*
G37*
G36*
G01X53573Y391018D02*
X50628D01*
Y393022D01*
X56132D01*
Y391007D01*
G03X55933Y390348I96J-388D01*
G02X53867I-1033J-948D01*
G03X53573Y391018I-295J270D01*
G37*
G36*
G01X1381928Y391468D02*
G02Y393132I-1128J832D01*
G03X1382572I322J238D01*
G02Y391468I1128J-832D01*
G03X1381928I-322J-238D01*
G37*
G36*
G01X1470953Y393463D02*
G02X1469582Y393653I-853J-1113D01*
G03X1469737Y394285I-148J371D01*
G02X1469538Y395811I1063J915D01*
G03X1469332Y396354I-360J174D01*
G02X1468706Y396871I542J1293D01*
G03X1468040I-333J-222D01*
G02X1465862Y396677I-1167J777D01*
G03X1465284I-289J-277D01*
G02Y398619I-1011J971D01*
G03X1465862I289J277D01*
G02X1468040Y398425I1011J-971D01*
G03X1468706I333J222D01*
G02X1471135Y397037I1167J-777D01*
G03X1471341Y396494I360J-174D01*
G02X1472183Y395433I-541J-1294D01*
G03X1472689Y395116I394J67D01*
G02X1471700Y393537I394J-1346D01*
G03X1471194Y393854I-394J-67D01*
G02X1471040Y393819I-387J1348D01*
G03X1470953Y393463I34J-197D01*
G37*
G36*
G01X126222Y395666D02*
G02X124199Y393687I-659J-1350D01*
G03X123515Y393758I-363J-168D01*
G02X121035Y395781I-1284J958D01*
G03X120989Y396358I-299J267D01*
G02X123293Y398546I1011J1243D01*
G03X123952Y398566I323J236D01*
G02X126178Y396360I1348J-866D01*
G03X126222Y395666I219J-335D01*
G37*
G36*
G01X1631023Y396730D02*
G02X1629663Y396770I-723J-1430D01*
G03X1629703Y397484I-159J367D01*
G02X1629491Y399767I697J1216D01*
G03X1629524Y400344I-260J304D01*
G02X1631459Y400233I1026J956D01*
G03X1631426Y399656I260J-304D01*
G02X1631025Y397445I-1026J-956D01*
G03X1631023Y396730I178J-358D01*
G37*
G36*
G01X1244795Y398467D02*
G02X1244034Y399589I-1396J-128D01*
G03X1244614Y399982I182J356D01*
G02X1245375Y398860I1396J128D01*
G03X1244795Y398467I-182J-356D01*
G37*
G36*
G01X1332810Y400430D02*
G02X1330695Y398590I-1039J-941D01*
G03X1330094Y398605I-307J-256D01*
G02X1327897Y398779I-1030J951D01*
G03X1327231I-333J-222D01*
G02X1324897I-1167J777D01*
G03X1324231I-333J-222D01*
G02X1322028Y398611I-1167J777D01*
G03X1321442Y398616I-295J-270D01*
G02X1319229Y398844I-1019J963D01*
G03X1318644Y398952I-341J-209D01*
G02X1316778Y401035I-857J1110D01*
G03Y401589I-288J277D01*
G02X1319048Y403176I1010J973D01*
G03X1319361Y403113I180J87D01*
G02X1319442Y403180I933J-1046D01*
G03X1319456Y403487I-121J159D01*
G02X1321567Y405301I944J1037D01*
G03X1322233I333J222D01*
G02X1324567I1167J-777D01*
G03X1325233I333J222D01*
G02X1327567I1167J-777D01*
G03X1328233I333J222D01*
G02X1330380Y405527I1167J-777D01*
G03X1330951Y405539I280J286D01*
G02X1332902Y403530I1022J-959D01*
G03X1332876Y402956I265J-300D01*
G02X1332829Y400986I-1020J-961D01*
G03X1332810Y400430I278J-288D01*
G37*
G36*
G01X1466215Y401593D02*
G02Y403147I-1167J777D01*
G03X1466881I333J222D01*
G02Y401593I1167J-777D01*
G03X1466215I-333J-222D01*
G37*
G36*
G01X175831Y403321D02*
G02X175784Y404774I-1222J688D01*
G03X176467Y404797I335J219D01*
G02X178913Y404794I1222J-688D01*
G03X179603Y404780I349J195D01*
G02X179575Y403364I1196J-732D01*
G03X178885Y403378I-349J-195D01*
G02X176514Y403344I-1196J731D01*
G03X175831Y403321I-335J-219D01*
G37*
G36*
G01X1198437Y406752D02*
G02X1196898Y406240I-408J-1341D01*
G03X1196692Y406859I-323J236D01*
G02X1198231Y407371I408J1341D01*
G03X1198437Y406752I323J-236D01*
G37*
G36*
G01X1467549Y405996D02*
G02Y407550I-1167J777D01*
G03X1468215I333J222D01*
G02Y405996I1167J-777D01*
G03X1467549I-333J-222D01*
G37*
G36*
G01X1513552Y408921D02*
G02X1511886Y408561I-598J-1268D01*
G03X1511752Y409182I-305J259D01*
G02X1511125Y409769I599J1268D01*
G03X1510425I-350J-194D01*
G02Y411131I-1225J681D01*
G03X1511125I350J194D01*
G02X1513418Y409542I1226J-680D01*
G03X1513552Y408921I305J-259D01*
G37*
G36*
G01X1613554Y410172D02*
G02X1611843Y409975I-729J-1198D01*
G03X1611771Y410602I-280J286D01*
G02X1613482Y410799I729J1198D01*
G03X1613554Y410172I280J-286D01*
G37*
G36*
G01X1440497Y410646D02*
G02X1439003Y410566I-684J-1224D01*
G03X1438967Y411242I-231J327D01*
G02X1440461Y411322I684J1224D01*
G03X1440497Y410646I231J-327D01*
G37*
G36*
G01X798376Y410593D02*
G02X797035Y411222I-1176J-763D01*
G03X797324Y411837I-47J397D01*
G02X798834Y413962I1176J763D01*
G03X799302Y414494I95J388D01*
G02X800276Y413638I1308J506D01*
G03X799808Y413106I-95J-388D01*
G02X798665Y411208I-1308J-506D01*
G03X798376Y410593I47J-397D01*
G37*
G36*
G01X1395067Y411723D02*
G02X1392890Y413473I-1167J778D01*
G03Y414027I-288J277D01*
G02X1393952Y416401I1010J973D01*
G03X1394357Y416888I14J400D01*
G02X1397076Y416819I1368J305D01*
G03X1397337Y416332I386J-107D01*
G02X1397910Y414027I-437J-1332D01*
G03Y413473I288J-277D01*
G02X1395733Y411723I-1010J-972D01*
G03X1395067I-333J-222D01*
G37*
G36*
G01X1535647Y412859D02*
G02X1535604Y414219I-1247J641D01*
G03X1536303Y414241I343J205D01*
G02X1536869Y414825I1246J-642D01*
G03Y415525I-194J350D01*
G02X1536325Y416069I681J1225D01*
G03X1535625I-350J-194D01*
G02Y417431I-1225J681D01*
G03X1536325I350J194D01*
G02X1538775I1225J-681D01*
G03X1539475I350J194D01*
G02X1541925I1225J-681D01*
G03X1542625I350J194D01*
G02X1545075I1225J-681D01*
G03X1545775I350J194D01*
G02Y416069I1225J-681D01*
G03X1545075I-350J-194D01*
G02X1544531Y415525I-1225J681D01*
G03Y414825I194J-350D01*
G02X1542625Y412919I-681J-1225D01*
G03X1541925I-350J-194D01*
G02X1539475I-1225J681D01*
G03X1538775I-350J-194D01*
G02X1536346Y412881I-1225J681D01*
G03X1535647Y412859I-343J-205D01*
G37*
G36*
G01X1516725Y412919D02*
G02Y414281I-1225J681D01*
G03X1517425I350J194D01*
G02X1517969Y414825I1225J-681D01*
G03Y415525I-194J350D01*
G02X1519331I681J1225D01*
G03Y414825I194J-350D01*
G02X1517425Y412919I-681J-1225D01*
G03X1516725I-350J-194D01*
G37*
G36*
G01X1526197Y412959D02*
G02X1524289Y414836I-1247J641D01*
G03X1524300Y415535I-189J353D01*
G02X1525661Y415514I699J1215D01*
G03X1525650Y414815I189J-353D01*
G02X1526154Y414319I-700J-1215D01*
G03X1526853Y414341I343J205D01*
G02X1526896Y412981I1247J-641D01*
G03X1526197Y412959I-343J-205D01*
G37*
G36*
G01X149308Y415575D02*
G02X147577Y415801I-1008J-975D01*
G03X147658Y416422I-206J343D01*
G02X149389Y416196I1008J975D01*
G03X149308Y415575I206J-343D01*
G37*
G36*
G01X621202Y416175D02*
G02X620188Y417547I-1402J25D01*
G03X620698Y417925I110J385D01*
G02X620711Y418092I1402J-25D01*
G03X620412Y418292I-198J28D01*
G02X618977Y420701I-712J1208D01*
G03X618973Y421389I-206J343D01*
G02X621066Y422810I707J1211D01*
G03X621537Y422477I396J60D01*
G02X622612Y422243I263J-1377D01*
G03X622924Y422368I116J163D01*
G02X622969Y422540I1376J-268D01*
G03X622794Y422802I-190J63D01*
G02X623345Y425530I107J1398D01*
G03X623855Y425796I127J379D01*
G02X626596Y425274I1345J-396D01*
G03X626996Y424838I398J-36D01*
G02X627621Y424693I4J-1402D01*
G03X628199Y425062I178J358D01*
G02X628979Y423843I1401J38D01*
G03X628401Y423474I-178J-358D01*
G02X627920Y422378I-1401J-39D01*
G03X627862Y421837I262J-302D01*
G02X626470Y419624I-1125J-837D01*
G03X625996Y419268I-76J-393D01*
G02X624051Y418110I-1396J132D01*
G03X623497Y417777I-156J-368D01*
G02X621712Y416553I-1397J123D01*
G03X621202Y416175I-110J-385D01*
G37*
G36*
G01X52868Y415596D02*
G02X52769Y417119I-1223J685D01*
G03X53439Y417163I321J239D01*
G02X53538Y415640I1223J-685D01*
G03X52868Y415596I-321J-239D01*
G37*
G36*
G01X1510425Y416069D02*
G02X1508519Y417975I-1225J681D01*
G03Y418675I-194J350D01*
G02Y421125I681J1225D01*
G03Y421825I-194J350D01*
G02Y424275I681J1225D01*
G03Y424975I-194J350D01*
G02Y427425I681J1225D01*
G03Y428125I-194J350D01*
G02X1508000Y428625I680J1226D01*
G03X1507303Y428602I-342J-207D01*
G02X1507259Y429974I-1244J647D01*
G03X1507956Y429997I342J207D01*
G02X1510425Y430031I1244J-647D01*
G03X1511125I350J194D01*
G02X1513575I1225J-681D01*
G03X1514275I350J194D01*
G02X1516725I1225J-681D01*
G03X1517425I350J194D01*
G02X1519331Y428125I1225J-681D01*
G03Y427425I194J-350D01*
G02Y424975I-681J-1225D01*
G03Y424275I194J-350D01*
G02X1517425Y422369I-681J-1225D01*
G03X1516725I-350J-194D01*
G02X1516181Y421825I-1225J681D01*
G03Y421125I194J-350D01*
G02X1514275Y419219I-681J-1225D01*
G03X1513575I-350J-194D01*
G02X1513031Y418675I-1225J681D01*
G03Y417975I194J-350D01*
G02X1511125Y416069I-681J-1225D01*
G03X1510425I-350J-194D01*
G37*
G36*
G01X1317793Y417890D02*
G02X1315810Y419873I-973J1010D01*
G03Y420427I-288J277D01*
G02X1317830I1010J973D01*
G03Y419873I288J-277D01*
G02X1317914Y419777I-1012J-970D01*
G03X1318226I156J125D01*
G02X1320417Y419773I1094J-877D01*
G03X1321060Y419796I313J249D01*
G02X1321233Y420003I1157J-791D01*
G03X1321267Y420535I-281J285D01*
G02X1323322Y422429I1104J864D01*
G03X1323881Y422445I271J294D01*
G02X1325879Y422462I1007J-975D01*
G03X1326434Y422453I282J284D01*
G02X1328372Y422426I955J-1027D01*
G03X1328927Y422420I281J285D01*
G02X1330862Y422410I962J-1020D01*
G03X1331416I277J288D01*
G02X1333362I973J-1010D01*
G03X1333916I277J288D01*
G02X1335965Y420501I973J-1010D01*
G03X1335982Y419968I306J-257D01*
G02X1333904Y418087I-1014J-968D01*
G03X1333297Y418088I-304J-260D01*
G02X1331263Y417994I-1062J916D01*
G03X1330709I-277J-288D01*
G02X1328753Y418004I-973J1010D01*
G03X1328198Y418010I-281J-285D01*
G02X1326246Y418038I-962J1020D01*
G03X1325691Y418047I-282J-284D01*
G02X1323784Y418045I-955J1027D01*
G03X1323225Y418029I-271J-294D01*
G02X1321120Y418131I-1008J975D01*
G03X1320477Y418108I-313J-249D01*
G02X1318347Y417890I-1157J792D01*
G03X1317793I-277J-288D01*
G37*
G36*
G01X123483Y419851D02*
G02X121934Y420567I-1241J-652D01*
G03X122200Y421143I-88J390D01*
G02X123749Y420427I1241J652D01*
G03X123483Y419851I88J-390D01*
G37*
G36*
G01X1468429Y419934D02*
G02Y421488I-1167J777D01*
G03X1469095I333J222D01*
G02Y419934I1167J-777D01*
G03X1468429I-333J-222D01*
G37*
G36*
G01X1525631Y424275D02*
G02X1524269I-681J-1225D01*
G03Y424975I-194J350D01*
G02Y427425I681J1225D01*
G03Y428125I-194J350D01*
G02X1525631I681J1225D01*
G03Y427425I194J-350D01*
G02Y424975I-681J-1225D01*
G03Y424275I194J-350D01*
G37*
G36*
G01X1532475Y422369D02*
G02X1530569Y424275I-1225J681D01*
G03Y424975I-194J350D01*
G02Y427425I681J1225D01*
G03Y428125I-194J350D01*
G02X1532475Y430031I681J1225D01*
G03X1533175I350J194D01*
G02X1535625I1225J-681D01*
G03X1536325I350J194D01*
G02X1538775I1225J-681D01*
G03X1539475I350J194D01*
G02X1541381Y428125I1225J-681D01*
G03Y427425I194J-350D01*
G02Y424975I-681J-1225D01*
G03Y424275I194J-350D01*
G02X1539475Y422369I-681J-1225D01*
G03X1538775I-350J-194D01*
G02X1536325I-1225J681D01*
G03X1535625I-350J-194D01*
G02X1533175I-1225J681D01*
G03X1532475I-350J-194D01*
G37*
G36*
G01X1668413Y425845D02*
G02X1667107Y425878I-684J-1224D01*
G03X1667125Y426585I-177J358D01*
G02X1666997Y428952I684J1224D01*
G03X1666962Y429627I-231J326D01*
G02X1668461Y429706I687J1222D01*
G03X1668496Y429031I231J-326D01*
G02X1668431Y426552I-687J-1222D01*
G03X1668413Y425845I177J-358D01*
G37*
G36*
G01X1612829Y430595D02*
G02X1611286Y430758I-894J-1080D01*
G03X1611356Y431420I-185J354D01*
G02X1611473Y433667I894J1080D01*
G03Y434333I-222J333D01*
G02X1613027I777J1167D01*
G03Y433667I222J-333D01*
G02X1612899Y431257I-777J-1167D01*
G03X1612829Y430595I185J-354D01*
G37*
G36*
G01X746945Y431271D02*
G02X745331Y431282I-815J-1141D01*
G03X745336Y431936I-228J329D01*
G02X746950Y431925I815J1141D01*
G03X746945Y431271I228J-329D01*
G37*
G36*
G01X1510425Y434969D02*
G02X1508519Y436875I-1225J681D01*
G03Y437575I-194J350D01*
G02Y440025I681J1225D01*
G03Y440725I-194J350D01*
G02X1510425Y442631I681J1225D01*
G03X1511125I350J194D01*
G02X1513575I1225J-681D01*
G03X1514275I350J194D01*
G02X1516181Y440725I1225J-681D01*
G03Y440025I194J-350D01*
G02X1516725Y439481I-681J-1225D01*
G03X1517425I350J194D01*
G02X1519331Y437575I1225J-681D01*
G03Y436875I194J-350D01*
G02X1517425Y434969I-681J-1225D01*
G03X1516725I-350J-194D01*
G02X1514275I-1225J681D01*
G03X1513575I-350J-194D01*
G02X1511125I-1225J681D01*
G03X1510425I-350J-194D01*
G37*
G36*
G01X1525631Y436875D02*
G02X1524269I-681J-1225D01*
G03Y437575I-194J350D01*
G02X1525631I681J1225D01*
G03Y436875I194J-350D01*
G37*
G36*
G01X1532475Y434969D02*
G02X1530569Y436875I-1225J681D01*
G03Y437575I-194J350D01*
G02X1532475Y439481I681J1225D01*
G03X1533175I350J194D01*
G02X1535625I1225J-681D01*
G03X1536325I350J194D01*
G02X1538775I1225J-681D01*
G03X1539475I350J194D01*
G02X1541381Y437575I1225J-681D01*
G03Y436875I194J-350D01*
G02X1540019I-681J-1225D01*
G03Y437575I-194J350D01*
G02X1539475Y438119I681J1225D01*
G03X1538775I-350J-194D01*
G02X1536325I-1225J681D01*
G03X1535625I-350J-194D01*
G02X1535081Y437575I-1225J681D01*
G03Y436875I194J-350D01*
G02X1533175Y434969I-681J-1225D01*
G03X1532475I-350J-194D01*
G37*
G36*
G01X1665691Y439085D02*
G02X1663833I-929J-1050D01*
G03Y439685I-265J300D01*
G02X1663985Y441902I929J1050D01*
G03Y442568I-222J333D01*
G02X1665539I777J1167D01*
G03Y441902I222J-333D01*
G02X1665812Y441664I-777J-1167D01*
G03X1666412I300J265D01*
G02X1668435Y441745I1050J-929D01*
G03X1668989I277J288D01*
G02X1670527Y439452I973J-1010D01*
G03X1670330Y438907I161J-366D01*
G02X1667769Y438789I-1254J-626D01*
G03X1667411Y439334I-373J145D01*
G02X1666412Y439806I51J1401D01*
G03X1665812I-300J-265D01*
G02X1665691Y439685I-1050J929D01*
G03Y439085I265J-300D01*
G37*
G36*
G01X1544591Y440047D02*
G02X1543231Y440004I-641J-1247D01*
G03X1543209Y440703I-205J343D01*
G02X1543169Y443175I641J1247D01*
G03Y443875I-194J350D01*
G02X1542625Y444419I681J1225D01*
G03X1541925I-350J-194D01*
G02X1539475I-1225J681D01*
G03X1538775I-350J-194D01*
G02X1536325I-1225J681D01*
G03X1535625I-350J-194D01*
G02X1533175I-1225J681D01*
G03X1532475I-350J-194D01*
G02X1530569Y446325I-1225J681D01*
G03Y447025I-194J350D01*
G02X1532475Y448931I681J1225D01*
G03X1533175I350J194D01*
G02X1535625I1225J-681D01*
G03X1536325I350J194D01*
G02X1538775I1225J-681D01*
G03X1539475I350J194D01*
G02X1541381Y447025I1225J-681D01*
G03Y446325I194J-350D01*
G02X1541925Y445781I-681J-1225D01*
G03X1542625I350J194D01*
G02X1544531Y443875I1225J-681D01*
G03Y443175I194J-350D01*
G02X1544569Y440746I-681J-1225D01*
G03X1544591Y440047I205J-343D01*
G37*
G36*
G01X1286805Y441007D02*
G02X1285559Y441448I-1036J-945D01*
G03X1285795Y442113I-60J395D01*
G02X1286911Y444458I1036J945D01*
G03X1287320Y444964I24J399D01*
G02X1288591Y443938I1351J374D01*
G03X1288182Y443432I-24J-399D01*
G02X1287041Y441672I-1351J-374D01*
G03X1286805Y441007I60J-395D01*
G37*
G36*
G01X1725270Y442675D02*
G02X1723640Y442799I-901J-1074D01*
G03X1723689Y443447I-208J342D01*
G02X1723579Y443550I902J1073D01*
G03X1723001I-289J-277D01*
G02Y445492I-1011J971D01*
G03X1723579I289J277D01*
G02X1725804Y445222I1011J-971D01*
G03X1726476Y445191I346J201D01*
G02X1726406Y443679I1144J-811D01*
G03X1725734Y443710I-346J-201D01*
G02X1725319Y443323I-1144J811D01*
G03X1725270Y442675I208J-342D01*
G37*
G36*
G01X1602290Y445654D02*
G02X1601199Y444330I310J-1367D01*
G03X1600710Y444733I-400J13D01*
G02X1601801Y446057I-310J1367D01*
G03X1602290Y445654I400J-13D01*
G37*
G36*
G01X1523025Y444419D02*
G02Y445781I-1225J681D01*
G03X1523725I350J194D01*
G02X1524269Y446325I1225J-681D01*
G03Y447025I-194J350D01*
G02X1525631I681J1225D01*
G03Y446325I194J-350D01*
G02X1523725Y444419I-681J-1225D01*
G03X1523025I-350J-194D01*
G37*
G36*
G01X1504495Y446629D02*
G02X1503769Y448171I-1370J297D01*
G03X1504344Y448442I184J355D01*
G02X1505070Y446900I1370J-297D01*
G03X1504495Y446629I-184J-355D01*
G37*
G36*
G01X1918547Y447249D02*
G02X1916039Y447364I-1225J681D01*
G03X1915340Y447424I-366J-162D01*
G02X1915456Y448766I-1167J777D01*
G03X1916155Y448706I366J162D01*
G02X1918547Y448611I1167J-776D01*
G03X1919247I350J194D01*
G02Y447249I1225J-681D01*
G03X1918547I-350J-194D01*
G37*
G36*
G01X1516725Y447569D02*
G02X1514777Y449451I-1225J681D01*
G03X1514753Y450151I-205J343D01*
G02X1516112Y450199I636J1249D01*
G03X1516136Y449499I205J-343D01*
G02X1516725Y448931I-636J-1249D01*
G03X1517425I350J194D01*
G02X1517996Y449490I1225J-681D01*
G03X1518002Y450195I-186J354D01*
G02X1519896Y452114I673J1230D01*
G03X1520590Y452108I349J196D01*
G02X1520579Y450711I1210J-708D01*
G03X1519885Y450717I-349J-196D01*
G02X1519329Y450185I-1210J708D01*
G03X1519323Y449480I186J-354D01*
G02X1517425Y447569I-673J-1230D01*
G03X1516725I-350J-194D01*
G37*
G36*
G01X1933562Y449612D02*
G02X1933835Y451960I-3243J1567D01*
G03X1934464Y451726I390J87D01*
G02X1934228Y449696I836J-1126D01*
G03X1933562Y449612I-306J-258D01*
G37*
G36*
G01X1887351Y453165D02*
G02X1884768Y453561I-1151J1115D01*
G03X1884063Y453579I-357J-180D01*
G02X1884101Y455087I-1394J790D01*
G03X1884806Y455069I357J180D01*
G02X1887264Y455477I1394J-789D01*
G03X1887817Y455498I266J299D01*
G02X1890228Y455372I1151J-1115D01*
G03X1890858I315J247D01*
G02Y453394I1260J-989D01*
G03X1890228I-315J-247D01*
G02X1887904Y453186I-1260J989D01*
G03X1887351Y453165I-266J-299D01*
G37*
G36*
G01X1842797Y453544D02*
G02Y455098I-1167J777D01*
G03X1843463I333J222D01*
G02Y453544I1167J-777D01*
G03X1842797I-333J-222D01*
G37*
G36*
G01X22038Y453348D02*
G02X19937Y455766I-1040J1218D01*
G03Y456366I-265J300D01*
G02X20141Y458919I1061J1200D01*
G03X20165Y459579I-214J338D01*
G02X22158Y462084I953J1287D01*
G03X22678I260J304D01*
G02X24758I1040J-1218D01*
G03X25278I260J304D01*
G02X27382Y462064I1041J-1218D01*
G03X27915Y462066I265J299D01*
G02X29845Y459523I1073J-1190D01*
G03X29821Y458863I214J-338D01*
G02X29929Y456376I-953J-1287D01*
G03Y455776I265J-300D01*
G02X27804Y453378I-1061J-1200D01*
G03X27271Y453376I-265J-299D01*
G02X25158Y453348I-1072J1190D01*
G03X24638I-260J-304D01*
G02X22558I-1040J1218D01*
G03X22038I-260J-304D01*
G37*
G36*
G01X620740Y465350D02*
G02X619173Y464668I-340J-1360D01*
G03X618920Y465250I-350J194D01*
G02X618450Y467754I340J1360D01*
G03X618479Y468385I-231J327D01*
G02X620200Y468306I911J1065D01*
G03X620171Y467675I231J-327D01*
G02X620487Y465932I-911J-1065D01*
G03X620740Y465350I350J-194D01*
G37*
G36*
G01X-5187Y465904D02*
G02X-6694Y466110I-913J-1064D01*
G03X-6603Y466776I-169J362D01*
G02X-5096Y466570I913J1064D01*
G03X-5187Y465904I169J-362D01*
G37*
G36*
G01X635166Y468771D02*
G02X633700Y469205I-1133J-1133D01*
G03X633917Y469861I-83J391D01*
G02X633628Y471206I1050J929D01*
G03X633151Y471713I-382J118D01*
G02X634270Y472704I-380J1556D01*
G03X634716Y472169I374J-141D01*
G02X635277Y472157I251J-1379D01*
G03X635761Y472605I88J390D01*
G02X636838Y471442I1387J204D01*
G03X636354Y470994I-88J-390D01*
G02X635342Y469439I-1387J-204D01*
G03X635166Y468771I107J-385D01*
G37*
G36*
G01X1617774Y469168D02*
G02Y470722I-1167J777D01*
G03X1618440I333J222D01*
G02Y469168I1167J-777D01*
G03X1617774I-333J-222D01*
G37*
G36*
G01X1911277Y473167D02*
G02X1909723I-777J-1167D01*
G03Y473833I-222J333D01*
G02X1911277I777J1167D01*
G03Y473167I222J-333D01*
G37*
G36*
G01X607004Y472635D02*
G02X604816Y474367I-1179J759D01*
G03Y474921I-288J277D01*
G02X606836I1010J973D01*
G03Y474367I288J-277D01*
G02X606961Y474216I-1015J-967D01*
G03X607622Y474234I324J235D01*
G02X607665Y472653I1178J-759D01*
G03X607004Y472635I-324J-235D01*
G37*
G36*
G01X66784Y476042D02*
G02X65693Y476991I-1334J-432D01*
G03X66143Y477508I70J394D01*
G02X67234Y476559I1334J432D01*
G03X66784Y476042I-70J-394D01*
G37*
G36*
G01X1841917Y474947D02*
G02Y476501I-1167J777D01*
G03X1842583I333J222D01*
G02Y474947I1167J-777D01*
G03X1841917I-333J-222D01*
G37*
G36*
G01X1419345Y478440D02*
G03X1420012Y478737I267J297D01*
G01Y478924D01*
X1429016D01*
Y476922D01*
X1419795D01*
X1419746Y476792D01*
G02X1419345Y478440I-1405J531D01*
G37*
G36*
G01X4127Y479339D02*
G02X3786Y477842I973J-1009D01*
G03X3133Y477991I-375J-139D01*
G02X931Y478326I-973J1009D01*
G03X229I-351J-192D01*
G02Y479674I-1229J674D01*
G03X931I351J192D01*
G02X1566Y480270I1229J-674D01*
G03X1661Y480932I-170J362D01*
G02X3795Y482698I928J1051D01*
G03X4483I344J204D01*
G02Y481268I1206J-715D01*
G03X3795I-344J-204D01*
G02X3183Y480713I-1206J715D01*
G03X3088Y480051I170J-362D01*
G02X3474Y479488I-928J-1050D01*
G03X4127Y479339I375J139D01*
G37*
G36*
G01X90883Y478991D02*
G02X90312Y480342I-1386J210D01*
G03X90940Y480608I232J325D01*
G02X93029Y481611I1386J-210D01*
G03X93622Y481881I200J346D01*
G02X94295Y480399I1376J-269D01*
G03X93702Y480129I-200J-346D01*
G02X91511Y479257I-1376J269D01*
G03X90883Y478991I-232J-325D01*
G37*
G36*
G01X1599811Y478370D02*
G02Y480080I-1111J855D01*
G03X1600446I317J243D01*
G02Y478370I1111J-855D01*
G03X1599811I-317J-243D01*
G37*
G36*
G01X1570800Y480997D02*
G02X1569699Y482101I-1375J-271D01*
G03X1570170Y482571I78J392D01*
G02X1571271Y481467I1375J271D01*
G03X1570800Y480997I-78J-392D01*
G37*
G36*
G01X626879Y481069D02*
G02X626695Y482403I-1310J499D01*
G03X627390Y482499I321J239D01*
G02X627574Y481165I1310J-499D01*
G03X626879Y481069I-321J-239D01*
G37*
G36*
G01X1367274Y482870D02*
G03X1367937Y483124I266J299D01*
G01X1376942D01*
Y481122D01*
X1367940D01*
Y481242D01*
X1367622D01*
X1367565Y481139D01*
G02X1367274Y482870I-1224J684D01*
G37*
G36*
G01X1419352Y481458D02*
G02X1419641Y483247I-911J1065D01*
G01X1419700Y483151D01*
X1420012D01*
Y483324D01*
X1429016D01*
Y481322D01*
X1419976D01*
G03X1419352Y481458I-363J-168D01*
G37*
G36*
G01X1387174Y483670D02*
G03X1387837Y483924I266J299D01*
G01X1396842D01*
Y481922D01*
X1387840D01*
Y482042D01*
X1387522D01*
X1387465Y481939D01*
G02X1387174Y483670I-1224J684D01*
G37*
G36*
G01X32607Y481958D02*
G02X32544Y483698I-1130J830D01*
G03X33170Y483720I304J259D01*
G02X33233Y481980I1130J-830D01*
G03X32607Y481958I-304J-259D01*
G37*
G36*
G01X1443612Y481522D02*
Y481754D01*
G03X1442908Y482014I-400J0D01*
G02X1443216Y483201I-1066J910D01*
G01X1443249Y483040D01*
X1443612D01*
Y483524D01*
X1452616D01*
Y481522D01*
X1443612D01*
G37*
G36*
G01X1688120Y485257D02*
G02X1686836Y485235I-621J-1257D01*
G03X1686823Y485946I-190J352D01*
G02X1688416Y488213I620J1257D01*
G03X1688970I277J288D01*
G02X1690893Y488234I973J-1010D01*
G03X1691448Y488247I271J294D01*
G02X1691493Y486228I995J-988D01*
G03X1690938Y486215I-271J-294D01*
G02X1688970Y486193I-995J988D01*
G03X1688416I-277J-288D01*
G02X1688107Y485968I-972J1010D01*
G03X1688120Y485257I190J-352D01*
G37*
G36*
G01X1457304Y487077D02*
G02X1455890Y487072I-703J-1213D01*
G03X1455888Y487763I-203J345D01*
G02X1457302Y487768I703J1213D01*
G03X1457304Y487077I203J-345D01*
G37*
G36*
G01X1367473Y487399D02*
X1367533Y487310D01*
X1367840D01*
Y487524D01*
X1376842D01*
Y485522D01*
X1367840D01*
Y485926D01*
X1367533D01*
X1367473Y485837D01*
G02Y487399I-1164J781D01*
G37*
G36*
G01X657051Y487930D02*
G02X655110Y487893I-951J-1030D01*
G03X655099Y488470I-282J283D01*
G02X657402Y489870I951J1030D01*
G03X658073Y489694I386J105D01*
G02X657718Y488339I997J-985D01*
G03X657047Y488515I-386J-105D01*
G02X657040Y488507I-1056J917D01*
G03X657051Y487930I282J-283D01*
G37*
G36*
G01X1448101Y488722D02*
X1443463D01*
X1443409Y488604D01*
G02X1442987Y490389I-1368J619D01*
G03X1443640Y490700I253J310D01*
G01Y490724D01*
X1452642D01*
Y488556D01*
X1452761Y488503D01*
G02X1451149Y486281I-574J-1280D01*
G03X1450568Y486293I-296J-268D01*
G02X1448426Y488089I-1000J983D01*
G03X1448101Y488722I-326J233D01*
G37*
G36*
G01X1387465Y488007D02*
X1387522Y487904D01*
X1387840D01*
Y488324D01*
X1396842D01*
Y486322D01*
X1387840D01*
Y486742D01*
X1387522D01*
X1387465Y486639D01*
G02Y488007I-1224J684D01*
G37*
G36*
G01X1642122Y488168D02*
G02X1641073Y489131I-1341J-408D01*
G03X1641539Y489639I83J391D01*
G02X1642588Y488676I1341J408D01*
G03X1642122Y488168I-83J-391D01*
G37*
G36*
G01X729744Y488062D02*
G02X729310Y489399I-1371J294D01*
G03X729968Y489613I267J298D01*
G02X730402Y488276I1371J-294D01*
G03X729744Y488062I-267J-298D01*
G37*
G36*
G01X1419174Y490570D02*
G03X1419840Y490868I266J299D01*
G01Y490924D01*
X1428842D01*
Y488922D01*
X1419840D01*
Y488942D01*
X1419522D01*
X1419465Y488839D01*
G02X1419174Y490570I-1224J684D01*
G37*
G36*
G01X1369374Y493770D02*
G03X1370037Y494024I266J299D01*
G01X1379042D01*
Y492022D01*
X1370040D01*
Y492142D01*
X1369722D01*
X1369665Y492039D01*
G02X1369374Y493770I-1224J684D01*
G37*
G36*
G01X1389674Y494670D02*
G03X1390340Y494968I266J299D01*
G01Y495224D01*
X1399342D01*
Y493222D01*
X1390091D01*
X1390040Y493097D01*
G02X1389674Y494670I-1299J527D01*
G37*
G36*
G01X1442974Y493376D02*
G02X1443265Y495107I-933J1047D01*
G01X1443322Y495004D01*
X1443640D01*
Y495124D01*
X1452642D01*
Y493122D01*
X1443637D01*
G03X1442974Y493376I-397J-45D01*
G37*
G36*
G01X1641064Y497040D02*
G02X1640645Y495487I899J-1076D01*
G03X1640012Y495658I-376J-136D01*
G02X1640431Y497211I-899J1076D01*
G03X1641064Y497040I376J136D01*
G37*
G36*
G01X1590192Y495198D02*
G02Y496752I-1167J777D01*
G03X1590858I333J222D01*
G02Y495198I1167J-777D01*
G03X1590192I-333J-222D01*
G37*
G36*
G01X1268014Y497007D02*
G02X1267785Y495327I992J-991D01*
G03X1267154Y495413I-348J-197D01*
G02X1267383Y497093I-992J991D01*
G03X1268014Y497007I348J197D01*
G37*
G36*
G01X1279705Y497522D02*
G02X1279311Y495877I890J-1083D01*
G03X1278690Y496025I-366J-161D01*
G02X1279084Y497670I-890J1083D01*
G03X1279705Y497522I366J161D01*
G37*
G36*
G01X1728637Y501596D02*
X1733639D01*
G02X1735150Y500095I0J-1511D01*
G01Y500000D01*
X1735141Y499916D01*
G02X1733639Y498574I-1502J169D01*
G01X1729602D01*
G03X1729310Y497901I0J-400D01*
G02X1726932Y495754I-1171J-1094D01*
G03X1726418Y495829I-301J-263D01*
G02X1723965Y497144I-852J1357D01*
G03X1723570Y497533I-400J-11D01*
G02X1723600Y500737I21J1602D01*
G03X1724002Y501110I3J400D01*
G02X1727123Y501498I1598J-110D01*
G03X1727741Y501301I380J124D01*
G02X1728637Y501596I897J-1216D01*
G37*
G36*
G01X1789242Y495925D02*
G02X1786803Y496003I-1197J729D01*
G03X1786100Y496014I-354J-185D01*
G02X1786120Y497352I-1222J687D01*
G03X1786823Y497341I354J185D01*
G02X1789235Y497396I1222J-687D01*
G03X1789916Y497399I340J211D01*
G02X1789923Y495928I1197J-730D01*
G03X1789242Y495925I-340J-211D01*
G37*
G36*
G01X328856Y501472D02*
X328040D01*
G03X327764Y500782I0J-400D01*
G02X327815Y498803I-967J-1015D01*
G03X327843Y498227I291J-275D01*
G02X325904Y498134I-921J-1057D01*
G03X325876Y498710I-291J275D01*
G02X326496Y501136I921J1057D01*
G01X326652Y501171D01*
Y507350D01*
X325508D01*
Y501472D01*
X323306D01*
Y507350D01*
X312122D01*
Y501472D01*
X309920D01*
Y507520D01*
X308650Y508789D01*
Y513089D01*
X305150Y516589D01*
Y519211D01*
X306574Y520634D01*
Y526684D01*
X308776D01*
Y520950D01*
X313266D01*
Y526684D01*
X315470D01*
Y520950D01*
X319960D01*
Y526684D01*
X322162D01*
Y520950D01*
X323306D01*
Y526684D01*
X325508D01*
Y520950D01*
X329998D01*
Y526684D01*
X332202D01*
Y520950D01*
X333346D01*
Y526684D01*
X335548D01*
Y520950D01*
X340038D01*
Y526684D01*
X342242D01*
Y520950D01*
X343384D01*
Y526684D01*
X345588D01*
Y520950D01*
X350078D01*
Y526684D01*
X352280D01*
Y520950D01*
X353424D01*
Y526684D01*
X355626D01*
Y520950D01*
X360116D01*
Y526684D01*
X362320D01*
Y520950D01*
X363464D01*
Y526684D01*
X365666D01*
Y520950D01*
X368911D01*
X370150Y519711D01*
Y508589D01*
X368911Y507350D01*
X365666D01*
Y501472D01*
X363464D01*
Y507350D01*
X362320D01*
Y501472D01*
X360116D01*
Y507350D01*
X355626D01*
Y501472D01*
X353424D01*
Y507350D01*
X348934D01*
Y501472D01*
X346732D01*
Y507350D01*
X345588D01*
Y501472D01*
X343384D01*
Y507350D01*
X338894D01*
Y501472D01*
X336692D01*
Y507350D01*
X335548D01*
Y501472D01*
X333346D01*
Y507350D01*
X328856D01*
Y501472D01*
G37*
G36*
G01X978464D02*
X977665D01*
G03X977389Y500782I0J-400D01*
G02X977433Y498798I-968J-1014D01*
G03X977457Y498221I289J-277D01*
G02X975518Y498140I-927J-1051D01*
G03X975494Y498717I-289J277D01*
G02X976106Y501134I927J1051D01*
G01X976260Y501170D01*
Y506950D01*
X975116D01*
Y501472D01*
X972914D01*
Y506950D01*
X961730D01*
Y501472D01*
X959528D01*
Y507512D01*
X958250Y508789D01*
Y513089D01*
X954750Y516589D01*
Y519711D01*
X956182Y521142D01*
Y526684D01*
X958384D01*
Y521150D01*
X962874D01*
Y526684D01*
X965078D01*
Y521150D01*
X969568D01*
Y526684D01*
X971770D01*
Y521150D01*
X972914D01*
Y526684D01*
X975116D01*
Y521150D01*
X979606D01*
Y526684D01*
X981810D01*
Y521150D01*
X982954D01*
Y526684D01*
X985156D01*
Y521150D01*
X989646D01*
Y526684D01*
X991850D01*
Y521150D01*
X992992D01*
Y526684D01*
X995196D01*
Y521150D01*
X999686D01*
Y526684D01*
X1001888D01*
Y521150D01*
X1003032D01*
Y526684D01*
X1005234D01*
Y521150D01*
X1009724D01*
Y526684D01*
X1011928D01*
Y521150D01*
X1013072D01*
Y526684D01*
X1015274D01*
Y521150D01*
X1018111D01*
X1020050Y519211D01*
Y509389D01*
X1017611Y506950D01*
X1015274D01*
Y501472D01*
X1013072D01*
Y506950D01*
X1011928D01*
Y501472D01*
X1009724D01*
Y506950D01*
X1005234D01*
Y501472D01*
X1003032D01*
Y506950D01*
X998542D01*
Y501472D01*
X996340D01*
Y506950D01*
X995196D01*
Y501472D01*
X992992D01*
Y506950D01*
X988502D01*
Y501472D01*
X986300D01*
Y506950D01*
X985156D01*
Y501472D01*
X982954D01*
Y506950D01*
X978464D01*
Y501472D01*
G37*
G36*
G01X1369665Y498207D02*
X1369722Y498104D01*
X1370040D01*
Y498424D01*
X1379042D01*
Y496422D01*
X1370040D01*
Y496942D01*
X1369722D01*
X1369665Y496839D01*
G02Y498207I-1224J684D01*
G37*
G36*
G01X689432Y497063D02*
G02X689149Y498770I-1230J673D01*
G03X689770Y498873I270J295D01*
G02X690053Y497166I1230J-673D01*
G03X689432Y497063I-270J-295D01*
G37*
G36*
G01X1616058Y497784D02*
G02X1615976Y499474I-1158J791D01*
G03X1616613Y499505I307J256D01*
G02X1616695Y497815I1158J-791D01*
G03X1616058Y497784I-307J-256D01*
G37*
G36*
G01X1389669Y497714D02*
G02X1389962Y499393I-950J1031D01*
G01X1390018Y499286D01*
X1390340D01*
Y499524D01*
X1399342D01*
Y497522D01*
X1390326D01*
G03X1389669Y497714I-387J-103D01*
G37*
G36*
G01X55164Y501438D02*
G02X53088Y503514I-1264J812D01*
G03Y504186I-216J336D01*
G02X55164Y506262I812J1264D01*
G03X55836I336J216D01*
G02X58364I1264J-812D01*
G03X59036I336J216D01*
G02X61112Y504186I1264J-812D01*
G03Y503514I216J-336D01*
G02X59036Y501438I-812J-1264D01*
G03X58364I-336J-216D01*
G02X55836I-1264J812D01*
G03X55164I-336J-216D01*
G37*
G36*
G01X120987Y509224D02*
G03X121299Y508574I312J-250D01*
G01X121374D01*
Y501472D01*
X119172D01*
Y508574D01*
X119192D01*
Y508880D01*
X119105Y508940D01*
G02X120987Y509224I787J1160D01*
G37*
G36*
G01X770595D02*
G03X770907Y508574I312J-250D01*
G01X770982D01*
Y501472D01*
X768780D01*
Y508574D01*
X768800D01*
Y508880D01*
X768713Y508940D01*
G02X770595Y509224I787J1160D01*
G37*
G36*
G01X1565777Y504496D02*
G02X1564223I-777J-1167D01*
G03Y505162I-222J333D01*
G02X1565777I777J1167D01*
G03Y504496I222J-333D01*
G37*
G36*
G01X680274Y503064D02*
G02X680159Y504602I-1225J682D01*
G03X680825Y504652I317J245D01*
G02X680940Y503114I1225J-682D01*
G03X680274Y503064I-317J-245D01*
G37*
G36*
G01X1689443Y505238D02*
G02X1688723Y503689I648J-1243D01*
G03X1688148Y503957I-391J-87D01*
G02X1686391Y504342I-648J1243D01*
G03X1685759I-316J-245D01*
G02Y506058I-1109J858D01*
G03X1686391I316J245D01*
G02X1688868Y505506I1109J-858D01*
G03X1689443Y505238I391J87D01*
G37*
G36*
G01X1333988Y506103D02*
G02X1331680Y507358I-1388J197D01*
G03X1331658Y507979I-263J302D01*
G02X1333892Y509263I842J1121D01*
G03X1334470Y508952I398J46D01*
G02X1334543Y506413I630J-1252D01*
G03X1333988Y506103I-159J-367D01*
G37*
G36*
G01X1534568Y510040D02*
G02X1532953Y510276I-972J-1010D01*
G03X1533047Y510920I-183J356D01*
G02X1534662Y510684I972J1010D01*
G03X1534568Y510040I183J-356D01*
G37*
G36*
G01X1401610Y509379D02*
G02X1401229Y511321I-1165J780D01*
G03X1401785Y511430I224J332D01*
G02X1404117Y511427I1165J-780D01*
G03X1404783I333J222D01*
G02X1406073Y512047I1167J-777D01*
G03X1406502Y512513I35J398D01*
G02X1407761Y511354I1382J238D01*
G03X1407332Y510888I-35J-398D01*
G02X1404783Y509873I-1382J-238D01*
G03X1404117I-333J-222D01*
G02X1402166Y509488I-1167J777D01*
G03X1401610Y509379I-224J-332D01*
G37*
G36*
G01X1910967Y509923D02*
G02Y511477I-1167J777D01*
G03X1911633I333J222D01*
G02Y509923I1167J-777D01*
G03X1910967I-333J-222D01*
G37*
G36*
G01X1296853Y509800D02*
G02X1294958Y511866I-973J1010D01*
G03X1294975Y512452I-263J301D01*
G02X1295183Y514617I985J998D01*
G03Y515283I-222J333D01*
G02Y517617I777J1167D01*
G03Y518283I-222J333D01*
G02X1296933Y520460I778J1167D01*
G03X1297487I277J288D01*
G02X1299237Y518283I972J-1010D01*
G03Y517617I222J-333D01*
G02Y515283I-777J-1167D01*
G03Y514617I222J-333D01*
G02X1299382Y512394I-777J-1167D01*
G03X1299365Y511808I263J-301D01*
G02X1297407Y509800I-985J-998D01*
G03X1296853I-277J-288D01*
G37*
G36*
G01X713293Y511963D02*
G02X713170Y513605I-1193J736D01*
G03X713816Y513654I305J259D01*
G02X713939Y512012I1193J-736D01*
G03X713293Y511963I-305J-259D01*
G37*
G36*
G01X1828753Y514383D02*
G02X1826598Y513175I-753J-1183D01*
G03X1826088Y513553I-400J-7D01*
G02X1826184Y516216I-388J1347D01*
G03X1826716Y516527I137J375D01*
G02X1827212Y517385I1384J-227D01*
G03X1827234Y517984I-254J309D01*
G02X1829088Y517915I966J1016D01*
G03X1829066Y517316I254J-309D01*
G02X1828775Y515071I-966J-1016D01*
G03X1828753Y514383I192J-351D01*
G37*
G36*
G01X1797553Y514117D02*
G02X1796878Y515400I-1400J83D01*
G03X1797483Y515719I206J343D01*
G02X1799952Y516543I1400J-83D01*
G03X1800555Y516535I305J259D01*
G02X1800531Y514693I1045J-935D01*
G03X1799928Y514701I-305J-259D01*
G02X1798158Y514436I-1045J935D01*
G03X1797553Y514117I-206J-343D01*
G37*
G36*
G01X1340419Y516938D02*
G02X1339015Y517074I-819J-1138D01*
G03X1339081Y517762I-167J363D01*
G02X1340485Y517626I819J1138D01*
G03X1340419Y516938I167J-363D01*
G37*
G36*
G01X1861057Y521367D02*
G02X1859312Y521214I-777J-1167D01*
G03X1859126Y521894I-276J290D01*
G02X1861122Y522069I728J3169D01*
G03X1861057Y521367I156J-368D01*
G37*
G36*
G01X41429Y521343D02*
G02X40279Y522116I-1318J-720D01*
G03X40675Y522705I45J397D01*
G02X41825Y521932I1318J720D01*
G03X41429Y521343I-45J-397D01*
G37*
G36*
G01X1804213Y522569D02*
G02X1802541Y526180I-3227J698D01*
G03X1803122Y526459I188J353D01*
G02X1803575Y527253I1378J-260D01*
G03X1803409Y527942I-264J301D01*
G02X1804677Y528248I343J1359D01*
G03X1804843Y527559I264J-301D01*
G02X1805726Y525521I-343J-1359D01*
G03X1806076Y524927I350J-194D01*
G02X1804931Y522716I0J-1402D01*
G03X1804213Y522569I-327J-231D01*
G37*
G36*
G01X1415993Y520663D02*
G02X1415941Y522214I-1193J736D01*
G03X1416607Y522237I325J233D01*
G02X1416659Y520686I1193J-736D01*
G03X1415993Y520663I-325J-233D01*
G37*
G36*
G01X90674Y523007D02*
G02X90451Y521273I976J-1007D01*
G03X89831Y521352I-342J-208D01*
G02X90054Y523086I-976J1007D01*
G03X90674Y523007I342J208D01*
G37*
G36*
G01X47646Y524933D02*
G02X46049Y525384I-1139J-980D01*
G03X46230Y526025I-122J381D01*
G02X47827Y525574I1139J980D01*
G03X47646Y524933I122J-381D01*
G37*
G36*
G01X1437747Y525335D02*
G02X1436550Y526531I-1389J-193D01*
G03X1437001Y526982I55J396D01*
G02X1438198Y525786I1389J193D01*
G03X1437747Y525335I-55J-396D01*
G37*
G36*
G01X717110Y526173D02*
G02X715090I-1010J-973D01*
G03Y526727I-288J277D01*
G02X715006Y526823I1012J970D01*
G03X714694I-156J-125D01*
G02X713488Y526302I-1094J877D01*
G03X713067Y525810I-32J-399D01*
G02X711816Y526881I-1363J-327D01*
G03X712237Y527373I32J399D01*
G02X712590Y528673I1363J328D01*
G03Y529227I-288J277D01*
G02Y531173I1010J973D01*
G03Y531727I-288J277D01*
G02X714573Y533710I1010J973D01*
G03X715127I277J288D01*
G02X717110Y531727I973J-1010D01*
G03Y531173I288J-277D01*
G02Y529227I-1010J-973D01*
G03Y528673I288J-277D01*
G02Y526727I-1010J-973D01*
G03Y526173I288J-277D01*
G37*
G36*
G01X1296749Y526817D02*
G02X1294883Y528867I-1089J883D01*
G03Y529533I-222J333D01*
G02Y531867I777J1167D01*
G03Y532533I-222J333D01*
G02Y534867I777J1167D01*
G03Y535533I-222J333D01*
G02X1296749Y537583I777J1167D01*
G03X1297371I311J252D01*
G02X1299237Y535533I1089J-883D01*
G03Y534867I222J-333D01*
G02Y532533I-777J-1167D01*
G03Y531867I222J-333D01*
G02Y529533I-777J-1167D01*
G03Y528867I222J-333D01*
G02X1297371Y526817I-777J-1167D01*
G03X1296749I-311J-252D01*
G37*
G36*
G01X309343Y528053D02*
G02X309250Y529790I-1145J810D01*
G03X309876Y529824I300J265D01*
G02X309969Y528087I1145J-810D01*
G03X309343Y528053I-300J-265D01*
G37*
G36*
G01X958951D02*
G02X958858Y529790I-1145J810D01*
G03X959484Y529824I300J265D01*
G02X959577Y528087I1145J-810D01*
G03X958951Y528053I-300J-265D01*
G37*
G36*
G01X652317Y529423D02*
G02X650121Y531152I-1167J777D01*
G03X650110Y531707I-293J272D01*
G02X652283Y533453I991J992D01*
G03X652971Y533475I337J214D01*
G02X655151Y531770I1229J-675D01*
G03X655140Y531193I271J-294D01*
G02X652983Y529423I-990J-993D01*
G03X652317I-333J-222D01*
G37*
G36*
G01X658223Y530290D02*
G02X656473Y532467I-972J1010D01*
G03Y533133I-222J333D01*
G02X658223Y535310I778J1167D01*
G03X658777I277J288D01*
G02X660527Y533133I972J-1010D01*
G03Y532467I222J-333D01*
G02X658777Y530290I-778J-1167D01*
G03X658223I-277J-288D01*
G37*
G36*
G01X1460414Y532386D02*
G02X1460352Y530695I1086J-886D01*
G03X1459715Y530718I-327J-230D01*
G02X1459777Y532409I-1086J886D01*
G03X1460414Y532386I327J230D01*
G37*
G36*
G01X726180Y532943D02*
G02X726154Y534496I-1180J757D01*
G03X726820Y534507I329J227D01*
G02X726846Y532954I1180J-757D01*
G03X726180Y532943I-329J-227D01*
G37*
G36*
G01X63667Y534723D02*
G02Y536277I-1167J777D01*
G03X64333I333J222D01*
G02X66667I1167J-777D01*
G03X67333I333J222D01*
G02Y534723I1167J-777D01*
G03X66667I-333J-222D01*
G02X64333I-1167J777D01*
G03X63667I-333J-222D01*
G37*
G36*
G01X1385303Y534550D02*
G02X1383533Y536707I-993J990D01*
G03Y537373I-222J333D01*
G02Y539707I777J1167D01*
G03Y540373I-222J333D01*
G02X1382961Y541923I777J1167D01*
G03X1382522Y542429I-384J110D01*
G02X1383680Y543435I-191J1389D01*
G03X1384119Y542929I384J-110D01*
G02X1385295Y542538I191J-1389D01*
G03X1385848Y542529I281J284D01*
G02X1386507Y542871I952J-1029D01*
G03X1386753Y543490I-83J391D01*
G02X1388200Y542915I1154J796D01*
G03X1387954Y542296I83J-391D01*
G02X1387577Y540333I-1154J-796D01*
G03Y539667I222J-333D01*
G02X1387632Y537372I-777J-1167D01*
G03Y536728I238J-322D01*
G02X1385856Y534564I-832J-1128D01*
G03X1385303Y534550I-269J-296D01*
G37*
G36*
G01X71506Y537405D02*
G02X69730Y539561I-984J999D01*
G03X69725Y540224I-226J330D01*
G02X71455Y542419I774J1169D01*
G03X72012Y542430I273J292D01*
G02X73953Y542481I997J-986D01*
G03X74497Y542486I269J296D01*
G02X76433Y542478I964J-1018D01*
G03X76988I277J288D01*
G02X78905Y542504I972J-1010D01*
G03X79444I270J295D01*
G02X81166Y540301I944J-1036D01*
G03Y539635I222J-333D01*
G02X79444Y537432I-778J-1167D01*
G03X78905I-270J-295D01*
G02X76988Y537458I-945J1036D01*
G03X76433I-277J-288D01*
G02X74517Y537431I-972J1010D01*
G03X73973Y537426I-269J-296D01*
G02X72058Y537414I-964J1018D01*
G03X71506Y537405I-271J-294D01*
G37*
G36*
G01X646927Y541517D02*
G02X645373I-777J-1167D01*
G03Y542183I-222J333D01*
G02Y544517I777J1167D01*
G03Y545183I-222J333D01*
G02X646927I777J1167D01*
G03Y544517I222J-333D01*
G02Y542183I-777J-1167D01*
G03Y541517I222J-333D01*
G37*
G36*
G01X120987Y547024D02*
G03X121299Y546374I312J-250D01*
G01X121374D01*
Y539272D01*
X119172D01*
Y546374D01*
X119192D01*
Y546680D01*
X119105Y546740D01*
G02X120987Y547024I787J1160D01*
G37*
G36*
G01X311790Y546742D02*
X311700Y546682D01*
Y546374D01*
X312122D01*
Y539272D01*
X309920D01*
Y546374D01*
X310342D01*
Y546682D01*
X310252Y546742D01*
G02X311790I769J1172D01*
G37*
G36*
G01X325176D02*
X325086Y546682D01*
Y546374D01*
X325508D01*
Y539272D01*
X323306D01*
Y546374D01*
X323728D01*
Y546682D01*
X323638Y546742D01*
G02X325176I769J1172D01*
G37*
G36*
G01X328523D02*
X328433Y546682D01*
Y546374D01*
X328856D01*
Y539272D01*
X326652D01*
Y546374D01*
X327075D01*
Y546682D01*
X326985Y546742D01*
G02X328523I769J1172D01*
G37*
G36*
G01X335215D02*
X335125Y546682D01*
Y546374D01*
X335548D01*
Y539272D01*
X333346D01*
Y546374D01*
X333767D01*
Y546682D01*
X333677Y546742D01*
G02X335215I769J1172D01*
G37*
G36*
G01X338562D02*
X338472Y546682D01*
Y546374D01*
X338894D01*
Y539272D01*
X336692D01*
Y546374D01*
X337114D01*
Y546682D01*
X337024Y546742D01*
G02X338562I769J1172D01*
G37*
G36*
G01X345244Y546743D02*
X345152Y546684D01*
Y546374D01*
X345588D01*
Y539272D01*
X343384D01*
Y546374D01*
X343820D01*
Y546684D01*
X343728Y546743D01*
G02X345244I758J1179D01*
G37*
G36*
G01X348591D02*
X348499Y546684D01*
Y546374D01*
X348934D01*
Y539272D01*
X346732D01*
Y546374D01*
X347167D01*
Y546684D01*
X347075Y546743D01*
G02X348591I758J1179D01*
G37*
G36*
G01X355751Y548602D02*
G03X356449Y548600I350J194D01*
G02X356446Y547234I1223J-686D01*
G03X355748Y547236I-350J-194D01*
G02X355283Y546743I-1222J687D01*
G01X355191Y546684D01*
Y546374D01*
X355626D01*
Y539272D01*
X353424D01*
Y546374D01*
X353859D01*
Y546684D01*
X353767Y546743D01*
G02X355751Y548602I758J1179D01*
G37*
G36*
G01X360315Y547014D02*
G02X362603Y548953I1203J900D01*
G03X363180I289J277D01*
G02X365468Y547014I1085J-1039D01*
G03X365666Y546393I320J-240D01*
G01Y539272D01*
X363464D01*
Y546644D01*
G02X363180Y546875I799J1272D01*
G03X362603I-289J-277D01*
G02X362320Y546644I-1084J1040D01*
G01Y539272D01*
X360116D01*
Y546393D01*
G03X360315Y547014I-121J381D01*
G37*
G36*
G01X415521Y546743D02*
X415429Y546684D01*
Y546374D01*
X415864D01*
Y539272D01*
X413660D01*
Y546374D01*
X414097D01*
Y546684D01*
X414005Y546743D01*
G02X415521I758J1179D01*
G37*
G36*
G01X428907D02*
X428815Y546684D01*
Y546374D01*
X429248D01*
Y539272D01*
X427046D01*
Y546374D01*
X427483D01*
Y546684D01*
X427391Y546743D01*
G02X428907I758J1179D01*
G37*
G36*
G01X435600D02*
X435508Y546684D01*
Y546374D01*
X435942D01*
Y539272D01*
X433738D01*
Y546374D01*
X434176D01*
Y546684D01*
X434084Y546743D01*
G02X435600I758J1179D01*
G37*
G36*
G01X438947D02*
X438855Y546684D01*
Y546374D01*
X439288D01*
Y539272D01*
X437086D01*
Y546374D01*
X437523D01*
Y546684D01*
X437431Y546743D01*
G02X438947I758J1179D01*
G37*
G36*
G01X445638D02*
X445546Y546684D01*
Y546374D01*
X445982D01*
Y539272D01*
X443778D01*
Y546374D01*
X444214D01*
Y546684D01*
X444122Y546743D01*
G02X445638I758J1179D01*
G37*
G36*
G01X770595Y547024D02*
G03X770907Y546374I312J-250D01*
G01X770982D01*
Y539272D01*
X768780D01*
Y546374D01*
X768800D01*
Y546680D01*
X768713Y546740D01*
G02X770595Y547024I787J1160D01*
G37*
G36*
G01X961398Y546742D02*
X961308Y546682D01*
Y546374D01*
X961730D01*
Y539272D01*
X959528D01*
Y546374D01*
X959950D01*
Y546682D01*
X959860Y546742D01*
G02X961398I769J1172D01*
G37*
G36*
G01X974784D02*
X974694Y546682D01*
Y546374D01*
X975116D01*
Y539272D01*
X972914D01*
Y546374D01*
X973336D01*
Y546682D01*
X973246Y546742D01*
G02X974784I769J1172D01*
G37*
G36*
G01X978131D02*
X978041Y546682D01*
Y546374D01*
X978464D01*
Y539272D01*
X976260D01*
Y546374D01*
X976683D01*
Y546682D01*
X976593Y546742D01*
G02X978131I769J1172D01*
G37*
G36*
G01X984823D02*
X984733Y546682D01*
Y546374D01*
X985156D01*
Y539272D01*
X982954D01*
Y546374D01*
X983375D01*
Y546682D01*
X983285Y546742D01*
G02X984823I769J1172D01*
G37*
G36*
G01X988170D02*
X988080Y546682D01*
Y546374D01*
X988502D01*
Y539272D01*
X986300D01*
Y546374D01*
X986722D01*
Y546682D01*
X986632Y546742D01*
G02X988170I769J1172D01*
G37*
G36*
G01X994852Y546743D02*
X994760Y546684D01*
Y546374D01*
X995196D01*
Y539272D01*
X992992D01*
Y546374D01*
X993428D01*
Y546684D01*
X993336Y546743D01*
G02X994852I758J1179D01*
G37*
G36*
G01X998199D02*
X998107Y546684D01*
Y546374D01*
X998542D01*
Y539272D01*
X996340D01*
Y546374D01*
X996775D01*
Y546684D01*
X996683Y546743D01*
G02X998199I758J1179D01*
G37*
G36*
G01X1005359Y548602D02*
G03X1006057Y548600I350J194D01*
G02X1006054Y547234I1223J-686D01*
G03X1005356Y547236I-350J-194D01*
G02X1004891Y546743I-1222J687D01*
G01X1004799Y546684D01*
Y546374D01*
X1005234D01*
Y539272D01*
X1003032D01*
Y546374D01*
X1003467D01*
Y546684D01*
X1003375Y546743D01*
G02X1005359Y548602I758J1179D01*
G37*
G36*
G01X1009923Y547014D02*
G02X1012211Y548953I1203J900D01*
G03X1012788I288J277D01*
G02X1015076Y547014I1085J-1039D01*
G03X1015274Y546393I320J-240D01*
G01Y539272D01*
X1013072D01*
Y546644D01*
G02X1012788Y546875I799J1272D01*
G03X1012211I-288J-277D01*
G02X1011928Y546644I-1084J1040D01*
G01Y539272D01*
X1009724D01*
Y546393D01*
G03X1009923Y547014I-121J381D01*
G37*
G36*
G01X1065129Y546743D02*
X1065037Y546684D01*
Y546374D01*
X1065472D01*
Y539272D01*
X1063268D01*
Y546374D01*
X1063705D01*
Y546684D01*
X1063613Y546743D01*
G02X1065129I758J1179D01*
G37*
G36*
G01X1078515D02*
X1078423Y546684D01*
Y546374D01*
X1078856D01*
Y539272D01*
X1076654D01*
Y546374D01*
X1077091D01*
Y546684D01*
X1076999Y546743D01*
G02X1078515I758J1179D01*
G37*
G36*
G01X1085208D02*
X1085116Y546684D01*
Y546374D01*
X1085550D01*
Y539272D01*
X1083346D01*
Y546374D01*
X1083784D01*
Y546684D01*
X1083692Y546743D01*
G02X1085208I758J1179D01*
G37*
G36*
G01X1088555D02*
X1088463Y546684D01*
Y546374D01*
X1088896D01*
Y539272D01*
X1086694D01*
Y546374D01*
X1087131D01*
Y546684D01*
X1087039Y546743D01*
G02X1088555I758J1179D01*
G37*
G36*
G01X1095246D02*
X1095154Y546684D01*
Y546374D01*
X1095590D01*
Y539272D01*
X1093386D01*
Y546374D01*
X1093822D01*
Y546684D01*
X1093730Y546743D01*
G02X1095246I758J1179D01*
G37*
G36*
G01X1940620Y541958D02*
G02X1938484Y540203I-920J-1058D01*
G03X1937951Y540358I-347J-199D01*
G02X1938516Y542297I-651J1242D01*
G03X1939049Y542142I347J199D01*
G02X1939064Y542150I667J-1233D01*
G03X1939077Y542499I-91J178D01*
G02X1938408Y543537I723J1201D01*
G03X1937830Y543848I-398J-46D01*
G02X1937855Y546340I-630J1252D01*
G03X1938432Y546606I187J354D01*
G02X1940771Y545289I1368J-306D01*
G03Y544711I277J-289D01*
G02X1940642Y542579I-971J-1011D01*
G03X1940620Y541958I241J-319D01*
G37*
G36*
G01X1922965Y544767D02*
G02X1921424Y545028I-965J-1017D01*
G03X1921535Y545683I-164J365D01*
G02X1923076Y545422I965J1017D01*
G03X1922965Y544767I164J-365D01*
G37*
G36*
G01X1453864Y545629D02*
G02X1450791Y544939I-1472J-631D01*
G03X1450287Y545310I-400J-15D01*
G02X1448818Y545799I-365J1354D01*
G03X1448175Y545780I-314J-247D01*
G02X1448126Y547443I-1153J798D01*
G03X1448769Y547462I314J247D01*
G02X1450926Y547642I1153J-798D01*
G03X1451603Y547833I287J279D01*
G02X1454310Y548603I1563J-352D01*
G03X1454892Y548615I285J280D01*
G02X1454936Y546418I1188J-1075D01*
G03X1454354Y546406I-285J-280D01*
G02X1454019Y546125I-1187J1075D01*
G03X1453864Y545629I213J-339D01*
G37*
G36*
G01X1915609Y545971D02*
G02X1914125Y546118I-859J-1108D01*
G03X1914191Y546792I-179J358D01*
G02X1915675Y546645I859J1108D01*
G03X1915609Y545971I179J-358D01*
G37*
G36*
G01X1811291Y544448D02*
G02X1811069Y546068I-1239J655D01*
G03X1811713Y546156I290J275D01*
G02X1811935Y544536I1239J-655D01*
G03X1811291Y544448I-290J-275D01*
G37*
G36*
G01X1278982Y546573D02*
G02X1277957Y545548I336J-1361D01*
G03X1277473Y546032I-389J95D01*
G02X1278498Y547057I-336J1361D01*
G03X1278982Y546573I389J-95D01*
G37*
G36*
G01X1899954Y546114D02*
G02X1898485Y546604I-1104J-864D01*
G03X1898696Y547236I-104J386D01*
G02X1898565Y547436I1103J865D01*
G03X1898010Y547591I-352J-190D01*
G02X1898535Y549464I-710J1209D01*
G03X1899090Y549309I352J190D01*
G02X1900165Y546746I710J-1209D01*
G03X1899954Y546114I104J-386D01*
G37*
G36*
G01X1857125Y548275D02*
G02X1855432Y549365I-1375J-275D01*
G03X1855733Y549833I-91J389D01*
G02X1856137Y551119I1375J275D01*
G03Y551697I-277J289D01*
G02X1856097Y551737I971J1011D01*
G03X1855519I-289J-277D01*
G02X1853146Y553039I-1011J971D01*
G03X1852678Y553526I-389J95D01*
G02X1853762Y554569I-278J1374D01*
G03X1854230Y554082I389J-95D01*
G02X1855519Y553679I278J-1374D01*
G03X1856097I289J277D01*
G02X1858119I1011J-971D01*
G03X1858697I289J277D01*
G02Y551737I1011J-971D01*
G03X1858119I-289J-277D01*
G02X1858079Y551697I-1011J971D01*
G03Y551119I277J-289D01*
G02X1857426Y548743I-971J-1011D01*
G03X1857125Y548275I91J-389D01*
G37*
G36*
G01X1849505Y549465D02*
G02X1848218Y549425I-605J-1265D01*
G03X1848195Y550135I-195J349D01*
G02X1849482Y550175I605J1265D01*
G03X1849505Y549465I195J-349D01*
G37*
G36*
G01X1836978Y550660D02*
G02X1836688Y549207I1022J-959D01*
G03X1836022Y549340I-374J-141D01*
G02X1836312Y550793I-1022J959D01*
G03X1836978Y550660I374J141D01*
G37*
G36*
G01X730541Y549008D02*
G02X728773Y551167I-991J992D01*
G03Y551833I-222J333D01*
G02Y554167I777J1167D01*
G03Y554833I-222J333D01*
G02X730541Y556992I777J1167D01*
G03X731107I283J282D01*
G02X732875Y554833I991J-992D01*
G03Y554167I222J-333D01*
G02Y551833I-777J-1167D01*
G03Y551167I222J-333D01*
G02X731107Y549008I-777J-1167D01*
G03X730541I-283J-282D01*
G37*
G36*
G01X1816995Y551606D02*
G02X1815565I-715J-1206D01*
G03Y552294I-204J344D01*
G02X1816995I715J1206D01*
G03Y551606I204J-344D01*
G37*
G36*
G01X1300777Y553567D02*
G02X1299223I-777J-1167D01*
G03Y554233I-222J333D01*
G02Y556567I777J1167D01*
G03Y557233I-222J333D01*
G02X1300777I777J1167D01*
G03Y556567I222J-333D01*
G02Y554233I-777J-1167D01*
G03Y553567I222J-333D01*
G37*
G36*
G01X1318667Y551623D02*
G02X1316723Y553567I-1167J777D01*
G03Y554233I-222J333D01*
G02Y556567I777J1167D01*
G03Y557233I-222J333D01*
G02X1318667Y559177I777J1167D01*
G03X1319333I333J222D01*
G02X1321667I1167J-777D01*
G03X1322333I333J222D01*
G02X1324277Y557233I1167J-777D01*
G03Y556567I222J-333D01*
G02Y554233I-777J-1167D01*
G03Y553567I222J-333D01*
G02X1322333Y551623I-777J-1167D01*
G03X1321667I-333J-222D01*
G02X1319333I-1167J777D01*
G03X1318667I-333J-222D01*
G37*
G36*
G01X658306Y551785D02*
G02Y553215I-1206J715D01*
G03X658994I344J204D01*
G02Y551785I1206J-715D01*
G03X658306I-344J-204D01*
G37*
G36*
G01X1755319Y553024D02*
G02X1754626Y554754I-1319J476D01*
G03X1755181Y554976I179J358D01*
G02X1757667Y555277I1319J-476D01*
G03X1758333I333J222D01*
G02Y553723I1167J-777D01*
G03X1757667I-333J-222D01*
G02X1755874Y553246I-1167J777D01*
G03X1755319Y553024I-179J-358D01*
G37*
G36*
G01X64667Y553723D02*
G02X62723Y555667I-1167J777D01*
G03Y556333I-222J333D01*
G02X64667Y558277I777J1167D01*
G03X65333I333J222D01*
G02X67667I1167J-777D01*
G03X68333I333J222D01*
G02X70667I1167J-777D01*
G03X71333I333J222D01*
G02X73667I1167J-777D01*
G03X74333I333J222D01*
G02X76667I1167J-777D01*
G03X77333I333J222D01*
G02X79667I1167J-777D01*
G03X80333I333J222D01*
G02X82277Y556333I1167J-777D01*
G03Y555667I222J-333D01*
G02X80333Y553723I-777J-1167D01*
G03X79667I-333J-222D01*
G02X77333I-1167J777D01*
G03X76667I-333J-222D01*
G02X74333I-1167J777D01*
G03X73667I-333J-222D01*
G02X71333I-1167J777D01*
G03X70667I-333J-222D01*
G02X68333I-1167J777D01*
G03X67667I-333J-222D01*
G02X65333I-1167J777D01*
G03X64667I-333J-222D01*
G37*
G36*
G01X1913006Y556655D02*
G02X1912416Y555278I794J-1155D01*
G03X1911794Y555545I-395J-63D01*
G02X1912384Y556922I-794J1155D01*
G03X1913006Y556655I395J63D01*
G37*
G36*
G01X369006Y556601D02*
G02X368922Y554910I1074J-901D01*
G03X368285Y554941I-330J-226D01*
G02X366236Y554834I-1074J901D01*
G03X365665Y554819I-278J-287D01*
G02X363284Y555058I-1100J1023D01*
G03X362601I-341J-208D01*
G02X360393Y557024I-1281J784D01*
G01X360470Y557084D01*
Y557382D01*
X360116D01*
Y564484D01*
X362320D01*
Y557382D01*
X362170D01*
Y557084D01*
X362247Y557024D01*
G02X362601Y556626I-928J-1181D01*
G03X363284I341J208D01*
G02X363638Y557024I1282J-783D01*
G01X363715Y557084D01*
Y557382D01*
X363464D01*
Y564484D01*
X365666D01*
Y557382D01*
X365415D01*
Y557084D01*
X365492Y557024D01*
G02X365665Y556865I-927J-1182D01*
G03X366236Y556850I293J272D01*
G02X368369Y556632I975J-1008D01*
G03X369006Y556601I330J226D01*
G37*
G36*
G01X1012209Y555058D02*
G02X1010001Y557024I-1281J784D01*
G01X1010078Y557084D01*
Y557382D01*
X1009724D01*
Y564484D01*
X1011928D01*
Y557382D01*
X1011778D01*
Y557084D01*
X1011855Y557024D01*
G02X1012209Y556626I-928J-1181D01*
G03X1012892I341J208D01*
G02X1013246Y557024I1282J-783D01*
G01X1013323Y557084D01*
Y557382D01*
X1013072D01*
Y564484D01*
X1015274D01*
Y557382D01*
X1015023D01*
Y557084D01*
X1015100Y557024D01*
G02X1015273Y556865I-927J-1182D01*
G03X1015844Y556850I293J272D01*
G02X1017990Y556613I975J-1008D01*
G03X1018651Y556604I334J220D01*
G02X1018629Y555029I1149J-804D01*
G03X1017968Y555038I-334J-220D01*
G02X1015844Y554834I-1149J804D01*
G03X1015273Y554819I-278J-287D01*
G02X1012892Y555058I-1100J1023D01*
G03X1012209I-342J-208D01*
G37*
G36*
G01X397260Y557014D02*
X397350Y557074D01*
Y557382D01*
X396928D01*
Y564484D01*
X399130D01*
Y557382D01*
X398708D01*
Y557074D01*
X398798Y557014D01*
G02X397260I-769J-1172D01*
G37*
G36*
G01X407300D02*
X407390Y557074D01*
Y557382D01*
X406968D01*
Y564484D01*
X409170D01*
Y557382D01*
X408748D01*
Y557074D01*
X408838Y557014D01*
G02X407300I-769J-1172D01*
G37*
G36*
G01X424032D02*
X424122Y557074D01*
Y557382D01*
X423700D01*
Y564484D01*
X425902D01*
Y557382D01*
X425480D01*
Y557074D01*
X425570Y557014D01*
G02X424032I-769J-1172D01*
G37*
G36*
G01X430725D02*
X430815Y557074D01*
Y557382D01*
X430392D01*
Y564484D01*
X432596D01*
Y557382D01*
X432173D01*
Y557074D01*
X432263Y557014D01*
G02X430725I-769J-1172D01*
G37*
G36*
G01X1046868D02*
X1046958Y557074D01*
Y557382D01*
X1046536D01*
Y564484D01*
X1048738D01*
Y557382D01*
X1048316D01*
Y557074D01*
X1048406Y557014D01*
G02X1046868I-769J-1172D01*
G37*
G36*
G01X1056908D02*
X1056998Y557074D01*
Y557382D01*
X1056576D01*
Y564484D01*
X1058778D01*
Y557382D01*
X1058356D01*
Y557074D01*
X1058446Y557014D01*
G02X1056908I-769J-1172D01*
G37*
G36*
G01X1073640D02*
X1073730Y557074D01*
Y557382D01*
X1073308D01*
Y564484D01*
X1075510D01*
Y557382D01*
X1075088D01*
Y557074D01*
X1075178Y557014D01*
G02X1073640I-769J-1172D01*
G37*
G36*
G01X1080333D02*
X1080423Y557074D01*
Y557382D01*
X1080000D01*
Y564484D01*
X1082204D01*
Y557382D01*
X1081781D01*
Y557074D01*
X1081871Y557014D01*
G02X1080333I-769J-1172D01*
G37*
G36*
G01X306886Y557016D02*
X306974Y557076D01*
Y557382D01*
X306574D01*
Y564484D01*
X308776D01*
Y557382D01*
X308376D01*
Y557076D01*
X308464Y557016D01*
G02X306886I-789J-1159D01*
G37*
G36*
G01X313579D02*
X313667Y557076D01*
Y557382D01*
X313266D01*
Y564484D01*
X315470D01*
Y557382D01*
X315069D01*
Y557076D01*
X315157Y557016D01*
G02X313579I-789J-1159D01*
G37*
G36*
G01X320272D02*
X320360Y557076D01*
Y557382D01*
X319960D01*
Y564484D01*
X322162D01*
Y557382D01*
X321762D01*
Y557076D01*
X321850Y557016D01*
G02X320272I-789J-1159D01*
G37*
G36*
G01X323618D02*
X323706Y557076D01*
Y557382D01*
X323306D01*
Y564484D01*
X325508D01*
Y557382D01*
X325108D01*
Y557076D01*
X325196Y557016D01*
G02X323618I-789J-1159D01*
G37*
G36*
G01X330311D02*
X330399Y557076D01*
Y557382D01*
X329998D01*
Y564484D01*
X332202D01*
Y557382D01*
X331801D01*
Y557076D01*
X331889Y557016D01*
G02X330311I-789J-1159D01*
G37*
G36*
G01X333658D02*
X333746Y557076D01*
Y557382D01*
X333346D01*
Y564484D01*
X335548D01*
Y557382D01*
X335148D01*
Y557076D01*
X335236Y557016D01*
G02X333658I-789J-1159D01*
G37*
G36*
G01X340351D02*
X340439Y557076D01*
Y557382D01*
X340038D01*
Y564484D01*
X342242D01*
Y557382D01*
X341841D01*
Y557076D01*
X341929Y557016D01*
G02X340351I-789J-1159D01*
G37*
G36*
G01X343697D02*
X343785Y557076D01*
Y557382D01*
X343384D01*
Y564484D01*
X345588D01*
Y557382D01*
X345187D01*
Y557076D01*
X345275Y557016D01*
G02X343697I-789J-1159D01*
G37*
G36*
G01X350390D02*
X350478Y557076D01*
Y557382D01*
X350078D01*
Y564484D01*
X352280D01*
Y557382D01*
X351880D01*
Y557076D01*
X351968Y557016D01*
G02X350390I-789J-1159D01*
G37*
G36*
G01X353737D02*
X353825Y557076D01*
Y557382D01*
X353424D01*
Y564484D01*
X355626D01*
Y557382D01*
X355227D01*
Y557076D01*
X355315Y557016D01*
G02X353737I-789J-1159D01*
G37*
G36*
G01X403934D02*
X404022Y557076D01*
Y557382D01*
X403620D01*
Y564484D01*
X405824D01*
Y557382D01*
X405424D01*
Y557076D01*
X405512Y557016D01*
G02X403934I-789J-1159D01*
G37*
G36*
G01X413974D02*
X414062Y557076D01*
Y557382D01*
X413660D01*
Y564484D01*
X415864D01*
Y557382D01*
X415464D01*
Y557076D01*
X415552Y557016D01*
G02X413974I-789J-1159D01*
G37*
G36*
G01X420667D02*
X420755Y557076D01*
Y557382D01*
X420354D01*
Y564484D01*
X422556D01*
Y557382D01*
X422157D01*
Y557076D01*
X422245Y557016D01*
G02X420667I-789J-1159D01*
G37*
G36*
G01X956494D02*
X956582Y557076D01*
Y557382D01*
X956182D01*
Y564484D01*
X958384D01*
Y557382D01*
X957984D01*
Y557076D01*
X958072Y557016D01*
G02X956494I-789J-1159D01*
G37*
G36*
G01X963187D02*
X963275Y557076D01*
Y557382D01*
X962874D01*
Y564484D01*
X965078D01*
Y557382D01*
X964677D01*
Y557076D01*
X964765Y557016D01*
G02X963187I-789J-1159D01*
G37*
G36*
G01X969880D02*
X969968Y557076D01*
Y557382D01*
X969568D01*
Y564484D01*
X971770D01*
Y557382D01*
X971370D01*
Y557076D01*
X971458Y557016D01*
G02X969880I-789J-1159D01*
G37*
G36*
G01X973226D02*
X973314Y557076D01*
Y557382D01*
X972914D01*
Y564484D01*
X975116D01*
Y557382D01*
X974716D01*
Y557076D01*
X974804Y557016D01*
G02X973226I-789J-1159D01*
G37*
G36*
G01X979919D02*
X980007Y557076D01*
Y557382D01*
X979606D01*
Y564484D01*
X981810D01*
Y557382D01*
X981409D01*
Y557076D01*
X981497Y557016D01*
G02X979919I-789J-1159D01*
G37*
G36*
G01X983266D02*
X983354Y557076D01*
Y557382D01*
X982954D01*
Y564484D01*
X985156D01*
Y557382D01*
X984756D01*
Y557076D01*
X984844Y557016D01*
G02X983266I-789J-1159D01*
G37*
G36*
G01X989959D02*
X990047Y557076D01*
Y557382D01*
X989646D01*
Y564484D01*
X991850D01*
Y557382D01*
X991449D01*
Y557076D01*
X991537Y557016D01*
G02X989959I-789J-1159D01*
G37*
G36*
G01X993305D02*
X993393Y557076D01*
Y557382D01*
X992992D01*
Y564484D01*
X995196D01*
Y557382D01*
X994795D01*
Y557076D01*
X994883Y557016D01*
G02X993305I-789J-1159D01*
G37*
G36*
G01X999998D02*
X1000086Y557076D01*
Y557382D01*
X999686D01*
Y564484D01*
X1001888D01*
Y557382D01*
X1001488D01*
Y557076D01*
X1001576Y557016D01*
G02X999998I-789J-1159D01*
G37*
G36*
G01X1003345D02*
X1003433Y557076D01*
Y557382D01*
X1003032D01*
Y564484D01*
X1005234D01*
Y557382D01*
X1004835D01*
Y557076D01*
X1004923Y557016D01*
G02X1003345I-789J-1159D01*
G37*
G36*
G01X1053542D02*
X1053630Y557076D01*
Y557382D01*
X1053228D01*
Y564484D01*
X1055432D01*
Y557382D01*
X1055032D01*
Y557076D01*
X1055120Y557016D01*
G02X1053542I-789J-1159D01*
G37*
G36*
G01X1063582D02*
X1063670Y557076D01*
Y557382D01*
X1063268D01*
Y564484D01*
X1065472D01*
Y557382D01*
X1065072D01*
Y557076D01*
X1065160Y557016D01*
G02X1063582I-789J-1159D01*
G37*
G36*
G01X1070275D02*
X1070363Y557076D01*
Y557382D01*
X1069962D01*
Y564484D01*
X1072164D01*
Y557382D01*
X1071765D01*
Y557076D01*
X1071853Y557016D01*
G02X1070275I-789J-1159D01*
G37*
G36*
G01X437396D02*
X437483Y557076D01*
Y557382D01*
X437086D01*
Y564484D01*
X439288D01*
Y557382D01*
X438891D01*
Y557076D01*
X438978Y557016D01*
G02X437396I-791J-1157D01*
G37*
G36*
G01X444089D02*
X444176Y557076D01*
Y557382D01*
X443778D01*
Y564484D01*
X445982D01*
Y557382D01*
X445584D01*
Y557076D01*
X445671Y557016D01*
G02X444089I-791J-1157D01*
G37*
G36*
G01X1087004D02*
X1087091Y557076D01*
Y557382D01*
X1086694D01*
Y564484D01*
X1088896D01*
Y557382D01*
X1088499D01*
Y557076D01*
X1088586Y557016D01*
G02X1087004I-791J-1157D01*
G37*
G36*
G01X1093697D02*
X1093784Y557076D01*
Y557382D01*
X1093386D01*
Y564484D01*
X1095590D01*
Y557382D01*
X1095192D01*
Y557076D01*
X1095279Y557016D01*
G02X1093697I-791J-1157D01*
G37*
G36*
G01X1536281Y560614D02*
G02X1533713Y558729I-1385J-805D01*
G03X1533131Y558740I-296J-269D01*
G02X1530906Y558677I-1145J1120D01*
G03X1530366I-270J-295D01*
G02X1528206I-1080J1183D01*
G03X1527666I-270J-295D01*
G02X1525021Y560201I-1080J1183D01*
G03X1524612Y560686I-391J85D01*
G02X1525595Y563490I-74J1600D01*
G03X1526144Y563510I264J301D01*
G02X1528365Y563569I1141J-1124D01*
G03X1528905I270J295D01*
G02X1531065I1080J-1183D01*
G03X1531605I270J295D01*
G02X1533765I1080J-1183D01*
G03X1534305I270J295D01*
G02X1536151Y563793I1080J-1183D01*
G03X1536740Y564098I192J351D01*
G02X1538930Y565399I1591J-185D01*
G03X1539480Y565787I150J371D01*
G02X1542280Y566920I1600J72D01*
G03X1542880I300J265D01*
G02X1543019Y567059I1200J-1061D01*
G03Y567659I-265J300D01*
G02X1545217Y569988I1062J1200D01*
G03X1545737Y569947I284J282D01*
G02X1547621Y569956I948J-1291D01*
G03X1548140Y570001I233J325D01*
G02X1550532Y567875I1145J-1120D01*
G03X1550560Y567342I311J-251D01*
G02X1550607Y565129I-1135J-1131D01*
G03X1550601Y564596I295J-270D01*
G02X1548459Y562241I-1206J-1055D01*
G03X1547940Y562196I-233J-325D01*
G02X1545716Y562132I-1145J1120D01*
G03X1545151Y562106I-269J-296D01*
G02X1542887Y562002I-1184J1079D01*
G03X1542347I-270J-295D01*
G02X1539752Y562663I-1080J1183D01*
G03X1539426Y562744I-189J-65D01*
G02X1539284Y562625I-1098J1166D01*
G03X1539290Y562300I119J-160D01*
G02X1536784Y561034I-905J-1322D01*
G03X1536451Y561190I-200J7D01*
G02X1536379Y561129I-1071J1191D01*
G03X1536281Y560614I248J-314D01*
G37*
G36*
G01X1377086Y560726D02*
G02X1374974Y560635I-1016J-966D01*
G03X1374935Y561176I-313J249D01*
G02X1377398Y562710I1026J1097D01*
G03X1378051Y562532I383J117D01*
G02X1377603Y561386I949J-1032D01*
G03X1377234Y561476I-199J-16D01*
G02X1377078Y561269I-1273J797D01*
G03X1377086Y560726I298J-267D01*
G37*
G36*
G01X1286743Y560598D02*
G02X1286157Y562180I-1343J402D01*
G03X1286757Y562402I217J336D01*
G02X1288885Y563162I1343J-402D01*
G03X1289506Y563450I224J332D01*
G02X1290115Y562138I1394J-150D01*
G03X1289494Y561850I-224J-332D01*
G02X1287343Y560820I-1394J150D01*
G03X1286743Y560598I-217J-336D01*
G37*
G36*
G01X64667Y560723D02*
G02Y562277I-1167J777D01*
G03X65333I333J222D01*
G02X67667I1167J-777D01*
G03X68333I333J222D01*
G02X70667I1167J-777D01*
G03X71333I333J222D01*
G02X73667I1167J-777D01*
G03X74333I333J222D01*
G02X76667I1167J-777D01*
G03X77333I333J222D01*
G02X79667I1167J-777D01*
G03X80333I333J222D01*
G02Y560723I1167J-777D01*
G03X79667I-333J-222D01*
G02X77333I-1167J777D01*
G03X76667I-333J-222D01*
G02X74333I-1167J777D01*
G03X73667I-333J-222D01*
G02X71333I-1167J777D01*
G03X70667I-333J-222D01*
G02X68333I-1167J777D01*
G03X67667I-333J-222D01*
G02X65333I-1167J777D01*
G03X64667I-333J-222D01*
G37*
G36*
G01X1744116Y562666D02*
G02X1742395Y562912I-1016J-966D01*
G03X1742484Y563534I-201J346D01*
G02X1742513Y565496I1016J966D01*
G03X1742447Y566118I-281J285D01*
G02X1742199Y568282I753J1183D01*
G03X1742155Y568881I-285J280D01*
G02X1744001Y569018I845J1119D01*
G03X1744045Y568419I285J-280D01*
G02X1744187Y566304I-845J-1119D01*
G03X1744253Y565682I281J-285D01*
G02X1744205Y563288I-753J-1182D01*
G03X1744116Y562666I201J-346D01*
G37*
G36*
G01X1934521Y563300D02*
G02X1933278Y562368I79J-1400D01*
G03X1932879Y562900I-377J133D01*
G02X1934122Y563832I-79J1400D01*
G03X1934521Y563300I377J-133D01*
G37*
G36*
G01X1417391Y563595D02*
G02X1417219Y561871I1011J-971D01*
G03X1416593Y561933I-337J-215D01*
G02X1416765Y563657I-1011J971D01*
G03X1417391Y563595I337J215D01*
G37*
G36*
G01X1324551Y564312D02*
G02X1322613Y562358I-778J-1167D01*
G03X1321998Y562415I-331J-224D01*
G02X1319833Y562623I-998J985D01*
G03X1319167I-333J-222D01*
G02X1316833I-1167J777D01*
G03X1316167I-333J-222D01*
G02X1313833I-1167J777D01*
G03X1313167I-333J-222D01*
G02X1310833I-1167J777D01*
G03X1310167I-333J-222D01*
G02X1307833I-1167J777D01*
G03X1307167I-333J-222D01*
G02X1304833I-1167J777D01*
G03X1304167I-333J-222D01*
G02X1301990Y564373I-1167J778D01*
G03Y564927I-288J277D01*
G02X1302223Y567067I1010J973D01*
G03Y567733I-222J333D01*
G02X1301990Y569873I777J1167D01*
G03Y570427I-288J277D01*
G02X1304167Y572177I1010J972D01*
G03X1304833I333J222D01*
G02X1307167I1167J-777D01*
G03X1307833I333J222D01*
G02X1310167I1167J-777D01*
G03X1310833I333J222D01*
G02X1313167I1167J-777D01*
G03X1313833I333J222D01*
G02X1316167I1167J-777D01*
G03X1316833I333J222D01*
G02X1319167I1167J-777D01*
G03X1319833I333J222D01*
G02X1322167I1167J-777D01*
G03X1322833I333J222D01*
G02X1325010Y570427I1167J-778D01*
G03Y569873I288J-277D01*
G02X1324809Y567755I-1010J-973D01*
G03X1324758Y567143I230J-327D01*
G02X1324551Y564978I-984J-998D01*
G03Y564312I222J-333D01*
G37*
G36*
G01X645967Y562523D02*
G02Y564077I-1167J777D01*
G03X646633I333J222D01*
G02X648967I1167J-777D01*
G03X649633I333J222D01*
G02X651967I1167J-777D01*
G03X652633I333J222D01*
G02Y562523I1167J-777D01*
G03X651967I-333J-222D01*
G02X649633I-1167J777D01*
G03X648967I-333J-222D01*
G02X646633I-1167J777D01*
G03X645967I-333J-222D01*
G37*
G36*
G01X1781547Y566291D02*
G02X1780064Y566043I-546J-1291D01*
G03X1779953Y566709I-267J298D01*
G02X1779579Y569057I547J1291D01*
G03Y569661I-262J302D01*
G02X1781421I921J1057D01*
G03Y569057I262J-302D01*
G02X1781436Y566957I-921J-1057D01*
G03X1781547Y566291I267J-298D01*
G37*
G36*
G01X1291833Y574879D02*
G02X1290274Y576083I-4430J-4124D01*
G03X1290847Y576550I190J352D01*
G02X1290798Y577116I1343J401D01*
G03X1290376Y577563I-397J48D01*
G02X1291684Y578798I-84J1399D01*
G03X1292106Y578351I397J-48D01*
G02X1292140Y575551I84J-1399D01*
G03X1291833Y574879I-14J-400D01*
G37*
G36*
G01X362540Y566100D02*
G02Y567528I-1322J714D01*
G03X363243I352J190D01*
G02X365658Y567844I1322J-714D01*
G03X366225Y567829I291J275D01*
G02Y565799I967J-1015D01*
G03X365658Y565784I-276J-290D01*
G02X363243Y566100I-1093J1030D01*
G03X362540I-351J-190D01*
G37*
G36*
G01X1012148D02*
G02Y567528I-1322J714D01*
G03X1012851I352J190D01*
G02X1015266Y567844I1322J-714D01*
G03X1015833Y567829I291J275D01*
G02Y565799I967J-1015D01*
G03X1015266Y565784I-276J-290D01*
G02X1012851Y566100I-1093J1030D01*
G03X1012148I-352J-190D01*
G37*
G36*
G01X309183Y566016D02*
G02X309148Y567525I-1199J727D01*
G03X309822Y567541I332J223D01*
G02X309857Y566032I1199J-727D01*
G03X309183Y566016I-332J-223D01*
G37*
G36*
G01X958791D02*
G02X958756Y567525I-1199J727D01*
G03X959430Y567541I332J223D01*
G02X959465Y566032I1199J-727D01*
G03X958791Y566016I-332J-223D01*
G37*
G36*
G01X1936343Y569287D02*
G02X1935512Y567803I557J-1287D01*
G03X1934957Y568113I-396J-57D01*
G02X1935788Y569597I-557J1287D01*
G03X1936343Y569287I396J57D01*
G37*
G36*
G01X1726471Y569981D02*
G02X1724917I-777J-1167D01*
G03Y570647I-222J333D01*
G02X1726471I777J1167D01*
G03Y569981I222J-333D01*
G37*
G36*
G01X1467630Y570975D02*
G02X1467374Y569429I1019J-963D01*
G03X1466719Y569537I-364J-166D01*
G02X1466975Y571083I-1019J963D01*
G03X1467630Y570975I364J166D01*
G37*
G36*
G01X1808834Y571292D02*
G02X1807280I-777J-1167D01*
G03Y571958I-222J333D01*
G02X1808834I777J1167D01*
G03Y571292I222J-333D01*
G37*
G36*
G01X1418208Y569756D02*
G02X1416196Y569715I-1026J955D01*
G03X1415654Y569735I-282J-284D01*
G02X1413758Y571797I-910J1066D01*
G03X1413757Y572366I-282J284D01*
G02X1415676Y574409I986J996D01*
G03X1416233Y574433I266J299D01*
G02X1416588Y574705I1019J-963D01*
G03X1416596Y575405I-190J352D01*
G02X1416340Y575591I691J1220D01*
G03X1415799I-270J-295D01*
G02Y577657I-948J1033D01*
G03X1416340I271J295D01*
G02X1418229Y577663I948J-1033D01*
G03X1418789Y577685I269J296D01*
G02X1420825Y577689I1020J-962D01*
G03X1421424Y577711I290J276D01*
G02X1423286Y575656I1085J-888D01*
G03Y574990I222J-333D01*
G02Y572656I-777J-1167D01*
G03Y571990I222J-333D01*
G02X1421493Y569857I-777J-1167D01*
G03X1420894Y569835I-290J-276D01*
G02X1418791Y569759I-1085J888D01*
G03X1418208Y569756I-290J-276D01*
G37*
G36*
G01X362540Y574028D02*
G02Y575456I-1322J714D01*
G03X363243I352J190D01*
G02X365658Y575772I1322J-714D01*
G03X366225Y575757I291J275D01*
G02Y573727I967J-1015D01*
G03X365658Y573712I-276J-290D01*
G02X363243Y574028I-1093J1030D01*
G03X362540I-351J-190D01*
G37*
G36*
G01X1012148D02*
G02Y575456I-1322J714D01*
G03X1012851I352J190D01*
G02X1015266Y575772I1322J-714D01*
G03X1015833Y575757I291J275D01*
G02Y573727I967J-1015D01*
G03X1015266Y573712I-276J-290D01*
G02X1012851Y574028I-1093J1030D01*
G03X1012148I-352J-190D01*
G37*
G36*
G01X1764596Y575913D02*
G02X1763899Y574647I704J-1213D01*
G03X1763299Y574978I-400J-15D01*
G02X1763996Y576244I-704J1213D01*
G03X1764596Y575913I400J15D01*
G37*
G36*
G01X1386444Y573872D02*
G02X1384021Y574167I-1128J833D01*
G03X1383396Y574322I-370J-153D01*
G02X1383795Y575938I-896J1078D01*
G03X1384420Y575783I370J153D01*
G02X1386266Y575736I896J-1078D01*
G03X1386858Y575793I270J295D01*
G02X1387036Y573929I1128J-833D01*
G03X1386444Y573872I-270J-295D01*
G37*
G36*
G01X72667Y574223D02*
G02X70723Y576167I-1167J777D01*
G03Y576833I-222J333D01*
G02X72667Y578777I777J1167D01*
G03X73333I333J222D01*
G02X75277Y576833I1167J-777D01*
G03Y576167I222J-333D01*
G02X73333Y574223I-777J-1167D01*
G03X72667I-333J-222D01*
G37*
G36*
G01X79667D02*
G02X77723Y576167I-1167J777D01*
G03Y576833I-222J333D01*
G02X79667Y578777I777J1167D01*
G03X80333I333J222D01*
G02X82277Y576833I1167J-777D01*
G03Y576167I222J-333D01*
G02X80333Y574223I-777J-1167D01*
G03X79667I-333J-222D01*
G37*
G36*
G01X1304167Y575223D02*
G02X1302223Y577167I-1167J777D01*
G03Y577833I-222J333D01*
G02X1304167Y579777I777J1167D01*
G03X1304833I333J222D01*
G02X1306777Y577833I1167J-777D01*
G03Y577167I222J-333D01*
G02X1304833Y575223I-777J-1167D01*
G03X1304167I-333J-222D01*
G37*
G36*
G01X1935503Y577183D02*
G02X1935270Y578606I-1303J517D01*
G03X1935947Y578717I305J259D01*
G02X1936180Y577294I1303J-517D01*
G03X1935503Y577183I-305J-259D01*
G37*
G36*
G01X120987Y584824D02*
G03X121299Y584174I312J-250D01*
G01X121374D01*
Y577072D01*
X119172D01*
Y584174D01*
X119192D01*
Y584480D01*
X119105Y584540D01*
G02X120987Y584824I787J1160D01*
G37*
G36*
G01X311790Y584542D02*
X311700Y584482D01*
Y584174D01*
X312122D01*
Y577072D01*
X309920D01*
Y584174D01*
X310342D01*
Y584482D01*
X310252Y584542D01*
G02X311790I769J1172D01*
G37*
G36*
G01X325176D02*
X325086Y584482D01*
Y584174D01*
X325508D01*
Y577072D01*
X323306D01*
Y584174D01*
X323728D01*
Y584482D01*
X323638Y584542D01*
G02X325176I769J1172D01*
G37*
G36*
G01X328523D02*
X328433Y584482D01*
Y584174D01*
X328856D01*
Y577072D01*
X326652D01*
Y584174D01*
X327075D01*
Y584482D01*
X326985Y584542D01*
G02X328523I769J1172D01*
G37*
G36*
G01X335215D02*
X335125Y584482D01*
Y584174D01*
X335548D01*
Y577072D01*
X333346D01*
Y584174D01*
X333767D01*
Y584482D01*
X333677Y584542D01*
G02X335215I769J1172D01*
G37*
G36*
G01X338562D02*
X338472Y584482D01*
Y584174D01*
X338894D01*
Y577072D01*
X336692D01*
Y584174D01*
X337114D01*
Y584482D01*
X337024Y584542D01*
G02X338562I769J1172D01*
G37*
G36*
G01X345244Y584543D02*
X345152Y584484D01*
Y584174D01*
X345588D01*
Y577072D01*
X343384D01*
Y584174D01*
X343820D01*
Y584484D01*
X343728Y584543D01*
G02X345244I758J1179D01*
G37*
G36*
G01X348591D02*
X348499Y584484D01*
Y584174D01*
X348934D01*
Y577072D01*
X346732D01*
Y584174D01*
X347167D01*
Y584484D01*
X347075Y584543D01*
G02X348591I758J1179D01*
G37*
G36*
G01X355501Y586729D02*
G03X356056Y586727I279J287D01*
G02X356049Y584707I969J-1013D01*
G03X355494Y584709I-279J-287D01*
G02X355283Y584543I-968J1014D01*
G01X355191Y584484D01*
Y584174D01*
X355626D01*
Y577072D01*
X353424D01*
Y584174D01*
X353859D01*
Y584484D01*
X353767Y584543D01*
G02X355501Y586729I758J1179D01*
G37*
G36*
G01X360315Y584814D02*
G02X362603Y586753I1203J900D01*
G03X363180I289J277D01*
G02X365246Y586852I1085J-1039D01*
G03X365814Y586898I261J303D01*
G02X366032Y584891I1076J-898D01*
G03X365468Y584814I-244J-317D01*
G02X365192Y584532I-1202J901D01*
G01X365315Y584174D01*
X365666D01*
Y577072D01*
X363464D01*
Y584444D01*
G02X363180Y584675I799J1272D01*
G03X362603I-289J-277D01*
G02X362320Y584444I-1084J1040D01*
G01Y577072D01*
X360116D01*
Y584193D01*
G03X360315Y584814I-121J381D01*
G37*
G36*
G01X415521Y584543D02*
X415429Y584484D01*
Y584174D01*
X415864D01*
Y577072D01*
X413660D01*
Y584174D01*
X414097D01*
Y584484D01*
X414005Y584543D01*
G02X415521I758J1179D01*
G37*
G36*
G01X428907D02*
X428815Y584484D01*
Y584174D01*
X429248D01*
Y577072D01*
X427046D01*
Y584174D01*
X427483D01*
Y584484D01*
X427391Y584543D01*
G02X428907I758J1179D01*
G37*
G36*
G01X435600D02*
X435508Y584484D01*
Y584174D01*
X435942D01*
Y577072D01*
X433738D01*
Y584174D01*
X434176D01*
Y584484D01*
X434084Y584543D01*
G02X435600I758J1179D01*
G37*
G36*
G01X438947D02*
X438855Y584484D01*
Y584174D01*
X439288D01*
Y577072D01*
X437086D01*
Y584174D01*
X437523D01*
Y584484D01*
X437431Y584543D01*
G02X438947I758J1179D01*
G37*
G36*
G01X445638D02*
X445546Y584484D01*
Y584174D01*
X445982D01*
Y577072D01*
X443778D01*
Y584174D01*
X444214D01*
Y584484D01*
X444122Y584543D01*
G02X445638I758J1179D01*
G37*
G36*
G01X770595Y584824D02*
G03X770907Y584174I312J-250D01*
G01X770982D01*
Y577072D01*
X768780D01*
Y584174D01*
X768800D01*
Y584480D01*
X768713Y584540D01*
G02X770595Y584824I787J1160D01*
G37*
G36*
G01X961398Y584542D02*
X961308Y584482D01*
Y584174D01*
X961730D01*
Y577072D01*
X959528D01*
Y584174D01*
X959950D01*
Y584482D01*
X959860Y584542D01*
G02X961398I769J1172D01*
G37*
G36*
G01X974784D02*
X974694Y584482D01*
Y584174D01*
X975116D01*
Y577072D01*
X972914D01*
Y584174D01*
X973336D01*
Y584482D01*
X973246Y584542D01*
G02X974784I769J1172D01*
G37*
G36*
G01X978131D02*
X978041Y584482D01*
Y584174D01*
X978464D01*
Y577072D01*
X976260D01*
Y584174D01*
X976683D01*
Y584482D01*
X976593Y584542D01*
G02X978131I769J1172D01*
G37*
G36*
G01X984823D02*
X984733Y584482D01*
Y584174D01*
X985156D01*
Y577072D01*
X982954D01*
Y584174D01*
X983375D01*
Y584482D01*
X983285Y584542D01*
G02X984823I769J1172D01*
G37*
G36*
G01X988170D02*
X988080Y584482D01*
Y584174D01*
X988502D01*
Y577072D01*
X986300D01*
Y584174D01*
X986722D01*
Y584482D01*
X986632Y584542D01*
G02X988170I769J1172D01*
G37*
G36*
G01X994852Y584543D02*
X994760Y584484D01*
Y584174D01*
X995196D01*
Y577072D01*
X992992D01*
Y584174D01*
X993428D01*
Y584484D01*
X993336Y584543D01*
G02X994852I758J1179D01*
G37*
G36*
G01X998199D02*
X998107Y584484D01*
Y584174D01*
X998542D01*
Y577072D01*
X996340D01*
Y584174D01*
X996775D01*
Y584484D01*
X996683Y584543D01*
G02X998199I758J1179D01*
G37*
G36*
G01X1005109Y586729D02*
G03X1005664Y586727I279J287D01*
G02X1005657Y584707I969J-1013D01*
G03X1005102Y584709I-279J-287D01*
G02X1004891Y584543I-968J1014D01*
G01X1004799Y584484D01*
Y584174D01*
X1005234D01*
Y577072D01*
X1003032D01*
Y584174D01*
X1003467D01*
Y584484D01*
X1003375Y584543D01*
G02X1005109Y586729I758J1179D01*
G37*
G36*
G01X1009923Y584814D02*
G02X1012211Y586753I1203J900D01*
G03X1012788I288J277D01*
G02X1015076Y584814I1085J-1039D01*
G03X1015274Y584193I320J-240D01*
G01Y577072D01*
X1013072D01*
Y584444D01*
G02X1012788Y584675I799J1272D01*
G03X1012211I-288J-277D01*
G02X1011928Y584444I-1084J1040D01*
G01Y577072D01*
X1009724D01*
Y584193D01*
G03X1009923Y584814I-121J381D01*
G37*
G36*
G01X1042945Y590206D02*
G02X1043535Y590450I555J-507D01*
G01X1055711D01*
X1057311Y588850D01*
X1059011D01*
X1060150Y587711D01*
Y587461D01*
G03X1060655Y587075I400J0D01*
G02X1060298Y584522I369J-1353D01*
G01X1060164Y584603D01*
X1058211Y582650D01*
X1055432D01*
Y577072D01*
X1053228D01*
Y582650D01*
X1052086D01*
Y577072D01*
X1049882D01*
Y582650D01*
X1045392D01*
Y577072D01*
X1043190D01*
Y582750D01*
X1041650Y584289D01*
Y585207D01*
G03X1040905Y585409I-400J0D01*
G02X1034196Y587229I-3108J1820D01*
G01Y592129D01*
G02X1041398I3601J0D01*
G01Y589625D01*
G03X1042081Y589342I400J0D01*
G01X1042945Y590206D01*
G37*
G36*
G01X1065129Y584543D02*
X1065037Y584484D01*
Y584174D01*
X1065472D01*
Y577072D01*
X1063268D01*
Y584174D01*
X1063705D01*
Y584484D01*
X1063613Y584543D01*
G02X1065129I758J1179D01*
G37*
G36*
G01X1078515D02*
X1078423Y584484D01*
Y584174D01*
X1078856D01*
Y577072D01*
X1076654D01*
Y584174D01*
X1077091D01*
Y584484D01*
X1076999Y584543D01*
G02X1078515I758J1179D01*
G37*
G36*
G01X1085208D02*
X1085116Y584484D01*
Y584174D01*
X1085550D01*
Y577072D01*
X1083346D01*
Y584174D01*
X1083784D01*
Y584484D01*
X1083692Y584543D01*
G02X1085208I758J1179D01*
G37*
G36*
G01X1088555D02*
X1088463Y584484D01*
Y584174D01*
X1088896D01*
Y577072D01*
X1086694D01*
Y584174D01*
X1087131D01*
Y584484D01*
X1087039Y584543D01*
G02X1088555I758J1179D01*
G37*
G36*
G01X1095246D02*
X1095154Y584484D01*
Y584174D01*
X1095590D01*
Y577072D01*
X1093386D01*
Y584174D01*
X1093822D01*
Y584484D01*
X1093730Y584543D01*
G02X1095246I758J1179D01*
G37*
G36*
G01X1383529Y580052D02*
G02X1381918Y580375I-1029J-952D01*
G03X1382045Y581011I-166J364D01*
G02X1383656Y580688I1029J952D01*
G03X1383529Y580052I166J-364D01*
G37*
G36*
G01X1780237Y580693D02*
G02X1778686Y580641I-736J-1193D01*
G03X1778663Y581307I-233J325D01*
G02X1778490Y583566I737J1193D01*
G03X1778401Y584232I-260J304D01*
G02X1778223Y586667I599J1268D01*
G03Y587333I-222J333D01*
G02X1779777I777J1167D01*
G03Y586667I222J-333D01*
G02X1779910Y584434I-777J-1167D01*
G03X1779999Y583768I260J-304D01*
G02X1780214Y581359I-599J-1268D01*
G03X1780237Y580693I233J-325D01*
G37*
G36*
G01X1431862Y580346D02*
G02X1429326Y580244I-1292J544D01*
G03X1428644Y580290I-355J-185D01*
G02X1428744Y581746I-1144J810D01*
G03X1429426Y581700I355J185D01*
G02X1431246Y582118I1144J-810D01*
G03X1431808Y582314I193J350D01*
G02X1432046Y582695I1293J-543D01*
G03X1431933Y583312I-301J264D01*
G02X1433644Y583625I658J1238D01*
G03X1433757Y583008I301J-264D01*
G02X1432424Y580542I-657J-1238D01*
G03X1431862Y580346I-193J-350D01*
G37*
G36*
G01X723628Y580068D02*
G02Y581732I-1128J832D01*
G03X724272I322J238D01*
G02Y580068I1128J-832D01*
G03X723628I-322J-238D01*
G37*
G36*
G01X1283571Y582011D02*
G02X1281629I-971J-1011D01*
G03Y582589I-277J289D01*
G02X1282579Y585002I971J1011D01*
G03X1282872Y585667I-6J400D01*
G02X1284548Y584343I4531J4012D01*
G03X1283969Y583904I-188J-353D01*
G02X1283571Y582589I-1369J-303D01*
G03Y582011I277J-289D01*
G37*
G36*
G01X72667Y581223D02*
G02Y582777I-1167J777D01*
G03X73333I333J222D01*
G02Y581223I1167J-777D01*
G03X72667I-333J-222D01*
G37*
G36*
G01X79667D02*
G02Y582777I-1167J777D01*
G03X80333I333J222D01*
G02Y581223I1167J-777D01*
G03X79667I-333J-222D01*
G37*
G36*
G01X1793330Y584687D02*
G02X1792007Y585292I-1160J-787D01*
G03X1792292Y585914I-46J398D01*
G02X1793615Y585309I1160J787D01*
G03X1793330Y584687I46J-398D01*
G37*
G36*
G01X1857775Y587634D02*
G02X1856700Y586776I225J-1384D01*
G03X1856265Y587320I-371J149D01*
G02X1857340Y588178I-225J1384D01*
G03X1857775Y587634I371J-149D01*
G37*
G36*
G01X1739937Y587832D02*
G02X1738234Y587102I-437J-1332D01*
G03X1737997Y587654I-361J172D01*
G02X1737778Y587747I437J1332D01*
G03X1737239Y587582I-186J-354D01*
G02X1736659Y589483I-1236J662D01*
G03X1737198Y589648I186J354D01*
G02X1738077Y590342I1236J-662D01*
G03X1738243Y591026I-101J387D01*
G02X1738719Y593394I936J1044D01*
G03X1738961Y593916I-131J378D01*
G02X1738950Y594891I1309J502D01*
G03X1738715Y595400I-377J135D01*
G02X1740531Y596239I496J1311D01*
G03X1740766Y595730I377J-135D01*
G02X1740730Y593095I-496J-1311D01*
G03X1740488Y592573I131J-378D01*
G02X1739536Y590714I-1309J-503D01*
G03X1739370Y590030I101J-387D01*
G02X1739700Y588384I-936J-1044D01*
G03X1739937Y587832I361J-172D01*
G37*
G36*
G01X1399147Y586309D02*
G02X1397189Y588243I-1167J777D01*
G03X1397195Y588899I-226J330D01*
G02X1396711Y589513I815J1141D01*
G03X1396056Y589644I-371J-151D01*
G02X1396359Y591157I-996J986D01*
G03X1397014Y591026I371J151D01*
G02X1399282Y590629I996J-986D01*
G03X1399942Y590528I363J168D01*
G02X1401990Y588613I1038J-942D01*
G03Y588059I288J-277D01*
G02X1399813Y586309I-1010J-972D01*
G03X1399147I-333J-222D01*
G37*
G36*
G01X363286Y592928D02*
G02X360761Y594542I-1322J714D01*
G03X360441Y595182I-320J240D01*
G01X360116D01*
Y602284D01*
X362319D01*
Y595108D01*
X362454Y595062D01*
G02X363286Y594356I-490J-1420D01*
G03X363989I351J190D01*
G02X364108Y594542I1322J-714D01*
G03X363788Y595182I-320J240D01*
G01X363464D01*
Y602284D01*
X365666D01*
Y595108D01*
X365801Y595062D01*
G02X366394Y594683I-490J-1420D01*
G03X366955Y594667I289J277D01*
G02X368964Y594568I956J-1025D01*
G03X369574Y594579I300J264D01*
G02X369606Y592765I1085J-888D01*
G03X368996Y592754I-300J-264D01*
G02X366955Y592617I-1085J888D01*
G03X366394Y592601I-272J-293D01*
G02X363989Y592928I-1083J1041D01*
G03X363286I-351J-190D01*
G37*
G36*
G01X1012894D02*
G02X1010369Y594542I-1322J714D01*
G03X1010049Y595182I-320J240D01*
G01X1009724D01*
Y602284D01*
X1011927D01*
Y595108D01*
X1012062Y595062D01*
G02X1012894Y594356I-490J-1420D01*
G03X1013597I352J190D01*
G02X1013716Y594542I1322J-714D01*
G03X1013396Y595182I-320J240D01*
G01X1013072D01*
Y602284D01*
X1015274D01*
Y595108D01*
X1015409Y595062D01*
G02X1016002Y594683I-490J-1420D01*
G03X1016563Y594667I289J277D01*
G02X1018582Y594556I956J-1025D01*
G03X1019200Y594569I304J260D01*
G02X1019237Y592786I1100J-869D01*
G03X1018619Y592773I-304J-260D01*
G02X1016563Y592617I-1100J869D01*
G03X1016002Y592601I-272J-293D01*
G02X1013597Y592928I-1083J1041D01*
G03X1012894I-352J-190D01*
G37*
G36*
G01X1073482Y594824D02*
X1073559Y594884D01*
Y595182D01*
X1073308D01*
Y602284D01*
X1075510D01*
Y595182D01*
X1075259D01*
Y594884D01*
X1075336Y594824D01*
G02X1073482I-927J-1182D01*
G37*
G36*
G01X356060Y594658D02*
G02X356047Y592638I966J-1016D01*
G03X355492Y592641I-279J-286D01*
G02X353737Y594816I-966J1016D01*
G01X353825Y594876D01*
Y595182D01*
X353424D01*
Y602284D01*
X355626D01*
Y595182D01*
X355227D01*
Y594876D01*
X355315Y594816D01*
G02X355505Y594661I-788J-1160D01*
G03X356060Y594658I279J286D01*
G37*
G36*
G01X397260Y594814D02*
X397350Y594874D01*
Y595182D01*
X396928D01*
Y602284D01*
X399130D01*
Y595182D01*
X398708D01*
Y594874D01*
X398798Y594814D01*
G02X397260I-769J-1172D01*
G37*
G36*
G01X407300D02*
X407390Y594874D01*
Y595182D01*
X406968D01*
Y602284D01*
X409170D01*
Y595182D01*
X408748D01*
Y594874D01*
X408838Y594814D01*
G02X407300I-769J-1172D01*
G37*
G36*
G01X424032D02*
X424122Y594874D01*
Y595182D01*
X423700D01*
Y602284D01*
X425902D01*
Y595182D01*
X425480D01*
Y594874D01*
X425570Y594814D01*
G02X424032I-769J-1172D01*
G37*
G36*
G01X430725D02*
X430815Y594874D01*
Y595182D01*
X430392D01*
Y602284D01*
X432596D01*
Y595182D01*
X432173D01*
Y594874D01*
X432263Y594814D01*
G02X430725I-769J-1172D01*
G37*
G36*
G01X1005668Y594658D02*
G02X1005655Y592638I966J-1016D01*
G03X1005100Y592641I-279J-286D01*
G02X1003345Y594816I-966J1016D01*
G01X1003433Y594876D01*
Y595182D01*
X1003032D01*
Y602284D01*
X1005234D01*
Y595182D01*
X1004835D01*
Y594876D01*
X1004923Y594816D01*
G02X1005113Y594661I-788J-1160D01*
G03X1005668Y594658I279J286D01*
G37*
G36*
G01X1046868Y594814D02*
X1046958Y594874D01*
Y595182D01*
X1046536D01*
Y602284D01*
X1048738D01*
Y595182D01*
X1048316D01*
Y594874D01*
X1048406Y594814D01*
G02X1046868I-769J-1172D01*
G37*
G36*
G01X1056908D02*
X1056998Y594874D01*
Y595182D01*
X1056576D01*
Y602284D01*
X1058778D01*
Y595182D01*
X1058356D01*
Y594874D01*
X1058446Y594814D01*
G02X1056908I-769J-1172D01*
G37*
G36*
G01X1080333D02*
X1080423Y594874D01*
Y595182D01*
X1080000D01*
Y602284D01*
X1082204D01*
Y595182D01*
X1081781D01*
Y594874D01*
X1081871Y594814D01*
G02X1080333I-769J-1172D01*
G37*
G36*
G01X306886Y594816D02*
X306974Y594876D01*
Y595182D01*
X306574D01*
Y602284D01*
X308776D01*
Y595182D01*
X308376D01*
Y594876D01*
X308464Y594816D01*
G02X306886I-789J-1159D01*
G37*
G36*
G01X313579D02*
X313667Y594876D01*
Y595182D01*
X313266D01*
Y602284D01*
X315470D01*
Y595182D01*
X315069D01*
Y594876D01*
X315157Y594816D01*
G02X313579I-789J-1159D01*
G37*
G36*
G01X320272D02*
X320360Y594876D01*
Y595182D01*
X319960D01*
Y602284D01*
X322162D01*
Y595182D01*
X321762D01*
Y594876D01*
X321850Y594816D01*
G02X320272I-789J-1159D01*
G37*
G36*
G01X323618D02*
X323706Y594876D01*
Y595182D01*
X323306D01*
Y602284D01*
X325508D01*
Y595182D01*
X325108D01*
Y594876D01*
X325196Y594816D01*
G02X323618I-789J-1159D01*
G37*
G36*
G01X330311D02*
X330399Y594876D01*
Y595182D01*
X329998D01*
Y602284D01*
X332202D01*
Y595182D01*
X331801D01*
Y594876D01*
X331889Y594816D01*
G02X330311I-789J-1159D01*
G37*
G36*
G01X333658D02*
X333746Y594876D01*
Y595182D01*
X333346D01*
Y602284D01*
X335548D01*
Y595182D01*
X335148D01*
Y594876D01*
X335236Y594816D01*
G02X333658I-789J-1159D01*
G37*
G36*
G01X340351D02*
X340439Y594876D01*
Y595182D01*
X340038D01*
Y602284D01*
X342242D01*
Y595182D01*
X341841D01*
Y594876D01*
X341929Y594816D01*
G02X340351I-789J-1159D01*
G37*
G36*
G01X343697D02*
X343785Y594876D01*
Y595182D01*
X343384D01*
Y602284D01*
X345588D01*
Y595182D01*
X345187D01*
Y594876D01*
X345275Y594816D01*
G02X343697I-789J-1159D01*
G37*
G36*
G01X350390D02*
X350478Y594876D01*
Y595182D01*
X350078D01*
Y602284D01*
X352280D01*
Y595182D01*
X351880D01*
Y594876D01*
X351968Y594816D01*
G02X350390I-789J-1159D01*
G37*
G36*
G01X403934D02*
X404022Y594876D01*
Y595182D01*
X403620D01*
Y602284D01*
X405824D01*
Y595182D01*
X405424D01*
Y594876D01*
X405512Y594816D01*
G02X403934I-789J-1159D01*
G37*
G36*
G01X413974D02*
X414062Y594876D01*
Y595182D01*
X413660D01*
Y602284D01*
X415864D01*
Y595182D01*
X415464D01*
Y594876D01*
X415552Y594816D01*
G02X413974I-789J-1159D01*
G37*
G36*
G01X420667D02*
X420755Y594876D01*
Y595182D01*
X420354D01*
Y602284D01*
X422556D01*
Y595182D01*
X422157D01*
Y594876D01*
X422245Y594816D01*
G02X420667I-789J-1159D01*
G37*
G36*
G01X956494D02*
X956582Y594876D01*
Y595182D01*
X956182D01*
Y602284D01*
X958384D01*
Y595182D01*
X957984D01*
Y594876D01*
X958072Y594816D01*
G02X956494I-789J-1159D01*
G37*
G36*
G01X963187D02*
X963275Y594876D01*
Y595182D01*
X962874D01*
Y602284D01*
X965078D01*
Y595182D01*
X964677D01*
Y594876D01*
X964765Y594816D01*
G02X963187I-789J-1159D01*
G37*
G36*
G01X969880D02*
X969968Y594876D01*
Y595182D01*
X969568D01*
Y602284D01*
X971770D01*
Y595182D01*
X971370D01*
Y594876D01*
X971458Y594816D01*
G02X969880I-789J-1159D01*
G37*
G36*
G01X973226D02*
X973314Y594876D01*
Y595182D01*
X972914D01*
Y602284D01*
X975116D01*
Y595182D01*
X974716D01*
Y594876D01*
X974804Y594816D01*
G02X973226I-789J-1159D01*
G37*
G36*
G01X979919D02*
X980007Y594876D01*
Y595182D01*
X979606D01*
Y602284D01*
X981810D01*
Y595182D01*
X981409D01*
Y594876D01*
X981497Y594816D01*
G02X979919I-789J-1159D01*
G37*
G36*
G01X983266D02*
X983354Y594876D01*
Y595182D01*
X982954D01*
Y602284D01*
X985156D01*
Y595182D01*
X984756D01*
Y594876D01*
X984844Y594816D01*
G02X983266I-789J-1159D01*
G37*
G36*
G01X989959D02*
X990047Y594876D01*
Y595182D01*
X989646D01*
Y602284D01*
X991850D01*
Y595182D01*
X991449D01*
Y594876D01*
X991537Y594816D01*
G02X989959I-789J-1159D01*
G37*
G36*
G01X993305D02*
X993393Y594876D01*
Y595182D01*
X992992D01*
Y602284D01*
X995196D01*
Y595182D01*
X994795D01*
Y594876D01*
X994883Y594816D01*
G02X993305I-789J-1159D01*
G37*
G36*
G01X999998D02*
X1000086Y594876D01*
Y595182D01*
X999686D01*
Y602284D01*
X1001888D01*
Y595182D01*
X1001488D01*
Y594876D01*
X1001576Y594816D01*
G02X999998I-789J-1159D01*
G37*
G36*
G01X1053542D02*
X1053630Y594876D01*
Y595182D01*
X1053228D01*
Y602284D01*
X1055432D01*
Y595182D01*
X1055032D01*
Y594876D01*
X1055120Y594816D01*
G02X1053542I-789J-1159D01*
G37*
G36*
G01X1063582D02*
X1063670Y594876D01*
Y595182D01*
X1063268D01*
Y602284D01*
X1065472D01*
Y595182D01*
X1065072D01*
Y594876D01*
X1065160Y594816D01*
G02X1063582I-789J-1159D01*
G37*
G36*
G01X1070275D02*
X1070363Y594876D01*
Y595182D01*
X1069962D01*
Y602284D01*
X1072164D01*
Y595182D01*
X1071765D01*
Y594876D01*
X1071853Y594816D01*
G02X1070275I-789J-1159D01*
G37*
G36*
G01X437396D02*
X437483Y594876D01*
Y595182D01*
X437086D01*
Y602284D01*
X439288D01*
Y595182D01*
X438891D01*
Y594876D01*
X438978Y594816D01*
G02X437396I-791J-1157D01*
G37*
G36*
G01X444089D02*
X444176Y594876D01*
Y595182D01*
X443778D01*
Y602284D01*
X445982D01*
Y595182D01*
X445584D01*
Y594876D01*
X445671Y594816D01*
G02X444089I-791J-1157D01*
G37*
G36*
G01X1087004D02*
X1087091Y594876D01*
Y595182D01*
X1086694D01*
Y602284D01*
X1088896D01*
Y595182D01*
X1088499D01*
Y594876D01*
X1088586Y594816D01*
G02X1087004I-791J-1157D01*
G37*
G36*
G01X1093697D02*
X1093784Y594876D01*
Y595182D01*
X1093386D01*
Y602284D01*
X1095590D01*
Y595182D01*
X1095192D01*
Y594876D01*
X1095279Y594816D01*
G02X1093697I-791J-1157D01*
G37*
G36*
G01X1821030Y593534D02*
G02X1820316Y595039I-1376J269D01*
G03X1820897Y595315I189J353D01*
G02X1821611Y593810I1376J-269D01*
G03X1821030Y593534I-189J-353D01*
G37*
G36*
G01X1938781Y595545D02*
G02X1937060Y595624I-911J-1065D01*
G03X1937089Y596255I-231J327D01*
G02X1938810Y596176I911J1065D01*
G03X1938781Y595545I231J-327D01*
G37*
G36*
G01X1444034Y596099D02*
G02X1442396Y595368I-380J-1350D01*
G03X1442145Y595929I-359J176D01*
G02X1442075Y598607I380J1350D01*
G03X1442286Y599198I-128J379D01*
G02X1443923Y598616I1187J746D01*
G03X1443712Y598025I128J-379D01*
G02X1443783Y596660I-1187J-746D01*
G03X1444034Y596099I359J-176D01*
G37*
G36*
G01X64667Y595223D02*
G02X62723Y597167I-1167J777D01*
G03Y597833I-222J333D01*
G02Y600167I777J1167D01*
G03Y600833I-222J333D01*
G02X64667Y602777I777J1167D01*
G03X65333I333J222D01*
G02X67667I1167J-777D01*
G03X68333I333J222D01*
G02X70667I1167J-777D01*
G03X71333I333J222D01*
G02X73667I1167J-777D01*
G03X74333I333J222D01*
G02X76667I1167J-777D01*
G03X77333I333J222D01*
G02X79667I1167J-777D01*
G03X80333I333J222D01*
G02X82277Y600833I1167J-777D01*
G03Y600167I222J-333D01*
G02Y597833I-777J-1167D01*
G03Y597167I222J-333D01*
G02X80333Y595223I-777J-1167D01*
G03X79667I-333J-222D01*
G02X77333I-1167J777D01*
G03X76667I-333J-222D01*
G02X74333I-1167J777D01*
G03X73667I-333J-222D01*
G02X71333I-1167J777D01*
G03X70667I-333J-222D01*
G02X68333I-1167J777D01*
G03X67667I-333J-222D01*
G02X65333I-1167J777D01*
G03X64667I-333J-222D01*
G37*
G36*
G01X1310267Y597723D02*
G02X1308090Y599473I-1167J778D01*
G03Y600027I-288J277D01*
G02X1310267Y601777I1010J972D01*
G03X1310933I333J222D01*
G02X1313267I1167J-777D01*
G03X1313933I333J222D01*
G02X1316267I1167J-777D01*
G03X1316933I333J222D01*
G02X1319267I1167J-777D01*
G03X1319933I333J222D01*
G02X1322110Y600027I1167J-778D01*
G03Y599473I288J-277D01*
G02X1319933Y597723I-1010J-972D01*
G03X1319267I-333J-222D01*
G02X1316933I-1167J777D01*
G03X1316267I-333J-222D01*
G02X1313933I-1167J777D01*
G03X1313267I-333J-222D01*
G02X1310933I-1167J777D01*
G03X1310267I-333J-222D01*
G37*
G36*
G01X1385675Y603929D02*
G02X1384126Y603796I-675J-1229D01*
G03X1384069Y604460I-249J313D01*
G02X1383529Y604989I675J1229D01*
G03X1382964Y605125I-347J-199D01*
G02X1383415Y607000I-764J1175D01*
G03X1383980Y606864I347J199D01*
G02X1385618Y604593I764J-1175D01*
G03X1385675Y603929I249J-313D01*
G37*
G36*
G01X1454689Y602452D02*
G02X1452656Y604378I-1061J916D01*
G03X1452616Y604988I-278J288D01*
G02X1452404Y605181I833J1128D01*
G03X1451798Y605171I-299J-266D01*
G02X1449720Y605084I-1078J896D01*
G03X1449132Y605065I-285J-280D01*
G02X1447003Y605073I-1061J916D01*
G03X1446354Y605016I-304J-259D01*
G02X1446213Y606635I-1209J710D01*
G03X1446862Y606692I304J259D01*
G02X1449071Y606964I1209J-711D01*
G03X1449659Y606983I285J280D01*
G02X1451767Y607000I1061J-916D01*
G03X1452373Y607010I299J266D01*
G02X1454451Y607097I1078J-896D01*
G03X1455039Y607116I285J280D01*
G02X1457072Y605190I1061J-916D01*
G03X1457112Y604580I278J-288D01*
G02X1455277Y602471I-835J-1126D01*
G03X1454689Y602452I-285J-280D01*
G37*
G36*
G01X713077Y605061D02*
G02X711135I-971J-1011D01*
G03Y605639I-277J289D01*
G02X711703Y607993I971J1011D01*
G03X711931Y608582I-115J383D01*
G02X714356Y609989I1201J724D01*
G03X715016Y609932I349J195D01*
G02X714882Y608367I1090J-882D01*
G03X714222Y608424I-349J-195D01*
G02X713535Y607963I-1090J882D01*
G03X713307Y607374I115J-383D01*
G02X713077Y605639I-1201J-724D01*
G03Y605061I277J-289D01*
G37*
G36*
G01X1758833Y605723D02*
G02X1757309Y605002I-283J-1373D01*
G03X1757036Y605580I-354J186D01*
G02X1758560Y606301I283J1373D01*
G03X1758833Y605723I354J-186D01*
G37*
G36*
G01X1921759Y605264D02*
G02X1921707Y603713I1141J-815D01*
G03X1921041Y603736I-341J-210D01*
G02X1921093Y605287I-1141J815D01*
G03X1921759Y605264I341J210D01*
G37*
G36*
G01X362540Y603900D02*
G02Y605328I-1322J714D01*
G03X363243I352J190D01*
G02Y603900I1322J-714D01*
G03X362540I-351J-190D01*
G37*
G36*
G01X1012148D02*
G02Y605328I-1322J714D01*
G03X1012851I352J190D01*
G02Y603900I1322J-714D01*
G03X1012148I-352J-190D01*
G37*
G36*
G01X1019465Y605264D02*
G02X1019460Y603946I1235J-664D01*
G03X1018754Y603950I-354J-186D01*
G02X1018759Y605268I-1235J664D01*
G03X1019465Y605264I354J186D01*
G37*
G36*
G01X1470066Y608965D02*
G02X1468457Y608910I-765J-1175D01*
G03X1468435Y609564I-241J319D01*
G02X1470044Y609619I765J1175D01*
G03X1470066Y608965I241J-319D01*
G37*
G36*
G01X1498208Y611341D02*
G02X1496845Y611026I-408J-1341D01*
G03X1496689Y611702I-272J293D01*
G02X1495870Y612364I407J1342D01*
G03X1495205Y612417I-350J-193D01*
G02X1493563Y611985I-1105J863D01*
G03X1493011Y611640I-153J-370D01*
G02X1492140Y613096I-1499J92D01*
G03X1492705Y613420I167J364D01*
G02X1492859Y613932I1395J-140D01*
G03X1492559Y614514I-354J186D01*
G02X1493991Y615251I191J1389D01*
G03X1494291Y614669I354J-186D01*
G02X1495327Y613959I-191J-1389D01*
G03X1495992Y613906I350J193D01*
G02X1498052Y612017I1105J-862D01*
G03X1498208Y611341I272J-293D01*
G37*
G36*
G01X730778Y610078D02*
G02X728540Y609964I-1162J785D01*
G03X727928Y609966I-307J-256D01*
G02X727933Y611770I-1071J905D01*
G03X728545Y611768I307J256D01*
G02X730698Y611754I1071J-905D01*
G03X731338Y611785I308J255D01*
G02X731418Y610109I1162J-784D01*
G03X730778Y610078I-308J-255D01*
G37*
G36*
G01X1701138Y618388D02*
G02X1700272Y616314I4633J-3152D01*
G03X1699708Y616752I-392J77D01*
G02X1700430Y618481I-602J1266D01*
G03X1701138Y618388I377J132D01*
G37*
G36*
G01X366394Y612926D02*
G02X366027Y610948I776J-1167D01*
G03X365462Y611037I-326J-232D01*
G02X363243Y611528I-897J1205D01*
G03X362540I-351J-190D01*
G02Y612956I-1322J714D01*
G03X363243I352J190D01*
G02X365834Y613045I1322J-714D01*
G03X366394Y612926I338J214D01*
G37*
G36*
G01X1016002D02*
G02X1015635Y610948I776J-1167D01*
G03X1015070Y611037I-326J-232D01*
G02X1012851Y611528I-897J1205D01*
G03X1012148I-352J-190D01*
G02Y612956I-1322J714D01*
G03X1012851I352J190D01*
G02X1015442Y613045I1322J-714D01*
G03X1016002Y612926I338J214D01*
G37*
G36*
G01X79667Y611223D02*
G02Y612777I-1167J777D01*
G03X80333I333J222D01*
G02Y611223I1167J-777D01*
G03X79667I-333J-222D01*
G37*
G36*
G01X70667Y614723D02*
G02Y616277I-1167J777D01*
G03X71333I333J222D01*
G02X73667I1167J-777D01*
G03X74333I333J222D01*
G02X76667I1167J-777D01*
G03X77333I333J222D01*
G02X79667I1167J-777D01*
G03X80333I333J222D01*
G02Y614723I1167J-777D01*
G03X79667I-333J-222D01*
G02X77333I-1167J777D01*
G03X76667I-333J-222D01*
G02X74333I-1167J777D01*
G03X73667I-333J-222D01*
G02X71333I-1167J777D01*
G03X70667I-333J-222D01*
G37*
G36*
G01X1471710Y617638D02*
G02X1469044Y617506I-1354J362D01*
G03X1468485Y617720I-374J-141D01*
G02X1469151Y619458I-646J1244D01*
G03X1469710Y619244I374J141D01*
G02X1471006Y619242I646J-1244D01*
G03X1471578Y619493I185J355D01*
G02X1474057Y619968I1354J-362D01*
G03X1474712Y619987I321J239D01*
G02X1476871Y620212I1171J-770D01*
G03X1477451Y620231I281J284D01*
G02X1479164Y620535I1049J-931D01*
G03X1479714Y620712I190J352D01*
G02X1482272Y620633I1261J-612D01*
G03X1482783Y620411I370J152D01*
G02X1481982Y618567I496J-1311D01*
G03X1481471Y618789I-370J-152D01*
G02X1480311Y618865I-497J1311D01*
G03X1479761Y618688I-190J-352D01*
G02X1477512Y618305I-1261J612D01*
G03X1476932Y618286I-281J-284D01*
G02X1474758Y618380I-1049J931D01*
G03X1474103Y618361I-321J-239D01*
G02X1472282Y617889I-1171J770D01*
G03X1471710Y617638I-185J-355D01*
G37*
G36*
G01X92682Y618956D02*
G02X92719Y617218I1118J-846D01*
G03X92131Y617249I-308J-255D01*
G02X89762Y618451I-981J1001D01*
G03X89365Y618908I-396J57D01*
G02X88156Y619592I-5J1402D01*
G03X87461Y619579I-344J-205D01*
G02X87434Y620968I-1231J671D01*
G03X88129Y620981I344J205D01*
G02X90158Y621463I1231J-671D01*
G03X90734Y621594I228J328D01*
G02X92499Y619609I1218J-694D01*
G03X92321Y619021I156J-368D01*
G02X92351Y618974I-1167J-778D01*
G03X92682Y618956I172J103D01*
G37*
G36*
G01X1778267Y620296D02*
G02X1777054Y619294I133J-1396D01*
G03X1776633Y619804I-384J112D01*
G02X1777846Y620806I-133J1396D01*
G03X1778267Y620296I384J-112D01*
G37*
G36*
G01X1517373Y618790D02*
G02X1515315Y618912I-973J1010D01*
G03X1514716Y618934I-309J-254D01*
G02X1512666Y618953I-1016J966D01*
G03X1512112Y618988I-295J-270D01*
G02X1510259Y619021I-908J1068D01*
G03X1509670Y618966I-269J-296D01*
G02X1507346Y619092I-1120J844D01*
G03X1506708Y619159I-344J-204D01*
G02X1506883Y620829I-1029J952D01*
G03X1507521Y620762I344J204D01*
G02X1509495Y620845I1029J-952D01*
G03X1510084Y620900I269J296D01*
G02X1512238Y621003I1120J-844D01*
G03X1512792Y620968I295J270D01*
G02X1514785Y620788I908J-1068D01*
G03X1515384Y620766I309J254D01*
G02X1517373Y620810I1016J-966D01*
G03X1517927I277J288D01*
G02Y618790I973J-1010D01*
G03X1517373I-277J-288D01*
G37*
G36*
G01X1614030Y585919D02*
X1614021Y585835D01*
G02X1612796Y584518I-1502J169D01*
G01X1612633Y584488D01*
Y584122D01*
X1612802D01*
Y581118D01*
X1608898D01*
Y584122D01*
X1611313D01*
G03X1611565Y584832I-1J400D01*
G02X1611008Y586004I954J1172D01*
G01Y590005D01*
G02X1614030Y590014I1511J-1D01*
G01Y585919D01*
G37*
G36*
G01X1411821Y302282D02*
X1410330D01*
G03X1409933Y301919I1J-400D01*
G02X1407135Y302052I-1396J128D01*
G01Y302252D01*
X1405036D01*
Y311256D01*
X1407038D01*
Y309058D01*
G03X1407682Y308741I400J0D01*
G02X1409534Y308616I855J-1111D01*
G03X1410218Y308897I284J281D01*
G01Y311286D01*
X1412222D01*
Y309062D01*
G03X1412865Y308745I400J0D01*
G02Y306523I855J-1111D01*
G03X1412222Y306206I-243J-317D01*
G01Y303536D01*
G03X1412852Y303209I400J0D01*
G02X1412220Y301904I868J-1226D01*
G03X1411821Y302282I-399J-22D01*
G37*
G36*
G01X1322260Y281218D02*
X1318751D01*
G02Y284242I0J1512D01*
G01X1322261D01*
G02X1323772Y282740I-1J-1512D01*
G01Y282645D01*
X1323762Y282561D01*
G02X1323058Y281447I-1502J170D01*
G03X1323004Y281396I108J-168D01*
G02X1322837Y281316I-160J120D01*
G03X1322763Y281305I-8J-200D01*
G02X1322260Y281218I-505J1425D01*
G37*
G36*
G01X1323733Y281174D02*
X1327244D01*
G02X1328422Y280609I0J-1511D01*
G03X1329023Y280584I311J251D01*
G02X1328993Y278685I1016J-966D01*
G03X1328390Y278679I-299J-266D01*
G02X1327243Y278152I-1147J984D01*
G01X1323734D01*
G02X1322936Y280946I0J1511D01*
G03X1322990Y280997I-108J168D01*
G02X1323157Y281077I160J-120D01*
G03X1323231Y281088I8J200D01*
G02X1323733Y281174I503J-1425D01*
G37*
G36*
G01X1453595Y267493D02*
G02X1452725Y265728I461J-1324D01*
G03X1452214Y265980I-380J-126D01*
G02X1450528Y266623I-461J1324D01*
G03X1449828I-350J-194D01*
G02X1447378Y266622I-1225J681D01*
G03X1446679I-350J-194D01*
G02X1444228Y266623I-1225J682D01*
G03X1443529I-350J-194D01*
G02X1441623Y268529I-1226J680D01*
G03Y269228I-195J349D01*
G02X1441622Y271679I680J1226D01*
G03Y272378I-195J350D01*
G02X1443529Y274284I682J1225D01*
G03X1444229I350J194D01*
G02X1444773Y274828I1225J-681D01*
G03Y275528I-194J350D01*
G02X1444772Y277978I681J1225D01*
G03Y278677I-194J350D01*
G02X1444229Y279221I683J1224D01*
G03X1443529I-350J-194D01*
G02Y280583I-1225J681D01*
G03X1444229I350J194D01*
G02X1446679Y280584I1225J-681D01*
G03X1447378I349J194D01*
G02X1447923Y281128I1225J-682D01*
G03Y281827I-195J349D01*
G02X1447921Y284278I680J1226D01*
G03Y284977I-194J350D01*
G02Y287427I682J1225D01*
G03Y288126I-194J350D01*
G02X1447378Y288669I682J1225D01*
G03X1446679I-350J-194D01*
G02X1444229I-1225J682D01*
G03X1443530I-350J-194D01*
G02X1441622Y290575I-1226J681D01*
G03Y291274I-194J349D01*
G02X1443513Y293209I682J1225D01*
G03X1444206Y293215I345J203D01*
G02X1444711Y293731I1221J-689D01*
G03Y294419I-205J344D01*
G02X1444774Y296864I716J1205D01*
G03X1444780Y297569I-187J354D01*
G02X1444228Y298118I674J1229D01*
G03X1443529I-350J-194D01*
G02Y299479I-1226J681D01*
G03X1444228I349J194D01*
G02X1444773Y300023I1225J-682D01*
G03Y300723I-194J350D01*
G02Y303173I681J1225D01*
G03Y303873I-194J350D01*
G02X1444229Y304417I681J1225D01*
G03X1443529I-350J-194D01*
G02X1441622Y306323I-1225J681D01*
G03Y307022I-194J350D01*
G02X1441623Y309472I682J1225D01*
G03Y310172I-194J350D01*
G02X1443529Y312078I681J1225D01*
G03X1444229I350J194D01*
G02X1446135Y310172I1225J-681D01*
G03Y309472I194J-350D01*
G02X1446679Y308929I-680J-1226D01*
G03X1447378I349J194D01*
G02X1449285Y307022I1225J-682D01*
G03Y306323I194J-350D01*
G02X1449828Y305779I-683J-1224D01*
G03X1450528I350J194D01*
G02X1452434Y303873I1225J-681D01*
G03Y303173I194J-350D01*
G02X1452978Y302630I-680J-1226D01*
G03X1453677I349J194D01*
G02X1455583Y300723I1225J-682D01*
G03Y300023I194J-350D01*
G02X1456127Y299479I-681J-1225D01*
G03X1456827I350J194D01*
G02X1459277I1225J-681D01*
G03X1459977I350J194D01*
G02X1460521Y300023I1225J-681D01*
G03Y300723I-194J350D01*
G02Y303173I681J1225D01*
G03Y303873I-194J350D01*
G02X1459977Y304417I681J1225D01*
G03X1459277I-350J-194D01*
G02X1457370Y306323I-1225J681D01*
G03Y307022I-194J350D01*
G02X1456827Y307566I683J1224D01*
G03X1456127I-350J-194D01*
G02X1454221Y309472I-1225J681D01*
G03Y310172I-194J350D01*
G02X1453677Y310715I680J1226D01*
G03X1452978I-350J-194D01*
G02X1451071Y312622I-1225J682D01*
G03Y313321I-194J350D01*
G02X1450528Y313865I683J1224D01*
G03X1449828I-350J-194D01*
G02X1447922Y315771I-1225J681D01*
G03Y316471I-194J350D01*
G02X1447389Y316995I681J1225D01*
G03X1446706Y317012I-347J-200D01*
G02X1446742Y318473I-1178J760D01*
G03X1447425Y318456I347J200D01*
G02X1449828Y318377I1178J-760D01*
G03X1450528I350J194D01*
G02X1452982Y318370I1225J-681D01*
G03X1453687Y318376I351J192D01*
G02X1455580Y316482I1241J-653D01*
G03X1455574Y315776I185J-355D01*
G02X1456127Y315227I-672J-1230D01*
G03X1456827I350J194D01*
G02X1459277I1225J-681D01*
G03X1459977I350J194D01*
G02X1461884Y313321I1225J-681D01*
G03Y312622I194J-350D01*
G02X1462427Y312079I-682J-1225D01*
G03X1463126I349J194D01*
G02X1465032Y310171I1225J-682D01*
G03Y309472I194J-350D01*
G02Y307022I-682J-1225D01*
G03Y306323I195J-350D01*
G02Y303873I-681J-1225D01*
G03Y303173I194J-350D01*
G02Y300723I-681J-1225D01*
G03Y300023I194J-350D01*
G02X1463126Y298116I-681J-1225D01*
G03X1462427I-350J-194D01*
G02X1461884Y297573I-1225J682D01*
G03Y296874I194J-349D01*
G02X1459977Y294968I-682J-1225D01*
G03X1459277I-350J-194D01*
G02X1456827I-1225J681D01*
G03X1456127I-350J-194D01*
G02X1455618Y294444I-1225J681D01*
G03X1455585Y293778I204J-344D01*
G02X1454035Y293856I-834J-1127D01*
G03X1454068Y294522I-204J344D01*
G02X1453676Y294969I834J1127D01*
G03X1452977I-350J-195D01*
G02X1450521Y294975I-1226J680D01*
G03X1449817Y294970I-351J-192D01*
G02X1447352Y294943I-1240J654D01*
G03X1446652I-350J-194D01*
G02X1446143Y294419I-1225J681D01*
G03Y293731I205J-344D01*
G02X1446101Y291297I-716J-1205D01*
G03X1446107Y290592I192J-351D01*
G02X1446679Y290033I-653J-1241D01*
G03X1447378I349J194D01*
G02X1449828Y290032I1225J-682D01*
G03X1450528I350J194D01*
G02X1452978Y290033I1225J-681D01*
G03X1453677I349J194D01*
G02X1456127Y290032I1225J-682D01*
G03X1456827I350J194D01*
G02X1459277I1225J-681D01*
G03X1459977I350J194D01*
G02X1461884Y288126I1225J-681D01*
G03Y287427I194J-350D01*
G02X1462427Y286884I-682J-1225D01*
G03X1463126I349J194D01*
G02X1465032Y284977I1225J-682D01*
G03Y284277I194J-350D01*
G02Y281827I-681J-1225D01*
G03Y281127I194J-350D01*
G02X1465033Y278677I-681J-1225D01*
G03Y277978I194J-350D01*
G02X1465109Y275573I-682J-1225D01*
G03X1465125Y274890I216J-337D01*
G02X1463666Y274856I-702J-1214D01*
G03X1463650Y275539I-216J337D01*
G02X1463126Y276071I701J1214D01*
G03X1462427I-350J-194D01*
G02X1461883Y275528I-1224J683D01*
G03Y274828I194J-350D01*
G02X1459977Y272922I-681J-1225D01*
G03X1459277I-350J-194D01*
G02X1458715Y272368I-1225J681D01*
G03X1458726Y271657I189J-353D01*
G02X1459346Y271048I-624J-1255D01*
G03X1460056Y271047I355J184D01*
G02Y269754I1244J-646D01*
G03X1459346Y269755I-355J-184D01*
G02X1456847Y269778I-1244J647D01*
G03X1456136Y269789I-358J-178D01*
G02X1453677Y269772I-1234J665D01*
G03X1452978I-350J-194D01*
G02X1452434Y269229I-1224J683D01*
G03Y268529I194J-350D01*
G02X1453084Y267745I-681J-1226D01*
G03X1453595Y267493I380J126D01*
G37*
G36*
G01X1395890Y242172D02*
Y239320D01*
G03X1396537Y239005I400J0D01*
G02X1398802Y237865I863J-1105D01*
G03X1399393Y237504I400J-10D01*
G02X1401041Y235266I674J-1230D01*
G03X1401021Y234712I278J-287D01*
G02X1399374Y232510I-1043J-937D01*
G03X1398802Y232142I-172J-361D01*
G02X1396093Y232625I-1402J-24D01*
G03X1395720Y233170I-373J145D01*
G01X1393888D01*
Y242172D01*
X1395890D01*
G37*
G36*
G01X1646462Y108510D02*
G02X1644556Y110416I-1225J681D01*
G03Y111116I-194J350D01*
G02Y113566I681J1225D01*
G03Y114266I-194J350D01*
G02X1644010Y114813I681J1225D01*
G03X1643310Y114814I-350J-193D01*
G02X1642626Y114201I-1226J680D01*
G03X1642556Y113501I154J-369D01*
G02X1641228Y113633I-786J-1161D01*
G03X1641298Y114333I-154J369D01*
G02X1641440Y116740I786J1161D01*
G03X1641455Y117442I-183J355D01*
G02X1643356Y119376I695J1218D01*
G03X1644041Y119371I344J204D01*
G02X1645919Y117415I1196J-731D01*
G03Y116716I194J-350D01*
G02X1646462Y116172I-683J-1224D01*
G03X1647162I350J194D01*
G02X1649612Y116173I1225J-681D01*
G03X1650311I350J194D01*
G02X1652217Y114266I1225J-682D01*
G03Y113566I194J-350D01*
G02X1652761Y113023I-680J-1226D01*
G03X1653460I350J194D01*
G02X1655910Y113022I1225J-682D01*
G03X1656610I350J194D01*
G02X1657154Y113566I1225J-681D01*
G03Y114266I-194J350D01*
G02X1657153Y116716I681J1225D01*
G03Y117415I-194J349D01*
G02X1656607Y117963I682J1225D01*
G03X1655906Y117960I-350J-194D01*
G02X1654005Y119861I-1233J668D01*
G03X1654008Y120562I-191J351D01*
G02X1654004Y123016I677J1228D01*
G03Y123715I-194J349D01*
G02X1653461Y124258I682J1225D01*
G03X1652762I-349J-194D01*
G02X1650855Y126164I-1226J681D01*
G03Y126864I-194J350D01*
G02Y129314I681J1225D01*
G03Y130014I-194J350D01*
G02X1650854Y132464I681J1225D01*
G03Y133163I-194J350D01*
G02X1650850Y135611I682J1225D01*
G03Y136309I-195J349D01*
G02X1650855Y138761I682J1225D01*
G03Y139461I-194J350D01*
G02Y141912I681J1226D01*
G03Y142612I-194J350D01*
G02X1650856Y145063I681J1225D01*
G03Y145762I-195J350D01*
G02X1652216I680J1226D01*
G03Y145063I195J-349D01*
G02X1652761Y144519I-680J-1226D01*
G03X1653460I350J194D01*
G02X1655910Y144518I1225J-682D01*
G03X1656610I350J194D01*
G02X1657154Y145062I1225J-681D01*
G03Y145762I-194J350D01*
G02X1659060Y147668I681J1225D01*
G03X1659760I350J194D01*
G02X1660304Y148212I1225J-681D01*
G03Y148912I-194J350D01*
G02X1661666I681J1225D01*
G03Y148212I194J-350D01*
G02X1662220Y147651I-680J-1226D01*
G03X1662930Y147662I352J189D01*
G02X1662951Y146374I1256J-624D01*
G03X1662241Y146363I-352J-189D01*
G02X1661666Y145762I-1255J625D01*
G03Y145062I194J-350D01*
G02X1661667Y142612I-681J-1225D01*
G03Y141913I194J-349D01*
G02Y139463I-682J-1225D01*
G03Y138764I194J-350D01*
G02X1662211Y138219I-682J-1225D01*
G03X1662911I350J194D01*
G02Y136857I1225J-681D01*
G03X1662211I-350J-194D01*
G02X1659761I-1225J681D01*
G03X1659061I-350J-194D01*
G02X1657155Y138763I-1225J681D01*
G03Y139463I-194J350D01*
G02X1656610Y140007I680J1226D01*
G03X1655911I-349J-194D01*
G02X1653460Y140005I-1226J680D01*
G03X1652761I-349J-194D01*
G02X1652213Y139460I-1224J683D01*
G03Y138760I194J-350D01*
G02X1652218Y136311I-681J-1226D01*
G03Y135613I195J-349D01*
G02X1652761Y135070I-682J-1225D01*
G03X1653460I350J194D01*
G02X1655367Y133163I1226J-681D01*
G03Y132464I194J-350D01*
G02X1655910Y131920I-683J-1224D01*
G03X1656610I350J194D01*
G02X1659060I1225J-681D01*
G03X1659760I350J194D01*
G02X1662210I1225J-681D01*
G03X1662910I350J194D01*
G02X1665360Y131921I1225J-681D01*
G03X1666059I350J194D01*
G02Y130557I1225J-682D01*
G03X1665360I-349J-194D01*
G02X1664816Y130014I-1224J683D01*
G03Y129314I194J-350D01*
G02X1662910Y127408I-681J-1225D01*
G03X1662210I-350J-194D01*
G02X1661666Y126864I-1225J681D01*
G03Y126164I194J-350D01*
G02X1661667Y123714I-681J-1225D01*
G03Y123015I194J-350D01*
G02X1662210Y122471I-683J-1224D01*
G03X1662910I350J194D01*
G02X1664816Y120565I1225J-681D01*
G03Y119865I194J-350D01*
G02X1664817Y117415I-681J-1225D01*
G03Y116716I194J-350D01*
G02X1665360Y116173I-682J-1225D01*
G03X1666059I350J194D01*
G02X1668509Y116172I1225J-682D01*
G03X1669209I350J194D01*
G02Y114810I1225J-681D01*
G03X1668509I-350J-194D01*
G02X1667978Y114273I-1225J681D01*
G03X1667968Y113584I198J-347D01*
G02X1666041Y111656I-730J-1197D01*
G03X1665353Y111646I-341J-208D01*
G02X1662910Y111660I-1218J695D01*
G03X1662210I-350J-194D01*
G02X1661666Y111116I-1225J681D01*
G03Y110416I194J-350D01*
G02X1659760Y108510I-681J-1225D01*
G03X1659060I-350J-194D01*
G02X1656610Y108509I-1225J681D01*
G03X1655911I-349J-194D01*
G02X1653461Y108510I-1225J682D01*
G03X1652761I-350J-194D01*
G02X1650311Y108509I-1225J681D01*
G03X1649612I-349J-194D01*
G02X1647162Y108510I-1225J682D01*
G03X1646462I-350J-194D01*
G37*
G36*
G01X1498944Y114388D02*
G02X1501966Y114398I1511J0D01*
G01Y110848D01*
X1501957Y110764D01*
G02X1500456Y109422I-1502J169D01*
G03X1500091Y108859I1J-400D01*
G02X1498755Y109691I-1281J-569D01*
G03X1499098Y110267I-16J400D01*
G02X1498944Y110930I1357J665D01*
G01Y114388D01*
G37*
G36*
G01X1614423Y107267D02*
G02X1613059I-682J-1225D01*
G03Y107966I-194J350D01*
G02X1613060Y110416I682J1225D01*
G03Y111116I-194J350D01*
G02X1612516Y111660I681J1225D01*
G03X1611816I-350J-194D01*
G02X1609366I-1225J681D01*
G03X1608666I-350J-194D01*
G02X1606760Y113566I-1225J681D01*
G03Y114266I-194J350D01*
G02X1608666Y116172I681J1225D01*
G03X1609366I350J194D01*
G02X1609909Y116716I1226J-680D01*
G03Y117415I-194J349D01*
G02X1609910Y119865I682J1225D01*
G03Y120565I-194J350D01*
G02X1609366Y121109I681J1225D01*
G03X1608666I-350J-194D01*
G02X1606759Y123015I-1225J681D01*
G03Y123714I-194J350D01*
G02X1608666Y125620I682J1225D01*
G03X1609366I350J194D01*
G02X1609910Y126164I1225J-681D01*
G03Y126864I-194J350D01*
G02X1611816Y128770I681J1225D01*
G03X1612516I350J194D01*
G02X1614966I1225J-681D01*
G03X1615666I350J194D01*
G02X1618116Y128771I1225J-681D01*
G03X1618815I350J194D01*
G02X1621265Y128770I1225J-682D01*
G03X1621965I350J194D01*
G02X1623872Y126864I1225J-681D01*
G03Y126165I194J-350D01*
G02X1624415Y125622I-682J-1225D01*
G03X1625114I350J194D01*
G02X1627012Y123710I1225J-682D01*
G03X1627018Y123005I192J-351D01*
G02X1627060Y120548I-654J-1240D01*
G03X1627054Y119857I198J-347D01*
G02X1627013Y117422I-715J-1206D01*
G03Y116720I192J-351D01*
G02X1627564Y116172I-674J-1229D01*
G03X1628264I350J194D01*
G02X1630714Y116173I1225J-681D01*
G03X1631413I350J194D01*
G02X1631957Y116716I1224J-683D01*
G03Y117415I-195J349D01*
G02X1633864Y119322I682J1225D01*
G03X1634563I350J194D01*
G02Y117958I1225J-682D01*
G03X1633864I-350J-194D01*
G02X1633320Y117415I-1224J683D01*
G03Y116716I195J-350D01*
G02X1633319Y114266I-682J-1225D01*
G03Y113566I194J-350D01*
G02X1633327Y111120I-681J-1225D01*
G03X1633322Y110426I196J-348D01*
G02X1633309Y107997I-707J-1211D01*
G03X1633299Y107307I197J-348D01*
G02X1631334Y105452I-725J-1200D01*
G03X1630630Y105458I-354J-187D01*
G02X1628753Y107375I-1230J673D01*
G03X1628772Y108074I-185J355D01*
G02X1628282Y108564I716J1206D01*
G03X1627583Y108544I-344J-204D01*
G02X1625615Y110392I-1244J647D01*
G03X1625606Y111082I-207J342D01*
G02X1625664Y113549I694J1218D01*
G03X1625672Y114258I-182J357D01*
G02X1625665Y116720I667J1233D01*
G03Y117422I-192J351D01*
G02X1625643Y119868I674J1229D01*
G03X1625649Y120559I-198J347D01*
G02X1625691Y122995I715J1206D01*
G03X1625685Y123700I-192J351D01*
G02X1625114Y124258I654J1240D01*
G03X1624415I-349J-194D01*
G02X1622508Y126165I-1225J682D01*
G03Y126864I-194J349D01*
G02X1621965Y127408I683J1224D01*
G03X1621265I-350J-194D01*
G02X1618815Y127407I-1225J681D01*
G03X1618116I-350J-194D01*
G02X1615666Y127408I-1225J682D01*
G03X1614966I-350J-194D01*
G02X1614436Y126872I-1225J681D01*
G03X1614425Y126184I199J-347D01*
G02X1614354Y123755I-735J-1194D01*
G03X1614366Y123045I190J-352D01*
G02X1614422Y120565I-625J-1255D01*
G03Y119865I194J-350D01*
G02X1614966Y119322I-680J-1226D01*
G03X1615665I350J195D01*
G02X1617524Y117391I1225J-681D01*
G03X1617515Y116682I181J-357D01*
G02X1617574Y114250I-667J-1233D01*
G03X1617583Y113560I207J-342D01*
G02X1615665Y111659I-693J-1219D01*
G03X1614966I-349J-194D01*
G02X1614422Y111116I-1224J683D01*
G03Y110416I194J-350D01*
G02X1614423Y107966I-681J-1225D01*
G03Y107267I194J-350D01*
G37*
G36*
G01X1464743Y358094D02*
G02X1462744Y358356I-1126J-835D01*
G03X1462816Y358907I-249J313D01*
G02X1462742Y359017I1125J837D01*
G03X1462092Y359067I-343J-206D01*
G02X1461366Y361323I-1076J898D01*
G03X1461851Y361819I100J387D01*
G02X1464431Y361528I1349J381D01*
G03X1464595Y360983I351J-192D01*
G02X1464815Y358645I-653J-1241D01*
G03X1464743Y358094I249J-313D01*
G37*
G36*
G01X1559790Y361274D02*
G02X1558147Y361257I-810J-1144D01*
G03X1558140Y361906I-238J322D01*
G02X1559783Y361923I810J1144D01*
G03X1559790Y361274I238J-322D01*
G37*
G36*
G01X110785Y128096D02*
G02X110826Y129597I-1163J783D01*
G03X111501Y129578I344J205D01*
G02X111460Y128077I1163J-783D01*
G03X110785Y128096I-344J-205D01*
G37*
G36*
G01X118581Y133842D02*
G03X119128Y133859I264J300D01*
G02X121151Y131918I989J-994D01*
G03X121155Y131373I295J-270D01*
G02X119191Y129374I-1017J-965D01*
G03X118646Y129369I-270J-295D01*
G02X116626Y131310I-964J1018D01*
G03X116620Y131843I-301J263D01*
G02X118581Y133842I1032J949D01*
G37*
G54D97*
X1950000Y220787D03*
Y228661D03*
G54D52*
X1037797Y608555D03*
Y551879D03*
Y570755D03*
Y514079D03*
Y532955D03*
Y88678D03*
Y69778D03*
Y31978D03*
Y-5822D03*
X388187Y608555D03*
Y551879D03*
Y589679D03*
Y570755D03*
Y514079D03*
Y532955D03*
Y88678D03*
Y69778D03*
Y31978D03*
Y-5822D03*
G54D64*
X11925Y74867D03*
X11864Y71294D03*
X11539Y39927D03*
X11500Y43400D03*
X44050Y504383D03*
X38389Y523748D03*
X27280Y510420D03*
X47550Y504367D03*
X1439Y546583D03*
X1539Y550183D03*
Y586183D03*
X1439Y582583D03*
X71500Y298000D03*
X66000Y292700D03*
X76800Y298000D03*
X76900Y292600D03*
X66500Y303400D03*
X76800D03*
X132959Y33700D03*
X163391D03*
X160431Y27899D03*
X130313D03*
X157084Y34100D03*
X153738Y27899D03*
X126580Y33700D03*
X123620Y27899D03*
X150391Y34100D03*
X147045Y27899D03*
X169770Y33700D03*
X167124Y27899D03*
X132959Y-4100D03*
X163391D03*
X160431Y-9901D03*
X163477Y12114D03*
X130313Y-9901D03*
X132959Y12114D03*
X157084Y-3700D03*
X153738Y-9901D03*
X157084Y12114D03*
X126580Y-4100D03*
X123620Y-9901D03*
X126666Y12114D03*
X150391Y-3700D03*
X147045Y-9901D03*
X150391Y12114D03*
X169770Y-4100D03*
X167124Y-9901D03*
X169770Y12114D03*
X132959Y71500D03*
X163391D03*
X160431Y65699D03*
X163477Y87714D03*
X130313Y65699D03*
X132959Y87714D03*
X157084Y71900D03*
X153738Y65699D03*
X157084Y87714D03*
X126580Y71500D03*
X123620Y65699D03*
X126666Y87714D03*
X150391Y71900D03*
X147045Y65699D03*
X150391Y87714D03*
X169770Y71500D03*
X167124Y65699D03*
X169770Y87714D03*
X163477Y49914D03*
X132959D03*
X157084D03*
X126666D03*
X150391D03*
X169770D03*
X125663Y230716D03*
X125563Y227116D03*
Y259116D03*
X125663Y262716D03*
Y294716D03*
X125563Y291116D03*
Y323116D03*
X125663Y326716D03*
X125563Y355116D03*
X125663Y358716D03*
Y390716D03*
X125563Y387116D03*
X163477Y513114D03*
X160431Y528899D03*
X132959Y513114D03*
X130313Y528899D03*
X153738D03*
X157084Y513114D03*
X123620Y528899D03*
X126666Y513114D03*
X150391D03*
X147045Y528899D03*
X167124D03*
X169770Y513114D03*
X132959Y534700D03*
X163391D03*
X157084Y535100D03*
X126580Y534700D03*
X150391Y535100D03*
X169770Y534700D03*
X132959Y572500D03*
X163391D03*
X163477Y550914D03*
X160431Y566699D03*
X132959Y550914D03*
X130313Y566699D03*
X157084Y572900D03*
Y550914D03*
X153738Y566699D03*
X126580Y572500D03*
X126666Y550914D03*
X123620Y566699D03*
X150391Y572900D03*
Y550914D03*
X147045Y566699D03*
X169770Y572500D03*
Y550914D03*
X167124Y566699D03*
X163477Y588714D03*
X132959D03*
X157084D03*
X126666D03*
X150391D03*
X169770D03*
X132959Y610300D03*
X163391D03*
X160431Y604499D03*
X130313D03*
X157084Y610700D03*
X153738Y604499D03*
X126580Y610300D03*
X123620Y604499D03*
X150391Y610700D03*
X147045Y604499D03*
X169770Y610300D03*
X167124Y604499D03*
X193895Y34100D03*
X190549Y27899D03*
X187202Y34100D03*
X183856Y27899D03*
X206581Y33700D03*
X203935Y27899D03*
X230706Y34100D03*
X227360Y27899D03*
X200202Y33700D03*
X197242Y27899D03*
X224013Y34100D03*
X220667Y27899D03*
X234053D03*
X193895Y-3700D03*
X190549Y-9901D03*
X193895Y12114D03*
X187202Y-3700D03*
X183856Y-9901D03*
X187202Y12114D03*
X206581Y-4100D03*
X203935Y-9901D03*
X206581Y12114D03*
X230706Y-3700D03*
X227360Y-9901D03*
X230706Y12114D03*
X200202Y-4100D03*
X197242Y-9901D03*
X200288Y12114D03*
X224013Y-3700D03*
X220667Y-9901D03*
X224013Y12114D03*
X234053Y-9901D03*
X193895Y71900D03*
X190549Y65699D03*
X193895Y87714D03*
X187202Y71900D03*
X183856Y65699D03*
X187202Y87714D03*
X206581Y71500D03*
X203935Y65699D03*
X206581Y87714D03*
X230706Y71900D03*
X227360Y65699D03*
X230706Y87714D03*
X200202Y71500D03*
X197242Y65699D03*
X200288Y87714D03*
X224013Y71900D03*
X220667Y65699D03*
X224013Y87714D03*
X234053Y65699D03*
X193895Y49914D03*
X187202D03*
X206581D03*
X230706D03*
X200288D03*
X224013D03*
X234053Y112327D03*
X193895Y513114D03*
X190549Y528899D03*
X183856D03*
X187202Y513114D03*
X206581D03*
X203935Y528899D03*
X227360D03*
X230706Y513114D03*
X200288D03*
X197242Y528899D03*
X220667D03*
X224013Y513114D03*
X234053Y528899D03*
X233292Y498500D03*
X193895Y535100D03*
X187202D03*
X206581Y534700D03*
X230706Y535100D03*
X200202Y534700D03*
X224013Y535100D03*
X193895Y572900D03*
Y550914D03*
X190549Y566699D03*
X187202Y572900D03*
Y550914D03*
X183856Y566699D03*
X206581Y572500D03*
Y550914D03*
X203935Y566699D03*
X230706Y572900D03*
Y550914D03*
X227360Y566699D03*
X200202Y572500D03*
X200288Y550914D03*
X197242Y566699D03*
X224013Y572900D03*
Y550914D03*
X220667Y566699D03*
X234053D03*
X193895Y588714D03*
X187202D03*
X206581D03*
X230706D03*
X200288D03*
X224013D03*
X193895Y610700D03*
X190549Y604499D03*
X187202Y610700D03*
X183856Y604499D03*
X206581Y610300D03*
X203935Y604499D03*
X230706Y610700D03*
X227360Y604499D03*
X200202Y610300D03*
X197242Y604499D03*
X224013Y610700D03*
X220667Y604499D03*
X234053D03*
X243392Y33700D03*
X240746Y27899D03*
X267517Y34100D03*
X264171Y27899D03*
X237013Y33700D03*
X260824Y34100D03*
X257478Y27899D03*
X280203Y33700D03*
X277557Y27899D03*
X273824Y33700D03*
X270864Y27899D03*
X294289D03*
X243392Y-4100D03*
X240746Y-9901D03*
X243392Y12114D03*
X267517Y-3700D03*
X264171Y-9901D03*
X267517Y12114D03*
X237013Y-4100D03*
X237099Y12114D03*
X260824Y-3700D03*
X257478Y-9901D03*
X260824Y12114D03*
X280203Y-4100D03*
X277557Y-9901D03*
X280203Y12114D03*
X273824Y-4100D03*
X270864Y-9901D03*
X273910Y12114D03*
X294289Y-9901D03*
X243392Y71500D03*
X240746Y65699D03*
X243392Y87714D03*
X267517Y71900D03*
X264171Y65699D03*
X267517Y87714D03*
X237013Y71500D03*
X237099Y87714D03*
X260824Y71900D03*
X257478Y65699D03*
X260824Y87714D03*
X280203Y71500D03*
X277557Y65699D03*
X280203Y87714D03*
X273824Y71500D03*
X270864Y65699D03*
X273910Y87714D03*
X294289Y65699D03*
X243392Y49914D03*
X267517D03*
X237099D03*
X260824D03*
X280203D03*
X273910D03*
X240746Y112327D03*
X243392Y106934D03*
X264171Y112327D03*
X267517Y107284D03*
X237099D03*
X257478Y112327D03*
X260824Y107284D03*
X277557Y112327D03*
X280203Y106934D03*
X270864Y112327D03*
X273910Y107284D03*
X294889Y110927D03*
X240746Y528899D03*
X243392Y513114D03*
X264171Y528899D03*
X267517Y513114D03*
X237099D03*
X257478Y528899D03*
X260824Y513114D03*
X280203D03*
X277557Y528899D03*
X273910Y513114D03*
X270864Y528899D03*
X294289D03*
X239592Y495900D03*
X243392Y495694D03*
X264171Y498487D03*
X267584Y493919D03*
X236892Y490800D03*
X257478Y498487D03*
X260824Y493744D03*
X277557Y498644D03*
X280203Y493244D03*
X271092Y498644D03*
X273992Y493744D03*
X294392Y493100D03*
X243392Y534700D03*
X267517Y535100D03*
X237013Y534700D03*
X260824Y535100D03*
X280203Y534700D03*
X273824D03*
X243392Y572500D03*
Y550914D03*
X240746Y566699D03*
X267517Y572900D03*
Y550914D03*
X264171Y566699D03*
X237013Y572500D03*
X237099Y550914D03*
X260824Y572900D03*
Y550914D03*
X257478Y566699D03*
X280203Y572500D03*
Y550914D03*
X277557Y566699D03*
X273824Y572500D03*
X273910Y550914D03*
X270864Y566699D03*
X294289D03*
X243392Y588714D03*
X267517D03*
X237099D03*
X260824D03*
X280203D03*
X273910D03*
X243392Y610300D03*
X240746Y604499D03*
X267517Y610700D03*
X264171Y604499D03*
X237013Y610300D03*
X260824Y610700D03*
X257478Y604499D03*
X280203Y610300D03*
X277557Y604499D03*
X273824Y610300D03*
X270864Y604499D03*
X294289D03*
X304328Y34100D03*
X300982Y27899D03*
X297635Y34100D03*
X321061Y-7108D03*
X327754Y-1743D03*
X324407Y-9901D03*
Y-4536D03*
X314368Y-7108D03*
X311021Y-4536D03*
X304328Y-3700D03*
X300982Y-9901D03*
X304328Y12114D03*
X297635Y-3700D03*
Y12114D03*
X334447Y-1743D03*
X331100Y-9786D03*
X354526Y-7108D03*
X354525Y-1742D03*
X351179Y-9901D03*
X347833Y-1743D03*
X344486Y-4536D03*
Y-9786D03*
X337793Y-4536D03*
X341140Y-7108D03*
X334447D03*
X304328Y71900D03*
X300982Y65699D03*
X304328Y87714D03*
X297635Y71900D03*
Y87714D03*
X304328Y49914D03*
X297635D03*
X300982Y109700D03*
X304178Y107684D03*
X297635Y105084D03*
X300982Y528899D03*
X304328Y513114D03*
X297635D03*
X301092Y493300D03*
X304392Y494700D03*
X297835Y494944D03*
X304328Y535100D03*
X297635D03*
X304328Y572900D03*
Y550914D03*
X300982Y566699D03*
X297635Y572900D03*
Y550914D03*
X304328Y588714D03*
X297635D03*
X321061Y607292D03*
X327754Y612457D03*
X324407Y604499D03*
Y609864D03*
X314368Y607292D03*
X311021Y609864D03*
X304328Y610700D03*
X300982Y604499D03*
X297635Y610700D03*
X334447Y612457D03*
X331100Y604614D03*
X354526Y607292D03*
X354525Y612358D03*
X351179Y604499D03*
X347833Y612357D03*
X344486Y609864D03*
Y604614D03*
X337793Y609864D03*
X341140Y607292D03*
X334447D03*
X398029Y28007D03*
X408069D03*
X404722Y-9901D03*
X401375Y-1743D03*
X414761Y-7108D03*
X398029Y-9901D03*
X404722Y-4536D03*
X414761Y-1743D03*
X408068Y-7108D03*
X394683Y-2200D03*
X398029Y65807D03*
X408069D03*
X398029Y529007D03*
X408069D03*
X394595Y537058D03*
X398029Y566807D03*
X408069D03*
X404722Y604499D03*
X401376Y612658D03*
X414761Y607292D03*
X398029Y604499D03*
X404722Y609864D03*
X414761Y612657D03*
X408068Y607292D03*
X394682Y612657D03*
X431494Y28007D03*
X460912Y33700D03*
X458266Y27899D03*
X481691D03*
X454533Y33700D03*
X451573Y27899D03*
X478344Y34100D03*
X474998Y27899D03*
X424801Y28007D03*
X438187Y-4536D03*
X431494Y-9901D03*
X444880Y-9786D03*
Y-4536D03*
X460912Y-4100D03*
X458266Y-9901D03*
X460912Y12114D03*
X481691Y-9901D03*
X454533Y-4100D03*
X451573Y-9901D03*
X454619Y12114D03*
X478344Y-3700D03*
X474998Y-9901D03*
X478344Y12114D03*
X428147Y-1743D03*
X421454Y-7108D03*
X434840Y-1743D03*
X424801Y-9786D03*
X438187D03*
X431494Y65807D03*
X460912Y71500D03*
X458266Y65699D03*
X460912Y87714D03*
X481691Y65699D03*
X454533Y71500D03*
X451573Y65699D03*
X454619Y87714D03*
X478344Y71900D03*
X474998Y65699D03*
X478344Y87714D03*
X424801Y65807D03*
X460912Y49914D03*
X454619Y49564D03*
X478344Y49914D03*
X460912Y513114D03*
X458266Y528899D03*
X481691D03*
X451573D03*
X454619Y513114D03*
X474998Y528899D03*
X478344Y513114D03*
X460912Y534700D03*
X454533D03*
X478344Y535100D03*
X431494Y566807D03*
X460912Y572500D03*
Y550914D03*
X458266Y566699D03*
X481691D03*
X454533Y572500D03*
X451573Y566699D03*
X454619Y550914D03*
X478344Y572900D03*
Y550914D03*
X474998Y566699D03*
X424801Y566807D03*
X460912Y588714D03*
X454619D03*
X478344D03*
X438187Y609864D03*
X431494Y604499D03*
X444880Y604614D03*
Y609864D03*
X460912Y610300D03*
X458266Y604499D03*
X481691D03*
X454533Y610300D03*
X451573Y604499D03*
X478344Y610700D03*
X474998Y604499D03*
X428147Y612657D03*
X421454Y607292D03*
X434840Y612657D03*
X424801Y604614D03*
X438187D03*
X485037Y34100D03*
X497723Y33700D03*
X495077Y27899D03*
X521848Y34100D03*
X518502Y27899D03*
X491344Y33700D03*
X488384Y27899D03*
X515155Y34100D03*
X511809Y27899D03*
X534534Y33700D03*
X531888Y27899D03*
X528155Y33700D03*
X525195Y27899D03*
X485037Y-3700D03*
Y12114D03*
X497723Y-4100D03*
X495077Y-9901D03*
X497723Y12114D03*
X521848Y-3700D03*
X518502Y-9901D03*
X521848Y12114D03*
X491344Y-4100D03*
X488384Y-9901D03*
X491430Y12114D03*
X515155Y-3700D03*
X511809Y-9901D03*
X515155Y12114D03*
X534534Y-4100D03*
X531888Y-9901D03*
X534534Y12114D03*
X528155Y-4100D03*
X525195Y-9901D03*
X528241Y12114D03*
X485037Y71900D03*
Y87714D03*
X497723Y71500D03*
X495077Y65699D03*
X497723Y87714D03*
X521848Y71900D03*
X518502Y65699D03*
X521848Y87714D03*
X491344Y71500D03*
X488384Y65699D03*
X491430Y87714D03*
X515155Y71900D03*
X511809Y65699D03*
X515155Y87714D03*
X534534Y71500D03*
X531888Y65699D03*
X534534Y87714D03*
X528155Y71500D03*
X525195Y65699D03*
X528241Y87714D03*
X485037Y49914D03*
X497723D03*
X521848D03*
X491430D03*
X515155D03*
X534534D03*
X528241D03*
X494927Y112357D03*
X497723Y106964D03*
X518317Y112357D03*
X521113Y106964D03*
X488634Y112357D03*
X491430Y106964D03*
X512024Y112357D03*
X514820Y106964D03*
X531888Y112357D03*
X534534Y106964D03*
X525134Y112357D03*
X528241Y107314D03*
X485037Y513114D03*
X497723D03*
X495077Y528899D03*
X521848Y513114D03*
X518502Y528899D03*
X488384D03*
X491430Y513114D03*
X511809Y528899D03*
X515155Y513114D03*
X534534D03*
X531888Y528899D03*
X528241Y513114D03*
X525195Y528899D03*
X494777Y498487D03*
X497723Y490894D03*
X517902Y498487D03*
X521048Y493844D03*
X488384Y498487D03*
X491430Y491144D03*
X511809Y498487D03*
X514755Y493744D03*
X530792Y498387D03*
X534534Y493394D03*
X524595Y498387D03*
X528191Y493544D03*
X485037Y535100D03*
X497723Y534700D03*
X521848Y535100D03*
X491344Y534700D03*
X515155Y535100D03*
X534534Y534700D03*
X528155D03*
X485037Y572900D03*
Y550914D03*
X497723Y572500D03*
Y550914D03*
X495077Y566699D03*
X521848Y572900D03*
Y550914D03*
X518502Y566699D03*
X491344Y572500D03*
X491430Y550914D03*
X488384Y566699D03*
X515155Y572900D03*
Y550914D03*
X511809Y566699D03*
X534534Y572500D03*
Y550914D03*
X531888Y566699D03*
X528155Y572500D03*
X528241Y550914D03*
X525195Y566699D03*
X485037Y588714D03*
X497723D03*
X521848D03*
X491430D03*
X515155D03*
X534534D03*
X528241D03*
X485037Y610700D03*
X498092Y611200D03*
X495077Y604499D03*
X521848Y610700D03*
X518502Y604499D03*
X491724Y611668D03*
X488384Y604499D03*
X515155Y610700D03*
X511809Y604499D03*
X534534Y610300D03*
X531888Y604499D03*
X528155Y610300D03*
X525195Y604499D03*
X558659Y34100D03*
X555313Y27899D03*
X551966Y34100D03*
X548620Y27899D03*
X571345Y33700D03*
X568699Y27899D03*
X595470Y34100D03*
X592124Y27899D03*
X564966Y33700D03*
X562006Y27899D03*
X588777Y34100D03*
X585431Y27899D03*
X558659Y-3700D03*
X555313Y-9901D03*
X558659Y12114D03*
X551966Y-3700D03*
X548620Y-9901D03*
X551966Y12114D03*
X571345Y-4100D03*
X568699Y-9901D03*
X571345Y12114D03*
X595470Y-3700D03*
X592124Y-9901D03*
X595470Y12114D03*
X564966Y-4100D03*
X562006Y-9901D03*
X565052Y12114D03*
X588777Y-3700D03*
X585431Y-9901D03*
X588777Y12114D03*
X558659Y71900D03*
X555313Y65699D03*
X558659Y87714D03*
X551966Y71900D03*
X548620Y65699D03*
X551966Y87714D03*
X571345Y71500D03*
X568699Y65699D03*
X571345Y87714D03*
X595470Y71900D03*
X592124Y65699D03*
X595470Y87714D03*
X564966Y71500D03*
X562006Y65699D03*
X565266Y87374D03*
X588777Y71900D03*
X585431Y65699D03*
X588777Y87714D03*
X558659Y49914D03*
X551966D03*
X571345D03*
X595470D03*
X565052D03*
X588777D03*
X555313Y112357D03*
X558659Y107314D03*
X548620Y112357D03*
X551966Y107314D03*
X558659Y513114D03*
X555313Y528899D03*
X548620D03*
X551966Y513114D03*
X571345D03*
X568699Y528899D03*
X595470Y513114D03*
X592124Y528899D03*
X562006D03*
X565266Y512774D03*
X588777Y513114D03*
X585431Y528899D03*
X554792Y498487D03*
X558659Y496144D03*
X548492Y498400D03*
X551366Y493344D03*
X558659Y535100D03*
X551966D03*
X571345Y534700D03*
X595470Y535100D03*
X564966Y534700D03*
X588777Y535100D03*
X558659Y572900D03*
Y550914D03*
X555313Y566699D03*
X551966Y572900D03*
Y550914D03*
X548620Y566699D03*
X571345Y572500D03*
Y550914D03*
X568699Y566699D03*
X595470Y572900D03*
Y550914D03*
X592124Y566699D03*
X564966Y572500D03*
X565266Y550574D03*
X562006Y566699D03*
X588777Y572900D03*
Y550914D03*
X585431Y566699D03*
X558659Y588714D03*
X551966D03*
X571345D03*
X595470D03*
X565052D03*
X588777D03*
X558659Y610700D03*
X555313Y604499D03*
X551966Y610700D03*
X548620Y604499D03*
X571345Y610300D03*
X568699Y604499D03*
X595470Y610700D03*
X592124Y604499D03*
X564966Y610300D03*
X562006Y604499D03*
X588777Y610700D03*
X585431Y604499D03*
X706500Y207800D03*
X706561Y211417D03*
X782567Y33700D03*
X779921Y27899D03*
X776188Y33700D03*
X773228Y27899D03*
X782567Y-4100D03*
Y12114D03*
X779921Y-9901D03*
X776188Y-4100D03*
X776274Y12114D03*
X773228Y-9901D03*
X782567Y71500D03*
X779921Y65699D03*
X782567Y87714D03*
X776188Y71500D03*
X773228Y65699D03*
X776274Y87714D03*
X782567Y49914D03*
X776274D03*
X775171Y234316D03*
X775271Y262716D03*
X775171Y259116D03*
X775271Y294716D03*
X775171Y291116D03*
X775271Y326716D03*
X775171Y323116D03*
X775271Y358716D03*
X775171Y355116D03*
X775221Y390716D03*
X775121Y387116D03*
X779921Y528899D03*
X782567Y513114D03*
X773228Y528899D03*
X776274Y513114D03*
X782567Y534700D03*
X776188D03*
X782567Y572500D03*
Y550914D03*
X779921Y566699D03*
X776188Y572500D03*
X776274Y550914D03*
X773228Y566699D03*
X782567Y588714D03*
X776274D03*
X782567Y610300D03*
X779921Y604499D03*
X776188Y610300D03*
X773228Y604499D03*
X843503Y34100D03*
X840157Y27899D03*
X812999Y33700D03*
X810039Y27899D03*
X836810Y34100D03*
X833464Y27899D03*
X849810Y33700D03*
X846850Y27899D03*
X806692Y34100D03*
X803346Y27899D03*
X799999Y34100D03*
X796653Y27899D03*
X819378Y33700D03*
X816732Y27899D03*
X843503Y-3700D03*
X840157Y-9901D03*
X843503Y12114D03*
X812999Y-4100D03*
X810039Y-9901D03*
X813085Y12114D03*
X836810Y-3700D03*
X833464Y-9901D03*
X836810Y12114D03*
X849810Y-4100D03*
X846850Y-9901D03*
X849896Y12114D03*
X806692Y-3700D03*
X803346Y-9901D03*
X806692Y12114D03*
X799999Y-3700D03*
X796653Y-9901D03*
X799999Y12114D03*
X819378Y-4100D03*
Y12114D03*
X816732Y-9901D03*
X843503Y71900D03*
X840157Y65699D03*
X843503Y87714D03*
X812999Y71500D03*
X810039Y65699D03*
X813085Y87714D03*
X836810Y71900D03*
X833464Y65699D03*
X836810Y87714D03*
X849810Y71500D03*
X846850Y65699D03*
X849896Y87714D03*
X806692Y71900D03*
X803346Y65699D03*
X806692Y87714D03*
X799999Y71900D03*
X796653Y65699D03*
X799999Y87714D03*
X819378Y71500D03*
X816732Y65699D03*
X819378Y87714D03*
X843503Y49914D03*
X813085D03*
X836810D03*
X849896D03*
X806692D03*
X799999D03*
X819378D03*
X840157Y528899D03*
X843503Y513114D03*
X813085D03*
X810039Y528899D03*
X833464D03*
X836810Y513114D03*
X849896D03*
X846850Y528899D03*
X806692Y513114D03*
X803346Y528899D03*
X799999Y513114D03*
X796653Y528899D03*
X816732D03*
X819378Y513114D03*
X843503Y535100D03*
X812999Y534700D03*
X836810Y535100D03*
X849810Y534700D03*
X806692Y535100D03*
X799999D03*
X819378Y534700D03*
X843503Y572900D03*
Y550914D03*
X840157Y566699D03*
X812999Y572500D03*
X813085Y550914D03*
X810039Y566699D03*
X836810Y572900D03*
Y550914D03*
X833464Y566699D03*
X849810Y572500D03*
X849896Y550914D03*
X846850Y566699D03*
X806692Y572900D03*
Y550914D03*
X803346Y566699D03*
X799999Y572900D03*
Y550914D03*
X796653Y566699D03*
X819378Y572500D03*
X816732Y566699D03*
X819378Y550914D03*
X843503Y588714D03*
X813085D03*
X836810D03*
X849896D03*
X806692D03*
X799999D03*
X819378D03*
X843503Y610700D03*
X840157Y604499D03*
X812999Y610300D03*
X810039Y604499D03*
X836810Y610700D03*
X833464Y604499D03*
X849810Y610300D03*
X846850Y604499D03*
X806692Y610700D03*
X803346Y604499D03*
X799999Y610700D03*
X796653Y604499D03*
X819378Y610300D03*
X816732Y604499D03*
X856189Y33700D03*
X853543Y27899D03*
X880314Y34100D03*
X876968Y27899D03*
X873621Y34100D03*
X870275Y27899D03*
X893000Y33700D03*
X890354Y27899D03*
X913779D03*
X886621Y33700D03*
X883661Y27899D03*
X910432Y34100D03*
X907086Y27899D03*
X856189Y-4100D03*
X853543Y-9901D03*
X856189Y12114D03*
X880314Y-3700D03*
X876968Y-9901D03*
X880314Y12114D03*
X873621Y-3700D03*
X870275Y-9901D03*
X873621Y12114D03*
X893000Y-4100D03*
Y12114D03*
X890354Y-9901D03*
X913779D03*
X886621Y-4100D03*
X886707Y12114D03*
X883661Y-9901D03*
X910432Y-3700D03*
X907086Y-9901D03*
X910432Y12114D03*
X856189Y71500D03*
X853543Y65699D03*
X856189Y87714D03*
X880314Y71900D03*
X876968Y65699D03*
X880314Y87714D03*
X873621Y71900D03*
X870275Y65699D03*
X873621Y87714D03*
X893000Y71500D03*
Y87714D03*
X890354Y65699D03*
X913779D03*
X886621Y71500D03*
X886707Y87714D03*
X883661Y65699D03*
X910432Y71900D03*
Y87714D03*
X907086Y65699D03*
X856189Y49914D03*
X880314D03*
X873621D03*
X893000D03*
X886707D03*
X910432D03*
X890354Y112327D03*
X893000Y106934D03*
X913779Y112327D03*
X883661D03*
X886707Y107284D03*
X907086Y112327D03*
X910432Y107284D03*
X853543Y528899D03*
X856189Y513114D03*
X876968Y528899D03*
X880314Y513114D03*
X870275Y528899D03*
X873621Y513114D03*
X890354Y528899D03*
X893000Y513114D03*
X913779Y528899D03*
X883661D03*
X886707Y513114D03*
X907086Y528899D03*
X910432Y513114D03*
X889200Y495900D03*
X893000Y495694D03*
X913779Y498487D03*
X882900Y498500D03*
X886500Y490800D03*
X907086Y498487D03*
X910432Y493744D03*
X856189Y534700D03*
X880314Y535100D03*
X873621D03*
X893000Y534700D03*
X886621D03*
X910432Y535100D03*
X856189Y572500D03*
Y550914D03*
X853543Y566699D03*
X880314Y572900D03*
X876968Y566699D03*
X880314Y550914D03*
X873621Y572900D03*
Y550914D03*
X870275Y566699D03*
X893000Y572500D03*
Y550914D03*
X890354Y566699D03*
X913779D03*
X886621Y572500D03*
X886707Y550914D03*
X883661Y566699D03*
X910432Y572900D03*
Y550914D03*
X907086Y566699D03*
X856189Y588714D03*
X880314D03*
X873621D03*
X893000D03*
X886707D03*
X910432D03*
X856189Y610300D03*
X853543Y604499D03*
X880314Y610700D03*
X876968Y604499D03*
X873621Y610700D03*
X870275Y604499D03*
X893000Y610300D03*
X890354Y604499D03*
X913779D03*
X886621Y610300D03*
X883661Y604499D03*
X910432Y610700D03*
X907086Y604499D03*
X917125Y34100D03*
X929811Y33700D03*
X927165Y27899D03*
X953936Y34100D03*
X950590Y27899D03*
X923432Y33700D03*
X920472Y27899D03*
X947243Y34100D03*
X943897Y27899D03*
X970669Y-7108D03*
X974015Y-9901D03*
Y-4536D03*
X963976Y-7108D03*
X960629Y-4536D03*
X917125Y-3700D03*
Y12114D03*
X929811Y-4100D03*
X927165Y-9901D03*
X929811Y12114D03*
X953936Y-3700D03*
X950590Y-9901D03*
X953936Y12114D03*
X923432Y-4100D03*
X920472Y-9901D03*
X923518Y12114D03*
X947243Y-3700D03*
X943897Y-9901D03*
X947243Y12114D03*
X917125Y71900D03*
Y87714D03*
X929811Y71500D03*
X927165Y65699D03*
X929811Y87714D03*
X953936Y71900D03*
X950590Y65699D03*
X953936Y87714D03*
X923432Y71500D03*
X920472Y65699D03*
X923518Y87714D03*
X947243Y71900D03*
X943897Y65699D03*
X947243Y87714D03*
X917125Y49914D03*
X929811D03*
X953936D03*
X923518D03*
X947243D03*
X917125Y107284D03*
X927165Y112327D03*
X929811Y106934D03*
X950590Y109700D03*
X953786Y107684D03*
X920472Y112327D03*
X923518Y107284D03*
X944497Y110927D03*
X947243Y105084D03*
X917125Y513114D03*
X927165Y528899D03*
X929811Y513114D03*
X950590Y528899D03*
X953936Y513114D03*
X920472Y528899D03*
X923518Y513114D03*
X943897Y528899D03*
X947243Y513114D03*
X917192Y493919D03*
X927165Y498644D03*
X929811Y493244D03*
X950700Y493300D03*
X954000Y494700D03*
X920700Y498644D03*
X923600Y493744D03*
X944000Y493100D03*
X947443Y494944D03*
X917125Y535100D03*
X929811Y534700D03*
X953936Y535100D03*
X923432Y534700D03*
X947243Y535100D03*
X917125Y572900D03*
Y550914D03*
X929811Y572500D03*
X927165Y566699D03*
X929811Y550914D03*
X953936Y572900D03*
Y550914D03*
X950590Y566699D03*
X923432Y572500D03*
X920472Y566699D03*
X923518Y550914D03*
X947243Y572900D03*
Y550914D03*
X943897Y566699D03*
X917125Y588714D03*
X929811D03*
X953936D03*
X923518D03*
X947243D03*
X970669Y607292D03*
X974015Y604499D03*
Y609864D03*
X963976Y607292D03*
X960629Y609864D03*
X917125Y610700D03*
X929811Y610300D03*
X927165Y604499D03*
X953936Y610700D03*
X950590Y604499D03*
X923432Y610300D03*
X920472Y604499D03*
X947243Y610700D03*
X943897Y604499D03*
X977362Y-1743D03*
X984055D03*
X980708Y-9786D03*
X1004134Y-7108D03*
X1004133Y-1742D03*
X1000787Y-9901D03*
X997441Y-1743D03*
X994094Y-4536D03*
Y-9786D03*
X987401Y-4536D03*
X990748Y-7108D03*
X984055D03*
X977362Y612457D03*
X984055D03*
X980708Y604614D03*
X1004134Y607292D03*
X1004133Y612358D03*
X1000787Y604499D03*
X997441Y612357D03*
X994094Y609864D03*
Y604614D03*
X987401Y609864D03*
X990748Y607292D03*
X984055D03*
X1081102Y28007D03*
X1047637D03*
X1057677D03*
X1074409D03*
X1054330Y-9901D03*
X1050983Y-1743D03*
X1087795Y-4536D03*
X1064369Y-7108D03*
X1081102Y-9901D03*
X1094488Y-9786D03*
Y-4536D03*
X1047637Y-9901D03*
X1054330Y-4536D03*
X1077755Y-1743D03*
X1064369D03*
X1071062Y-7108D03*
X1057676D03*
X1084448Y-1743D03*
X1074409Y-9786D03*
X1087795D03*
X1044291Y-2200D03*
X1081102Y65807D03*
X1047637D03*
X1057677D03*
X1074409D03*
X1047637Y529007D03*
X1057677D03*
X1044203Y537058D03*
X1081102Y566807D03*
X1047637D03*
X1057677D03*
X1074409D03*
X1054330Y604499D03*
X1050984Y612658D03*
X1087795Y609864D03*
X1064369Y607292D03*
X1081102Y604499D03*
X1094488Y604614D03*
Y609864D03*
X1047637Y604499D03*
X1054330Y609864D03*
X1077755Y612657D03*
X1064369D03*
X1071062Y607292D03*
X1057676D03*
X1084448Y612657D03*
X1074409Y604614D03*
X1087795D03*
X1044291Y612658D03*
X1110520Y33700D03*
X1107874Y27899D03*
X1134645Y34100D03*
X1131299Y27899D03*
X1104141Y33700D03*
X1101181Y27899D03*
X1127952Y34100D03*
X1124606Y27899D03*
X1147331Y33700D03*
X1144685Y27899D03*
X1140952Y33700D03*
X1137992Y27899D03*
X1110520Y-4100D03*
X1107874Y-9901D03*
X1110520Y12114D03*
X1134645Y-3700D03*
X1131299Y-9901D03*
X1134645Y12114D03*
X1104141Y-4100D03*
X1104227Y12114D03*
X1101181Y-9901D03*
X1127952Y-3700D03*
X1124606Y-9901D03*
X1127952Y12114D03*
X1147331Y-4100D03*
X1144685Y-9901D03*
X1147331Y12114D03*
X1140952Y-4100D03*
X1137992Y-9901D03*
X1141038Y12114D03*
X1110520Y71500D03*
X1107874Y65699D03*
X1110520Y87714D03*
X1134645Y71900D03*
X1131299Y65699D03*
X1134645Y87714D03*
X1104141Y71500D03*
X1101181Y65699D03*
X1104227Y87714D03*
X1127952Y71900D03*
X1124606Y65699D03*
X1127952Y87714D03*
X1147331Y71500D03*
X1144685Y65699D03*
X1147331Y87714D03*
X1140952Y71500D03*
X1137992Y65699D03*
X1141038Y87714D03*
X1110520Y49914D03*
X1134645D03*
X1104227Y49564D03*
X1127952Y49914D03*
X1147331D03*
X1141038D03*
X1144535Y112357D03*
X1147331Y106964D03*
X1138242Y112357D03*
X1141038Y106964D03*
X1107874Y528899D03*
X1110520Y513114D03*
X1131299Y528899D03*
X1134645Y513114D03*
X1104227D03*
X1101181Y528899D03*
X1124606D03*
X1127952Y513114D03*
X1147331D03*
X1144685Y528899D03*
X1141038Y513114D03*
X1137992Y528899D03*
X1144385Y498487D03*
X1147331Y490894D03*
X1137992Y498487D03*
X1141038Y491144D03*
X1110520Y534700D03*
X1134645Y535100D03*
X1104141Y534700D03*
X1127952Y535100D03*
X1147331Y534700D03*
X1140952D03*
X1110520Y572500D03*
Y550914D03*
X1107874Y566699D03*
X1134645Y572900D03*
Y550914D03*
X1131299Y566699D03*
X1104141Y572500D03*
X1104227Y550914D03*
X1101181Y566699D03*
X1127952Y572900D03*
Y550914D03*
X1124606Y566699D03*
X1147331Y572500D03*
Y550914D03*
X1144685Y566699D03*
X1140952Y572500D03*
X1141038Y550914D03*
X1137992Y566699D03*
X1110520Y588714D03*
X1134645D03*
X1104227D03*
X1127952D03*
X1147331D03*
X1141038D03*
X1110520Y610300D03*
X1107874Y604499D03*
X1134645Y610700D03*
X1131299Y604499D03*
X1104141Y610300D03*
X1101181Y604499D03*
X1127952Y610700D03*
X1124606Y604499D03*
X1147700Y611200D03*
X1144685Y604499D03*
X1141332Y611668D03*
X1137992Y604499D03*
X1171456Y34100D03*
X1168110Y27899D03*
X1164763Y34100D03*
X1161417Y27899D03*
X1184142Y33700D03*
X1181496Y27899D03*
X1208267Y34100D03*
X1204921Y27899D03*
X1177763Y33700D03*
X1174803Y27899D03*
X1201574Y34100D03*
X1198228Y27899D03*
X1220953Y33700D03*
X1218307Y27899D03*
X1214574Y33700D03*
X1211614Y27899D03*
X1171456Y-3700D03*
X1168110Y-9901D03*
X1171456Y12114D03*
X1164763Y-3700D03*
X1161417Y-9901D03*
X1164763Y12114D03*
X1184142Y-4100D03*
Y12114D03*
X1181496Y-9901D03*
X1208267Y-3700D03*
X1204921Y-9901D03*
X1208267Y12114D03*
X1177763Y-4100D03*
X1174803Y-9901D03*
X1177849Y12114D03*
X1201574Y-3700D03*
Y12114D03*
X1198228Y-9901D03*
X1220953Y-4100D03*
X1218307Y-9901D03*
X1220953Y12114D03*
X1214574Y-4100D03*
X1211614Y-9901D03*
X1214660Y12114D03*
X1171456Y71900D03*
X1168110Y65699D03*
X1171456Y87714D03*
X1164763Y71900D03*
X1161417Y65699D03*
X1164763Y87714D03*
X1184142Y71500D03*
Y87714D03*
X1181496Y65699D03*
X1208267Y71900D03*
Y87714D03*
X1204921Y65699D03*
X1177763Y71500D03*
X1174803Y65699D03*
X1177849Y87714D03*
X1201574Y71900D03*
Y87714D03*
X1198228Y65699D03*
X1220953Y71500D03*
Y87714D03*
X1218307Y65699D03*
X1214574Y71500D03*
X1214874Y87374D03*
X1211614Y65699D03*
X1171456Y49914D03*
X1164763D03*
X1184142D03*
X1208267D03*
X1177849D03*
X1201574D03*
X1220953D03*
X1214660D03*
X1167925Y112357D03*
X1170721Y106964D03*
X1161632Y112357D03*
X1164428Y106964D03*
X1181496Y112357D03*
X1184142Y106964D03*
X1204921Y112357D03*
X1208267Y107314D03*
X1174742Y112357D03*
X1177849Y107314D03*
X1198228Y112357D03*
X1201574Y107314D03*
X1171456Y513114D03*
X1168110Y528899D03*
X1161417D03*
X1164763Y513114D03*
X1181496Y528899D03*
X1184142Y513114D03*
X1208267D03*
X1204921Y528899D03*
X1174803D03*
X1177849Y513114D03*
X1201574D03*
X1198228Y528899D03*
X1220953Y513114D03*
X1218307Y528899D03*
X1214874Y512774D03*
X1211614Y528899D03*
X1167510Y498487D03*
X1170656Y493844D03*
X1161417Y498487D03*
X1164363Y493744D03*
X1180400Y498387D03*
X1184142Y493394D03*
X1204400Y498487D03*
X1208267Y496144D03*
X1174203Y498387D03*
X1177799Y493544D03*
X1198100Y498400D03*
X1200974Y493344D03*
X1171456Y535100D03*
X1164763D03*
X1184142Y534700D03*
X1208267Y535100D03*
X1177763Y534700D03*
X1201574Y535100D03*
X1220953Y534700D03*
X1214574D03*
X1171456Y572900D03*
Y550914D03*
X1168110Y566699D03*
X1164763Y572900D03*
Y550914D03*
X1161417Y566699D03*
X1184142Y572500D03*
Y550914D03*
X1181496Y566699D03*
X1208267Y572900D03*
Y550914D03*
X1204921Y566699D03*
X1177763Y572500D03*
X1177849Y550914D03*
X1174803Y566699D03*
X1201574Y572900D03*
Y550914D03*
X1198228Y566699D03*
X1220953Y572500D03*
Y550914D03*
X1218307Y566699D03*
X1214574Y572500D03*
X1214874Y550574D03*
X1211614Y566699D03*
X1171456Y588714D03*
X1164763D03*
X1184142D03*
X1208267D03*
X1177849D03*
X1201574D03*
X1220953D03*
X1214660D03*
X1171456Y610700D03*
X1168110Y604499D03*
X1164763Y610700D03*
X1161417Y604499D03*
X1184142Y610300D03*
X1181496Y604499D03*
X1208267Y610700D03*
X1204921Y604499D03*
X1177763Y610300D03*
X1174803Y604499D03*
X1201574Y610700D03*
X1198228Y604499D03*
X1220953Y610300D03*
X1218307Y604499D03*
X1214574Y610300D03*
X1211614Y604499D03*
X1245078Y34100D03*
X1241732Y27899D03*
X1238385Y34100D03*
X1235039Y27899D03*
X1245078Y-3700D03*
X1241732Y-9901D03*
X1245078Y12114D03*
X1238385Y-3700D03*
X1235039Y-9901D03*
X1238385Y12114D03*
X1245078Y71900D03*
Y87714D03*
X1241732Y65699D03*
X1238385Y71900D03*
Y87714D03*
X1235039Y65699D03*
X1245078Y49914D03*
X1238385D03*
X1241732Y528899D03*
X1245078Y513114D03*
X1238385D03*
X1235039Y528899D03*
X1245078Y535100D03*
X1238385D03*
X1245078Y572900D03*
Y550914D03*
X1241732Y566699D03*
X1238385Y572900D03*
Y550914D03*
X1235039Y566699D03*
X1245078Y588714D03*
X1238385D03*
X1245078Y610700D03*
X1241732Y604499D03*
X1238385Y610700D03*
X1235039Y604499D03*
X1374300Y377885D03*
Y381485D03*
X1375961Y569473D03*
X1376000Y565700D03*
X1400216Y560128D03*
X1375961Y600673D03*
X1375861Y597073D03*
X1375961Y593473D03*
X1523450Y612900D03*
X1519850Y613000D03*
X1487912Y611632D03*
X1484312Y611732D03*
X1590154Y354762D03*
X1594280Y472370D03*
X1681586Y141438D03*
X1693586Y142438D03*
X1689785Y161180D03*
X1688207Y168972D03*
X1788290Y612006D03*
X1842250Y90750D03*
X1885000Y227500D03*
X1934256Y99459D03*
X1909421Y208805D03*
G54D87*
X1643803Y570630D03*
X1646756Y565118D03*
Y580079D03*
Y610000D03*
X1643803Y600551D03*
Y615512D03*
X1691047Y570630D03*
X1694000Y565118D03*
Y580079D03*
Y610000D03*
X1691047Y600551D03*
Y615512D03*
G54D74*
X50500Y205696D03*
X108174Y164127D03*
X85609Y385234D03*
X123624Y164600D03*
X234501Y270392D03*
X224390Y258920D03*
X230800Y265200D03*
X219500Y254500D03*
X195300Y229250D03*
X219000Y335900D03*
X229100Y325900D03*
X224000Y330900D03*
X234000Y320900D03*
X214000Y340900D03*
X378294Y292904D03*
X605176Y487581D03*
X628589Y463649D03*
X641107Y471989D03*
X629359Y469583D03*
X710800Y7100D03*
X705250Y8600D03*
X818960Y202230D03*
X814849Y205001D03*
X808165Y203529D03*
X803134Y202969D03*
X792514Y201290D03*
X844400Y280500D03*
X845050Y229400D03*
X844350Y344000D03*
X889586Y274278D03*
X884586Y269278D03*
X879586Y264278D03*
X874586Y259278D03*
X869586Y254278D03*
X877008Y326100D03*
X867008Y336100D03*
X872008Y331100D03*
X862008Y341100D03*
X1028136Y309815D03*
X1017083Y309910D03*
X1301240Y476228D03*
X1431664Y190213D03*
X1463369Y561763D03*
X1490821Y73750D03*
X1567425Y144373D03*
X1573121Y120649D03*
X1591865Y237407D03*
X1570020Y295340D03*
X1569926Y308064D03*
X1576074Y359600D03*
X1590530Y610620D03*
X1608099Y197125D03*
X1608280Y249234D03*
X1598028Y256422D03*
X1600552Y261281D03*
X1640001Y370790D03*
X1644856Y604930D03*
X1640921Y605334D03*
X1680139Y99073D03*
X1695734Y164676D03*
X1663566Y213009D03*
X1687741Y466988D03*
X1759093Y9310D03*
X1761872Y-7220D03*
X1734875Y9238D03*
X1777000Y115750D03*
X1778000Y120000D03*
X1723189Y176012D03*
X1758324Y232657D03*
X1758000Y250000D03*
X1789356Y38286D03*
X1780720Y153850D03*
X1784750Y124000D03*
X1828390Y165600D03*
X1832000Y165800D03*
X1836396Y481349D03*
X1852654Y164624D03*
X1847654D03*
X1847000Y198600D03*
X1954271Y80449D03*
X1908400Y101010D03*
X1949389Y152083D03*
X1963092Y167936D03*
X1944550Y176450D03*
X1950981Y168064D03*
X1966700Y152400D03*
X251213Y646784D03*
Y652784D03*
X261125Y646784D03*
Y652784D03*
X389473Y646508D03*
Y652508D03*
X379561Y646508D03*
Y652508D03*
X448593Y652514D03*
Y646514D03*
X438681D03*
Y652514D03*
X567029Y652238D03*
Y646238D03*
X576941D03*
Y652238D03*
X951795Y652234D03*
Y646234D03*
X941883D03*
Y652234D03*
X1196198Y652206D03*
Y646206D03*
X1206110D03*
Y652206D03*
X1265293Y652264D03*
Y646264D03*
X1255381D03*
Y652264D03*
X1509696Y652236D03*
Y646236D03*
X1519608D03*
Y652236D03*
G54D99*
X1912406Y518328D03*
X1904532D03*
G54D69*
X10512Y467244D03*
X20512D03*
X50512D03*
X1884100Y493000D03*
X1894100D03*
X1891086Y592105D03*
Y612105D03*
Y602105D03*
X1904100Y493000D03*
G54D89*
X1779504Y-15000D03*
G54D79*
X1392264Y23976D03*
X1513918D03*
G54D65*
X-10236Y116969D03*
X-4725D03*
X23228Y124843D03*
X17716D03*
X-10236Y132717D03*
X-4725D03*
X6299D03*
X11811D03*
X17716Y140591D03*
X23228D03*
X-10236Y373110D03*
X-4725D03*
X23228Y380984D03*
X17716D03*
X-10236Y388858D03*
X-4725D03*
X6299D03*
X11811D03*
X17716Y396732D03*
X23228D03*
G54D81*
X1527844Y80791D03*
X1724606Y235430D03*
G54D96*
X1892720Y525415D03*
X1900595D03*
X1894689Y518328D03*
X1908469Y525415D03*
X1916343D03*
X1924217D03*
G54D84*
X1627642Y-14488D03*
X1647327Y-315D03*
X1667012Y-14488D03*
X1969291Y486064D03*
Y497874D03*
G54D49*
X1630386Y413942D03*
X1634400Y412900D03*
X1630120Y418887D03*
X1621347Y415297D03*
X1603000Y422971D03*
X1611418D03*
X1673800Y201070D03*
X1681352Y196092D03*
X1469000Y345850D03*
X-19210Y162529D03*
X-17014Y455604D03*
X-17200Y510800D03*
X-17302Y506798D03*
X-13500Y486400D03*
X-14800Y526100D03*
X-18160Y522609D03*
X-19802Y476738D03*
X-19783Y481286D03*
X-16186Y519304D03*
X-12600Y578900D03*
X-14971Y540000D03*
X-17500Y574000D03*
X8660Y27274D03*
X43960Y20572D03*
X-3560Y34620D03*
X-10850Y30800D03*
X2871Y22791D03*
X19964Y18793D03*
X2934Y26933D03*
X16550Y18300D03*
X602Y30502D03*
X25827Y-16958D03*
X8988Y58267D03*
X-1750Y43320D03*
X-1920Y47290D03*
X-1470Y63910D03*
X37037Y138425D03*
X39109Y154901D03*
X5120Y276058D03*
X2269Y273532D03*
X48550Y301650D03*
X1500Y295000D03*
X47100Y327000D03*
X49200Y340650D03*
X10365Y461602D03*
X37550Y425400D03*
X40965Y429434D03*
X2450Y460000D03*
X-9600Y526100D03*
X-6650Y487800D03*
X-5680Y524570D03*
X47800Y487600D03*
X3354Y517143D03*
X6748Y517021D03*
X-6200Y505400D03*
X-6676Y501800D03*
X10932Y523601D03*
X14700Y517000D03*
X-9900Y486400D03*
X-2430Y524340D03*
X-7360Y512000D03*
X-6712Y515731D03*
X-2083Y513704D03*
X-4350Y482100D03*
X-900Y482300D03*
X22491Y500618D03*
X2350Y469650D03*
X-8318Y542216D03*
X-8200Y578600D03*
X-3100Y533991D03*
X-2500Y569500D03*
X-10947Y544117D03*
X-4300Y558400D03*
X-4100Y554400D03*
X-9287Y531604D03*
X-6566Y568363D03*
X-9291Y535201D03*
X-9283Y571324D03*
X-4500Y594000D03*
X93500Y-18000D03*
X82300Y-16600D03*
X53382Y-1173D03*
X52744Y-4368D03*
X74386Y-18439D03*
X71172Y-18486D03*
X87091Y-16391D03*
X106000Y17260D03*
X52389Y-14258D03*
X60035Y7508D03*
X51090Y8080D03*
X54307Y-8051D03*
X104500Y-1850D03*
X76106Y89337D03*
X86600Y94000D03*
X70980Y97166D03*
X105898Y55194D03*
X82046Y90043D03*
X98420Y112198D03*
X99250Y160370D03*
X104424Y110833D03*
X87200Y152374D03*
X91913Y121318D03*
X77790Y121030D03*
X79670Y132300D03*
X75660Y152380D03*
X78950Y152810D03*
X91306Y157194D03*
X61800Y191600D03*
X76143Y183019D03*
X61356Y181000D03*
X61256Y186000D03*
X90831Y184982D03*
X86731Y189148D03*
X107700Y211040D03*
X104820Y202100D03*
X102507Y211047D03*
X79300Y272300D03*
X84000Y272500D03*
X99500Y223800D03*
X97200Y265000D03*
X99758Y240300D03*
X91600Y278700D03*
X70700Y330349D03*
X93500Y289000D03*
X58400Y314600D03*
X53000Y323500D03*
X52804Y333247D03*
X61300Y328600D03*
X93500Y285000D03*
X93400Y296000D03*
X53400Y298100D03*
X79410Y331636D03*
X84000Y324542D03*
X53100Y327000D03*
X64700Y310525D03*
X69125Y310625D03*
X84300Y305700D03*
Y310700D03*
X66300Y285850D03*
X72904Y284898D03*
X84300Y289000D03*
X82050Y283951D03*
X77103Y283900D03*
X88000Y343900D03*
X88600Y302997D03*
X94360Y335210D03*
X82500Y341400D03*
X103500Y304700D03*
X104600Y316602D03*
X103500Y308500D03*
X84866Y294213D03*
X79400Y325400D03*
X84300Y299000D03*
X87400Y337200D03*
X103200Y330190D03*
X88840Y324740D03*
X53100Y315000D03*
X53250Y302800D03*
X102322Y295478D03*
X66900Y322000D03*
X60400Y355750D03*
X57395Y366795D03*
X55500Y371700D03*
X109500Y370000D03*
X61914Y368731D03*
X57800Y376100D03*
X60565Y380131D03*
X65000Y383000D03*
X74800Y379700D03*
X80200D03*
X62600Y375100D03*
X87900Y347500D03*
X93712Y380507D03*
X97472Y380934D03*
X90518Y388828D03*
X110452Y407092D03*
X79100Y347000D03*
X61041Y351737D03*
X74800Y383114D03*
X66016Y468350D03*
X106392Y527413D03*
X59731Y480066D03*
X71050Y478670D03*
X86100Y505200D03*
X105392Y566000D03*
X102236Y614167D03*
X106192Y604600D03*
X114680Y17320D03*
X116070Y35780D03*
X114050Y21320D03*
X116692Y-1800D03*
X116300Y-9460D03*
X116200Y70387D03*
X115980Y73680D03*
X117600Y193805D03*
X122542Y214019D03*
X150000Y194850D03*
Y199850D03*
X162800Y195600D03*
X162788Y200650D03*
X124340Y197750D03*
X122203Y246675D03*
X122400Y278671D03*
X122361Y342649D03*
X122493Y310633D03*
X122473Y374716D03*
X153392Y404000D03*
X167640Y404842D03*
X118220Y360500D03*
X151909Y413267D03*
X148409Y422239D03*
X153392Y407500D03*
X167680Y408440D03*
X157862Y416012D03*
X150650Y409860D03*
X116927Y517900D03*
X113692Y566000D03*
X119892Y536983D03*
Y574700D03*
X114150Y585850D03*
X114509Y575658D03*
X116927Y555700D03*
X115883Y548024D03*
X114792Y604600D03*
X119892Y612583D03*
X116927Y593500D03*
X206600Y372400D03*
X274619Y205210D03*
X271239Y207159D03*
X277999Y218860D03*
X281379Y216909D03*
X284759Y218860D03*
X294899Y216909D03*
Y220809D03*
X288139D03*
X284759Y203260D03*
Y211060D03*
X294899Y205210D03*
Y209109D03*
X281379Y205210D03*
Y209109D03*
X291519Y203260D03*
Y211060D03*
X288139Y201309D03*
Y213009D03*
Y205210D03*
Y209109D03*
X267859D03*
X277999Y199360D03*
X274619Y201309D03*
X271239Y203260D03*
X294899Y197409D03*
X274619Y209109D03*
X264179Y257860D03*
X281379Y228610D03*
X288139Y224709D03*
X271239Y257860D03*
X284759Y230559D03*
X288139Y228610D03*
X277999Y222760D03*
X264092Y242260D03*
X271239D03*
X264179Y261760D03*
X271239D03*
X264179Y246160D03*
X271239D03*
Y250060D03*
X277999Y226660D03*
X271239Y253960D03*
X267859Y248109D03*
X281379Y224709D03*
X284759Y222760D03*
X267859Y255909D03*
X281379Y267609D03*
X277999Y238360D03*
X281379Y236409D03*
X284759Y250060D03*
X288139Y248109D03*
X277999Y242260D03*
X284759Y238360D03*
X288139Y263709D03*
X277999Y257860D03*
X281379Y255909D03*
X284759Y269560D03*
X288139Y267609D03*
X277999Y261760D03*
X284759Y257860D03*
X281379Y248109D03*
X288139Y244209D03*
Y259809D03*
X277999Y246160D03*
X288139Y240309D03*
X277999Y265660D03*
X284759Y261760D03*
X281379Y244209D03*
X284759Y242260D03*
X281379Y263709D03*
X294899Y232509D03*
Y236409D03*
Y252009D03*
Y255909D03*
Y240309D03*
Y259809D03*
X239778Y274478D03*
X271239Y277360D03*
Y281260D03*
X267392Y276000D03*
X267359Y279310D03*
Y283209D03*
X288139Y279310D03*
X284759Y281260D03*
X291519D03*
X277999D03*
X274619Y279310D03*
Y283209D03*
X288139D03*
X281379Y279310D03*
Y283209D03*
X294899D03*
Y279310D03*
X267859Y271509D03*
X264179Y273460D03*
X274619Y271509D03*
X294899D03*
Y267609D03*
X291519Y273460D03*
X277999D03*
X271239Y335860D03*
X264179D03*
X271239Y331960D03*
X264179D03*
X271239Y343660D03*
Y339760D03*
X267859Y345609D03*
Y337809D03*
X288139Y333909D03*
X281379Y330009D03*
Y341709D03*
X277999Y339760D03*
X288139Y330009D03*
X284759Y328060D03*
Y339760D03*
X277999Y335860D03*
Y331960D03*
X284759Y335860D03*
X281379Y333909D03*
X288139Y337809D03*
X294899Y341709D03*
Y337809D03*
X271239Y320260D03*
Y324160D03*
X270939Y316160D03*
X267359Y318309D03*
X267859Y326110D03*
X267392Y322000D03*
X270892Y304660D03*
Y311960D03*
Y300760D03*
Y308560D03*
Y292959D03*
Y289060D03*
Y285500D03*
Y296860D03*
X281379Y302709D03*
X288139D03*
X294899D03*
X291519Y304660D03*
X281379Y306609D03*
Y310509D03*
X288139Y306609D03*
Y310509D03*
X284759Y304660D03*
X294899Y310509D03*
Y306609D03*
X281379Y287109D03*
X288139Y291009D03*
X284759Y289060D03*
X291519D03*
Y296860D03*
X288139Y298809D03*
X274619Y306609D03*
Y310509D03*
X277999Y304660D03*
X274619Y302709D03*
Y298809D03*
Y294909D03*
X277999Y289060D03*
X274619Y287109D03*
Y291009D03*
X277999Y296860D03*
X288139Y287109D03*
X281379Y298809D03*
Y294909D03*
X288139D03*
X284759Y296860D03*
X281379Y291009D03*
X294899Y298809D03*
Y294909D03*
Y291009D03*
Y287109D03*
X291519Y312460D03*
X284759D03*
X277999D03*
X274619Y314409D03*
X294899D03*
X281379D03*
X288139D03*
X274619Y318309D03*
X291519Y320260D03*
X284759D03*
X288139Y322209D03*
X281379D03*
X291519Y324160D03*
X277999D03*
X294899Y326109D03*
Y330009D03*
X288139Y372909D03*
X281379Y369010D03*
Y380709D03*
X277999Y378760D03*
X288139Y369010D03*
X284759Y367060D03*
Y378760D03*
X277999Y374860D03*
X294899Y376809D03*
Y380709D03*
X264179Y351460D03*
X271239D03*
X264179Y347560D03*
X271239D03*
X284759Y374860D03*
X277999Y370959D03*
X288139Y376809D03*
X281379Y372909D03*
X284759Y359260D03*
X281379Y361209D03*
X288139Y349509D03*
X284759Y347560D03*
X277999Y355360D03*
Y359260D03*
X284759Y386560D03*
Y394359D03*
X294899Y388509D03*
Y392410D03*
X281379Y388509D03*
Y392410D03*
X291519Y386560D03*
Y394359D03*
X288139Y353409D03*
X281379Y349509D03*
X284759Y355360D03*
X288139Y388509D03*
X277999Y351460D03*
X288139Y396309D03*
Y357309D03*
Y384609D03*
X281379Y353409D03*
X288139Y392410D03*
X294899Y361209D03*
Y365109D03*
Y345609D03*
Y357309D03*
X274619Y400209D03*
X281379D03*
X271239Y394359D03*
X267859Y392410D03*
X294899Y400209D03*
X271239Y398260D03*
X277999D03*
X274619Y396309D03*
X308157Y-7180D03*
X307675Y28014D03*
X321061D03*
X327754Y35957D03*
X324407Y28014D03*
Y35957D03*
X314368Y28014D03*
X311021Y35957D03*
X334447D03*
X331100Y28014D03*
X354525Y28022D03*
X354526Y35957D03*
X351179Y28022D03*
X347833Y35957D03*
X344486D03*
Y28022D03*
X337793Y35957D03*
X341140Y28022D03*
X334446Y28014D03*
X321061Y-1743D03*
X314368Y-1843D03*
X331100Y-4536D03*
X327754Y-7108D03*
X317714Y-9786D03*
X311021D03*
X321061Y9114D03*
X311021Y28014D03*
X321061Y35957D03*
X314368D03*
X317714Y28014D03*
X311021Y17057D03*
X317714D03*
X327754D03*
Y28014D03*
X347833Y-7108D03*
X357872Y-9786D03*
X351179Y9122D03*
X341140Y-1743D03*
X337793Y-9901D03*
X357872Y-1858D03*
X341140Y9122D03*
X347833Y17057D03*
X341140Y35957D03*
X337793Y17057D03*
Y28014D03*
X357872D03*
Y17014D03*
X351179Y35957D03*
X347833Y28022D03*
X351179Y-4536D03*
X331100Y35957D03*
Y9114D03*
X314368D03*
X317714Y35957D03*
Y-4536D03*
Y9114D03*
X307928Y67802D03*
X321061Y65814D03*
X327754Y73757D03*
X324407Y65814D03*
Y73757D03*
X314368Y65814D03*
X334447Y73757D03*
X331100Y65814D03*
X354525Y65822D03*
X354526Y73757D03*
X351179Y65822D03*
X347833Y73757D03*
X344486D03*
Y65822D03*
X337793Y73757D03*
X341140Y65822D03*
X334446Y65814D03*
X311021D03*
X317714D03*
X314368Y46914D03*
X321061D03*
X331100D03*
X327754Y65814D03*
Y54857D03*
X331100Y73757D03*
X314368D03*
X321061D03*
X337793Y65814D03*
Y54857D03*
X351179Y46922D03*
X347833Y54857D03*
X357872Y65736D03*
X341140Y46922D03*
X351179Y73757D03*
X358491Y73479D03*
X341140Y73757D03*
X357872Y46914D03*
X347833Y65822D03*
X317714Y54857D03*
X311021D03*
X317714Y73757D03*
Y46914D03*
X313637Y105725D03*
X342218Y205210D03*
X298279Y214960D03*
X308418Y216909D03*
Y220809D03*
X305039Y214960D03*
X301659Y213009D03*
Y216909D03*
Y220809D03*
X345598Y207159D03*
X342218Y209109D03*
X348978Y205210D03*
Y216909D03*
X352357Y218860D03*
X345598D03*
X342218Y213009D03*
X338838Y214960D03*
X359117Y211060D03*
Y218860D03*
X355737Y216909D03*
Y213009D03*
X357987Y193507D03*
X338838Y218860D03*
X345598Y214960D03*
X352357D03*
X345598Y203260D03*
X355737Y205210D03*
X342218Y216909D03*
X335458Y220809D03*
X338838Y207158D03*
Y203258D03*
X345598Y211060D03*
X348978Y213009D03*
X338838Y250060D03*
Y230560D03*
X298279Y222760D03*
X305039D03*
X328698Y236409D03*
X301659Y224709D03*
X328698Y248109D03*
Y240309D03*
Y244209D03*
X325318Y238360D03*
Y246160D03*
X335458Y240309D03*
Y244209D03*
X321938Y240309D03*
Y244209D03*
X332078Y238360D03*
Y246160D03*
X342218Y224709D03*
X345598Y230559D03*
X338838Y222760D03*
X352357D03*
X348978Y224709D03*
X355737D03*
X348978Y228610D03*
X352357Y230559D03*
X348978Y236409D03*
Y240309D03*
X352357Y234460D03*
X345598Y242260D03*
Y234460D03*
X342218Y240309D03*
Y228610D03*
Y236409D03*
X298279Y261760D03*
Y230559D03*
X301659Y244209D03*
X305039Y242260D03*
X301659Y232509D03*
X311798Y230559D03*
X318558Y234460D03*
Y222760D03*
X321938Y224709D03*
X305039Y257860D03*
X311798Y234460D03*
X315178Y236409D03*
Y224709D03*
X321938Y228610D03*
X328698Y255909D03*
Y263709D03*
X338838Y257860D03*
Y261760D03*
X325318Y257860D03*
Y261760D03*
X335458Y255909D03*
Y263709D03*
X298279Y250060D03*
X301659Y263709D03*
X305039Y261760D03*
X301659Y252009D03*
X298279Y242260D03*
X305039Y238360D03*
Y253960D03*
X311798Y226660D03*
X332078Y253960D03*
X315178Y263709D03*
X305039Y234460D03*
X321938Y232509D03*
X332078Y265660D03*
X315178Y275409D03*
X301659Y255909D03*
X298279Y238360D03*
X315178Y228610D03*
X332078Y257860D03*
X315178Y267609D03*
X301659Y236409D03*
X318558Y230559D03*
X332078Y261760D03*
X315178Y271509D03*
X298279Y257860D03*
X311798Y265660D03*
Y273460D03*
X321938Y267609D03*
Y271509D03*
X308418Y267609D03*
Y271509D03*
X318558Y265660D03*
Y273460D03*
X352357Y246160D03*
X345598D03*
X359117Y230559D03*
X355737Y228610D03*
Y236409D03*
X352357Y242260D03*
X355737Y240309D03*
X301659Y279310D03*
X298279Y281260D03*
X308418Y283209D03*
X305039Y281260D03*
X308418Y279310D03*
X311798Y281260D03*
X301659Y283209D03*
X348978Y267609D03*
X357057Y277360D03*
Y281260D03*
X345598D03*
X348978Y283209D03*
X345598Y277360D03*
X348978Y279310D03*
Y275409D03*
Y271509D03*
X352357Y265660D03*
X355737Y263709D03*
X342218Y244209D03*
Y232509D03*
X355737Y244209D03*
X348978D03*
X345598Y226660D03*
X352357D03*
X348978Y232509D03*
X355737D03*
X345598Y222760D03*
X332078D03*
X328698Y224709D03*
X332078Y226660D03*
X335458Y228610D03*
X328698D03*
X332078Y230560D03*
X335458Y232510D03*
X311798Y242260D03*
X315178Y244209D03*
X311798Y246160D03*
X315178Y248109D03*
X308418D03*
X352357Y250060D03*
X345598D03*
X318558D03*
X355737Y252009D03*
X348978D03*
X321938D03*
X352357Y253960D03*
X345598D03*
X355737Y255909D03*
X348978D03*
X338838Y273460D03*
X345598Y261760D03*
X338838Y269560D03*
X332078Y273460D03*
X298279D03*
X335458Y275409D03*
X328698D03*
X338838Y277360D03*
X332078D03*
X325318D03*
X335458Y279310D03*
X328698D03*
X321938D03*
X335458Y271509D03*
X342218Y252009D03*
Y248109D03*
X301659Y271509D03*
X328698D03*
X298279Y269560D03*
X348978Y259809D03*
X345598Y257860D03*
X352357D03*
X348978Y337809D03*
X305039Y339760D03*
X298279Y335860D03*
X332078D03*
Y343660D03*
X342218Y337809D03*
Y341709D03*
X328698Y337809D03*
Y341709D03*
X338838Y335860D03*
Y343660D03*
X305039Y335860D03*
X301659Y333909D03*
X335458Y337809D03*
X318558Y328060D03*
Y335860D03*
X301659Y341709D03*
X298279Y339760D03*
X335458Y333909D03*
X318558Y324160D03*
X335458Y341709D03*
X318558Y331960D03*
X305039Y343660D03*
X315178Y326110D03*
Y333909D03*
X325318Y328060D03*
Y331960D03*
X311798Y328060D03*
Y331960D03*
X321938Y326110D03*
Y333909D03*
X308418Y306609D03*
X301659Y310509D03*
Y306609D03*
X311798Y304660D03*
X305039D03*
X321938Y306609D03*
X325318Y304660D03*
Y308560D03*
X298279Y304660D03*
X308418Y302709D03*
X301659D03*
X315178D03*
X321938D03*
X318558Y304660D03*
Y308560D03*
X321938Y291009D03*
X318558Y296860D03*
X315178Y294909D03*
X321938D03*
X301659D03*
X325318Y285160D03*
Y289060D03*
Y296860D03*
X298279D03*
Y289060D03*
X308418Y298809D03*
X301659D03*
X305039Y289060D03*
X308418Y291009D03*
Y287109D03*
X311798Y289060D03*
X308418Y294909D03*
X311798Y296860D03*
X305039D03*
X315178Y287109D03*
X318558Y285160D03*
X321938Y287109D03*
X301659D03*
Y291009D03*
X315178Y298809D03*
X321938D03*
X318558Y289060D03*
X315178Y291009D03*
X332078Y308560D03*
Y304660D03*
X328698Y302709D03*
Y306609D03*
Y287109D03*
Y291009D03*
Y294909D03*
Y298809D03*
X332078Y296860D03*
Y285160D03*
Y289060D03*
X315178Y306609D03*
X308418Y310509D03*
X311798Y312460D03*
X305039D03*
X298279D03*
X308418Y314409D03*
X301659D03*
X335458Y298809D03*
X357057Y296860D03*
X348978Y287109D03*
X345598Y285160D03*
X357057D03*
Y292959D03*
X348978Y298809D03*
Y291009D03*
X345598Y289060D03*
Y292959D03*
Y296860D03*
X348978Y294909D03*
X345598Y300760D03*
X348978Y302709D03*
X357057Y300760D03*
Y308560D03*
X348978Y306609D03*
X345598Y304660D03*
Y308560D03*
X348978Y310509D03*
X357057Y304660D03*
Y289060D03*
X342218Y302709D03*
Y306609D03*
Y291009D03*
Y287109D03*
Y294909D03*
Y298809D03*
X338838Y308560D03*
X335458Y302709D03*
X338838Y304660D03*
X335458Y306609D03*
Y287109D03*
X338838Y289060D03*
Y285160D03*
X335458Y291009D03*
X338838Y296860D03*
X335458Y294909D03*
X348978Y314409D03*
X357057Y312460D03*
X345598D03*
X357987Y327609D03*
X348978Y322209D03*
X355737Y333909D03*
X345598Y316360D03*
X348978Y318309D03*
Y330009D03*
X352357Y331960D03*
X348978Y326110D03*
X357057Y320260D03*
Y324160D03*
Y316360D03*
X328698Y314409D03*
X321938D03*
X332078Y328060D03*
X328698Y322209D03*
Y318309D03*
X332078Y324160D03*
Y320260D03*
Y316360D03*
X325318Y320260D03*
X305039D03*
X321938Y318309D03*
X315178D03*
X318558Y316360D03*
X301659Y322209D03*
X325318Y316360D03*
X305039Y324160D03*
X311798Y320260D03*
X308418Y322209D03*
X301659Y326110D03*
X335458Y314409D03*
Y326110D03*
Y318309D03*
Y322209D03*
X338838Y320260D03*
Y324160D03*
Y328060D03*
X298279Y324160D03*
Y320260D03*
X355737Y345609D03*
X348978Y341709D03*
X352357Y343660D03*
X321938Y341709D03*
X352357Y339760D03*
X321938Y345609D03*
X359117Y343660D03*
X355737Y341709D03*
X342218Y384609D03*
X341892Y396301D03*
X345598Y386560D03*
X298279Y374860D03*
Y382660D03*
X308418Y376809D03*
Y380709D03*
X305039Y374860D03*
Y382660D03*
X301659Y376809D03*
X328698Y353409D03*
X301659Y384609D03*
X328698Y361209D03*
X301659Y372909D03*
X328698Y349509D03*
X301659Y380709D03*
X328698Y357309D03*
X325318Y351460D03*
Y359260D03*
X335458Y353409D03*
Y357309D03*
X321938Y353409D03*
Y357309D03*
X332078Y351460D03*
Y359260D03*
X348978Y388509D03*
X342218Y380709D03*
X351192Y402800D03*
X345598Y378760D03*
X348978Y380709D03*
X345598Y367060D03*
X348978Y372909D03*
X342218D03*
X338838Y374860D03*
Y370959D03*
Y378760D03*
X352357D03*
Y374860D03*
X359117Y386560D03*
X355737Y380709D03*
X359117Y374860D03*
X355737Y372909D03*
X348978Y369010D03*
X352357Y367060D03*
X355737Y384609D03*
X345598Y355360D03*
X348978Y357309D03*
X345598Y351460D03*
X348978Y361209D03*
X345598Y363160D03*
X342218Y357309D03*
Y369010D03*
Y361209D03*
X301659Y365109D03*
X298279Y367060D03*
X305039Y355360D03*
X301659Y353409D03*
X318558Y363160D03*
X311798Y367060D03*
X321938Y372909D03*
X318558Y374860D03*
X315178Y361209D03*
X311798Y363160D03*
X321938Y369010D03*
X315178Y372909D03*
X298279Y347560D03*
X301659Y345609D03*
X305039Y359260D03*
X298279Y355360D03*
X301659Y361209D03*
X318558Y367060D03*
X311798Y370959D03*
X335458Y345609D03*
X305039Y363160D03*
X321938Y365109D03*
X298279Y359260D03*
X315178Y369010D03*
X352357Y351460D03*
Y363160D03*
X359117D03*
X355737Y361209D03*
Y369010D03*
X352357Y355360D03*
X355737Y357309D03*
X359117Y351460D03*
X345598Y370959D03*
X355737Y353409D03*
X348978D03*
X342218Y365109D03*
Y353409D03*
X338838Y367060D03*
X348978Y365109D03*
X355737D03*
X352357Y370959D03*
X338838Y382660D03*
X357987Y402800D03*
X345598Y382660D03*
X352357D03*
X348978Y392410D03*
X355737D03*
X315178Y349509D03*
Y353409D03*
X348978Y345609D03*
X311798Y355360D03*
Y347560D03*
Y351460D03*
X308418Y349509D03*
X342218D03*
X345598Y347560D03*
X315178Y384609D03*
X348978D03*
X315178Y380709D03*
X335458Y376809D03*
X332078Y374860D03*
X345598D03*
X328698Y372909D03*
X332078Y370959D03*
X328698Y369010D03*
X335458D03*
X332078Y367060D03*
X335458Y365109D03*
X338838Y363160D03*
X352357Y347560D03*
X321061Y529014D03*
X324407D03*
X331100D03*
X354525Y529022D03*
X351179D03*
X344486D03*
X341140D03*
X334446Y529014D03*
X317714D03*
X311701Y499136D03*
X327754Y529014D03*
X337793D03*
X357872Y528942D03*
X347833Y529022D03*
X327754Y536957D03*
X324407D03*
X311021D03*
X334447D03*
X354526D03*
X347833D03*
X344486D03*
X337793D03*
X321061Y566814D03*
X327754Y574757D03*
X324407Y566814D03*
Y574757D03*
X314368Y566814D03*
X311021Y574757D03*
X334447D03*
X331100Y566814D03*
X354525Y566822D03*
X354526Y574757D03*
X351179Y566822D03*
X347833Y574757D03*
X344486D03*
Y566822D03*
X337793Y574757D03*
X341140Y566822D03*
X334446Y566814D03*
X321061Y536957D03*
X331100Y547914D03*
Y536957D03*
X321061Y547914D03*
X314368D03*
Y536957D03*
X327754Y555857D03*
X317714D03*
X311021D03*
X327754Y566814D03*
X331100Y574757D03*
Y585714D03*
X314368D03*
Y574757D03*
X317714Y566814D03*
X321061Y585714D03*
Y574757D03*
X351179Y547922D03*
X357910Y536727D03*
X351179Y536957D03*
X341140Y547922D03*
Y536957D03*
X337793Y555857D03*
X347833D03*
X357910Y555842D03*
X337793Y566814D03*
X341140Y574757D03*
Y585722D03*
X351179Y574757D03*
X357872Y574742D03*
X347833Y566822D03*
X357910Y566814D03*
X351179Y585722D03*
X317714Y536957D03*
Y547914D03*
Y574757D03*
Y585714D03*
X308157Y607220D03*
X327754Y607292D03*
X331100Y609864D03*
X327754Y593657D03*
X317714D03*
X311021D03*
X317714Y604614D03*
X311021D03*
X314368Y612457D03*
X321061D03*
X337793Y593657D03*
Y604499D03*
X357872Y604614D03*
Y612242D03*
X352109Y609918D03*
X347833Y607292D03*
X341140Y612457D03*
X347833Y593657D03*
X317714Y609864D03*
X404723Y28022D03*
X401377Y35957D03*
X364565Y28014D03*
X361218D03*
X414762Y28021D03*
X404723Y35957D03*
X414763D03*
X394684D03*
X367911Y-9786D03*
Y-1858D03*
Y9114D03*
Y35942D03*
Y28014D03*
X398029Y-4536D03*
X401375Y-7108D03*
X408068Y-1743D03*
X418108Y-4536D03*
X411415Y-9786D03*
X418108Y-9701D03*
X408069Y35942D03*
X411416Y17057D03*
X401376Y17042D03*
X418108D03*
X398029Y35942D03*
X401377Y28022D03*
X418108Y28007D03*
X411416Y28022D03*
X418108Y35942D03*
Y9107D03*
X376700Y-1300D03*
X371258Y-1858D03*
Y-9800D03*
X411415Y36058D03*
Y-4536D03*
X374401Y-11346D03*
X394682Y17157D03*
X394492Y54700D03*
X404723Y65822D03*
X401377Y73757D03*
X414763Y65822D03*
X404723Y73757D03*
X414763D03*
X367911Y54842D03*
X366992Y65950D03*
X367742Y73450D03*
X401376Y54842D03*
X401377Y65822D03*
X411416D03*
Y54857D03*
X418108Y65807D03*
Y54842D03*
Y46907D03*
X398029Y73742D03*
X418108D03*
X408069D03*
X367911Y46914D03*
X380600Y37400D03*
X384992Y81600D03*
X411416Y73757D03*
X394682Y68492D03*
X372637Y207159D03*
X399676D03*
X372637Y211060D03*
X392916D03*
X389537Y213009D03*
X396296D03*
X369257D03*
X396296Y216909D03*
X376017D03*
X365877Y218860D03*
X372637D03*
X362497Y216909D03*
X382777Y213009D03*
X399676Y218860D03*
X386157Y211060D03*
X407706Y216909D03*
X415634Y220096D03*
Y216196D03*
X419214Y218147D03*
Y222047D03*
X379397Y207159D03*
X369257Y216909D03*
X382777D03*
X379397Y218860D03*
X392916D03*
X362497Y213009D03*
X386157Y218860D03*
X389537Y216909D03*
X376017Y213009D03*
X378267Y193507D03*
X386157Y207159D03*
X382777Y201309D03*
X365877Y214960D03*
X372637D03*
X379397D03*
X359117D03*
X365877Y203260D03*
X376017Y205211D03*
X362497Y205210D03*
X386157Y214960D03*
X404392Y199100D03*
X392898Y195041D03*
X392916Y214960D03*
Y203260D03*
X396296Y197359D03*
X399676Y203260D03*
Y214960D03*
Y211060D03*
X415634Y239596D03*
Y243496D03*
X419214Y245447D03*
X396296Y244209D03*
Y240309D03*
X376017Y224709D03*
X372637Y222760D03*
X365877D03*
X369257Y224709D03*
X362497D03*
X386157Y222760D03*
X396296Y228610D03*
X389537Y224709D03*
X399676Y222760D03*
X415634Y227896D03*
Y231797D03*
X419214Y225947D03*
Y229847D03*
X382777Y224709D03*
X379397Y222760D03*
X359117D03*
X392916D03*
X396296Y224709D03*
X379397Y230559D03*
X365877Y242260D03*
X407706Y236409D03*
X372637Y234460D03*
X365877D03*
X372637Y230559D03*
X365877D03*
X369257Y236409D03*
X362497D03*
X369257Y228610D03*
X362497D03*
X382777D03*
X389537Y236409D03*
X399676Y230559D03*
Y234460D03*
X382777Y236409D03*
X392916Y230559D03*
X407706Y224709D03*
Y228610D03*
X376017Y236409D03*
X369257Y240309D03*
X376017D03*
X386157Y230559D03*
X372637Y242260D03*
X379397Y234460D03*
X399676Y238360D03*
X359117Y242260D03*
X362497Y240309D03*
X359117Y234460D03*
Y246160D03*
X386157Y234460D03*
X392916D03*
X389537Y228610D03*
X396296Y236409D03*
X376017Y228610D03*
X372637Y253960D03*
X376017Y252009D03*
X368127Y264300D03*
X364747Y266300D03*
X362497Y259809D03*
X365877Y257860D03*
X369257Y255909D03*
X391787Y254259D03*
X388407Y256500D03*
X374887Y260300D03*
X385027Y254259D03*
X359117Y261760D03*
X371507Y262300D03*
X381647Y256400D03*
X378267Y258400D03*
X395166Y256400D03*
X418084Y253546D03*
X398546Y254259D03*
X405306Y254500D03*
X401926Y256500D03*
X386157Y226660D03*
X389537Y232509D03*
X369257Y244209D03*
X362497D03*
X372637Y226660D03*
X365877D03*
X369257Y232509D03*
X362497D03*
X379397Y226660D03*
X382777Y232509D03*
X376017D03*
X359117Y226660D03*
X407706Y240309D03*
Y232509D03*
X392916Y226660D03*
X396296Y232509D03*
X399676Y226660D03*
Y242260D03*
X362497Y248109D03*
X359117Y250060D03*
Y253960D03*
X389537Y240309D03*
X382777D03*
X392916Y242260D03*
X386157D03*
X379397D03*
X389537Y244209D03*
X382777D03*
X376017D03*
X392916Y246160D03*
X386157D03*
X379397D03*
X372637D03*
X365877D03*
X369257Y248109D03*
X365877Y250060D03*
X362497Y252009D03*
X407706Y244209D03*
X399676Y246160D03*
X388407Y345160D03*
X364747Y331509D03*
X361367Y329560D03*
X371507Y335409D03*
X362497Y337809D03*
X369257Y341709D03*
X368127Y333460D03*
X365877Y339760D03*
X372637Y343660D03*
X374887Y337360D03*
X381647Y341260D03*
X378267Y339309D03*
X385027Y343209D03*
X359117Y335860D03*
X395166Y345160D03*
X401926D03*
X407448Y338641D03*
X394648Y338341D03*
X362497Y345609D03*
X392916Y355360D03*
X396296Y357309D03*
X389537D03*
X372637Y390460D03*
X396296Y384609D03*
X372637Y386560D03*
X392916D03*
X389537Y384609D03*
X399676Y390460D03*
X376017Y372909D03*
X369257Y384609D03*
X396296Y380709D03*
X369257Y372909D03*
X362497D03*
X372637Y378760D03*
X362497Y380709D03*
X372637Y374860D03*
X365877D03*
X376017Y380709D03*
X365877Y378760D03*
X382777Y384609D03*
X386157Y374860D03*
X399676Y378760D03*
X396296Y369010D03*
X386157Y386560D03*
X389537Y372909D03*
X403056Y380709D03*
X399676Y374860D03*
X379397Y386560D03*
X369257Y380709D03*
X382777D03*
Y372909D03*
X379397Y378760D03*
Y374860D03*
X392916Y378760D03*
X362497Y384609D03*
X359117Y378760D03*
X386157D03*
X392916Y374860D03*
X389537Y380709D03*
X396296Y372909D03*
X376017Y384609D03*
X379397Y367060D03*
X365877Y355360D03*
X403056Y361209D03*
X369257Y369010D03*
X362497D03*
X369257Y361209D03*
X362497D03*
X372637Y367060D03*
X365877D03*
X372637Y363160D03*
X365877D03*
X382777Y369010D03*
X389537Y361209D03*
X399676Y367060D03*
Y363160D03*
X382777Y361209D03*
X392916Y367060D03*
X403056Y372909D03*
Y369010D03*
X376017Y361209D03*
X369257Y357309D03*
X376017D03*
X386157Y367060D03*
X372637Y355360D03*
X379397Y363160D03*
X399676Y359260D03*
X359117Y355360D03*
X362497Y357309D03*
X359117Y367060D03*
X386157Y363160D03*
X392916D03*
X389537Y369010D03*
X396296Y361209D03*
X376017Y369010D03*
X391787Y347109D03*
X398546D03*
X379397Y370959D03*
X372637D03*
X365877D03*
X359117D03*
X386157D03*
X362497Y353409D03*
X376017D03*
X369257D03*
X389537Y365109D03*
X382777D03*
X369257D03*
X362497D03*
X376017D03*
X390657Y394359D03*
X391787Y402800D03*
X369257Y392410D03*
X362497D03*
X379397Y382660D03*
X372637D03*
X365877D03*
X359117D03*
X379397Y390460D03*
X378267Y402800D03*
X376017Y392410D03*
X386157Y382660D03*
X392916Y370959D03*
X399676D03*
X396296Y365109D03*
X403056D03*
Y357309D03*
X392916Y382660D03*
Y390460D03*
X399676Y382660D03*
X406568Y402471D03*
X403056Y392410D03*
X411431Y359351D03*
X411086Y355360D03*
X403056Y353409D03*
X369257Y349509D03*
X399676Y355360D03*
X365877Y351460D03*
X372637D03*
X379397D03*
X362497Y349509D03*
X376017D03*
X382777Y353409D03*
X386157Y355360D03*
X403056Y396309D03*
X411086Y394359D03*
Y390460D03*
X399676Y386560D03*
X411086D03*
Y382660D03*
Y378760D03*
X398546Y402900D03*
X382777Y357309D03*
X379397Y355360D03*
X402892Y400400D03*
X365877Y347560D03*
X359117D03*
X404723Y529022D03*
X386630Y521860D03*
X367911Y529057D03*
X401377Y529022D03*
X418108Y529007D03*
X411416Y529022D03*
X394587Y529026D03*
X401377Y536957D03*
X404723D03*
X414763D03*
X404723Y566822D03*
X401377Y574757D03*
X414763Y566822D03*
X404723Y574757D03*
X414763D03*
X394684D03*
X367692Y547914D03*
Y536200D03*
X398029Y536942D03*
X418108D03*
Y547907D03*
X408069Y536942D03*
X401376Y555842D03*
X418108D03*
X411416Y555857D03*
X398029Y574742D03*
X401377Y566822D03*
X418108Y566807D03*
X408069Y574742D03*
X418108Y585599D03*
Y574742D03*
X411416Y566822D03*
X376892Y581127D03*
X370596Y585614D03*
X376792Y543700D03*
X411416Y536957D03*
Y574757D03*
X394682Y569492D03*
X408068Y612657D03*
X367911Y604614D03*
X418108Y609864D03*
X398029D03*
X401376Y593642D03*
X401375Y607292D03*
X418108Y593642D03*
X411416Y593657D03*
X411415Y604614D03*
X418108Y604499D03*
X378600Y606200D03*
X371312Y604709D03*
X371134Y612453D03*
X411415Y609864D03*
X394682Y607292D03*
X421455Y9121D03*
X421454Y-1817D03*
X438189Y35957D03*
X444880Y28022D03*
X444882Y35957D03*
X428149D03*
X421456Y28022D03*
X434842Y35957D03*
X438189Y28022D03*
X421456Y35957D03*
X431494Y-4536D03*
X424801D03*
X428147Y-7108D03*
X434840D03*
X441533Y-1843D03*
X434842Y17057D03*
X441533Y17042D03*
X431494Y35942D03*
X441533D03*
X428149Y28022D03*
X424801Y35942D03*
X434842Y28268D03*
X441533Y28007D03*
X428149Y17057D03*
X441533Y9107D03*
X424801D03*
X431494D03*
X448226Y11100D03*
X421455Y46921D03*
X421456Y73757D03*
X438189D03*
X444880Y65822D03*
X428149Y73757D03*
X421456Y65822D03*
X434842Y73757D03*
X438189Y65822D03*
X434842Y54857D03*
X441533Y54842D03*
X424801Y46907D03*
X431494D03*
X441533D03*
Y65807D03*
X434842Y65822D03*
X428149D03*
X431494Y73742D03*
X441533D03*
X424801D03*
X428149Y54857D03*
X436113Y220096D03*
X446253Y222047D03*
X432733D03*
X442873Y220096D03*
X456393D03*
X466533Y222047D03*
X453013D03*
X463153Y220096D03*
X476672D03*
X473292Y222047D03*
X439493Y218147D03*
X459773D03*
X480052D03*
X439493Y222047D03*
X459773D03*
X480052D03*
X425974D03*
X422594Y220096D03*
X480052Y210346D03*
X458400Y276400D03*
X436113Y227896D03*
X446253Y225947D03*
X432733D03*
X442873Y227896D03*
X456393D03*
X466533Y225947D03*
X453013D03*
X463153Y227896D03*
X476672D03*
X473292Y225947D03*
X439493Y229847D03*
X459773D03*
X480052Y225947D03*
X439493D03*
X459773D03*
X480052Y229847D03*
X425974Y225947D03*
X422594Y227896D03*
X466533Y233746D03*
Y241547D03*
X476672Y235696D03*
Y239596D03*
X463153Y235696D03*
Y239596D03*
X473292Y233746D03*
Y241547D03*
X469913Y231797D03*
Y243496D03*
Y235696D03*
Y239596D03*
X425974Y233746D03*
Y241547D03*
X436113Y235696D03*
Y239596D03*
X422594Y235696D03*
Y239596D03*
X432733Y233746D03*
Y241547D03*
X446253Y233746D03*
Y241547D03*
X456393Y235696D03*
Y239596D03*
X442873Y235696D03*
Y239596D03*
X453013Y233746D03*
Y241547D03*
X456393Y247396D03*
Y255196D03*
X466533Y249347D03*
Y253247D03*
X453013Y249347D03*
Y253247D03*
X463153Y247396D03*
Y255196D03*
X476672Y247396D03*
Y255196D03*
X473292Y249347D03*
Y253247D03*
X429354Y231797D03*
X449633D03*
X459773Y245447D03*
X480052D03*
X429354Y243496D03*
X449633D03*
X459773Y257147D03*
X480052D03*
X429354Y235696D03*
X449633D03*
X459773Y249347D03*
X480052D03*
X429354Y239596D03*
X449633D03*
X459773Y253247D03*
X480052D03*
X452865Y270081D03*
X465100Y280300D03*
X434983Y255497D03*
X438363Y257446D03*
X421464Y255497D03*
X431604Y257446D03*
X448503Y263297D03*
X441743Y259397D03*
X455263Y267197D03*
X436113Y247396D03*
X446253Y249347D03*
X442873Y251296D03*
X439493Y249347D03*
X442873Y247396D03*
X439493Y245447D03*
X446253Y253247D03*
X466533Y261047D03*
X463153Y262996D03*
X477792Y276646D03*
Y280547D03*
X469913Y282496D03*
X474413Y274696D03*
X469913Y278596D03*
X466533Y268847D03*
X422594Y247396D03*
X429781Y264793D03*
X459773Y264947D03*
X469913Y266896D03*
Y262996D03*
X473292Y261047D03*
X469913Y259096D03*
X481172Y282496D03*
Y270796D03*
X480052Y264947D03*
X473292D03*
Y268847D03*
X476672Y266896D03*
Y262996D03*
X474413Y344896D03*
X481172Y321496D03*
Y325396D03*
Y317596D03*
Y333196D03*
X463671Y319386D03*
X466734Y287074D03*
X442020Y339220D03*
X438240Y339380D03*
X451883Y342646D03*
X448503Y344597D03*
X481172Y298096D03*
X469913D03*
Y301996D03*
X481172Y305896D03*
X477792Y284447D03*
Y296147D03*
Y300047D03*
Y292247D03*
X481172Y294196D03*
X469913D03*
Y290296D03*
X474413Y329296D03*
X468783Y332897D03*
X474413Y333196D03*
Y325396D03*
X477792Y323446D03*
X430089Y338428D03*
X426494Y338361D03*
X463800Y289500D03*
X464273Y342947D03*
X471033Y339047D03*
X456900Y333000D03*
X481172Y329296D03*
X471033Y342947D03*
X466100Y300021D03*
X460893Y344896D03*
X481172Y286396D03*
X477792Y311747D03*
X469913Y309797D03*
Y313696D03*
Y317596D03*
X477792Y339047D03*
Y335147D03*
Y331247D03*
X481172Y340996D03*
Y337096D03*
X453400Y293686D03*
X477792Y346847D03*
X481172Y348796D03*
X477792Y350747D03*
X443993Y381947D03*
Y389747D03*
X454133Y383896D03*
Y387796D03*
X440613Y383896D03*
Y387796D03*
X450753Y381947D03*
Y389747D03*
X464273Y381947D03*
Y389747D03*
X474413Y383896D03*
Y387796D03*
X460893Y383896D03*
Y387796D03*
X471033Y381947D03*
Y389747D03*
X481172Y383896D03*
Y387796D03*
X447373Y383896D03*
X467653Y379996D03*
X447373Y391696D03*
X467653D03*
X447373Y379996D03*
X467653Y383896D03*
X447373Y387796D03*
X467653D03*
X423714Y389747D03*
Y393647D03*
X433854Y383896D03*
Y387796D03*
X423714Y378047D03*
Y381947D03*
X430474D03*
Y389747D03*
X474413Y368296D03*
Y376096D03*
X481172Y364396D03*
X471033Y370247D03*
Y374146D03*
X481172Y368296D03*
Y376096D03*
X427094Y383896D03*
X477792Y370247D03*
X427094Y391696D03*
X477792Y378047D03*
X427094Y379996D03*
X477792Y366347D03*
X427094Y387796D03*
X477792Y374146D03*
X427094Y364396D03*
X423714Y370247D03*
X437233Y366347D03*
Y370247D03*
X423714Y358547D03*
Y366347D03*
X433854Y364396D03*
Y372197D03*
X454133Y368296D03*
Y376096D03*
X464273Y370247D03*
Y374146D03*
X450753Y370247D03*
Y374146D03*
X460893Y368296D03*
Y376096D03*
X443993Y354647D03*
Y362447D03*
X454133Y356596D03*
Y360496D03*
X440613Y356596D03*
Y360496D03*
X450753Y354647D03*
Y362447D03*
X464273Y354647D03*
Y362447D03*
X474413Y356596D03*
Y360496D03*
X460893Y356596D03*
Y360496D03*
X471033Y354647D03*
Y362447D03*
X430474Y366347D03*
X457513Y370247D03*
X447373Y356596D03*
X467653D03*
X430474Y370247D03*
X457513Y378047D03*
X447373Y364396D03*
X467653D03*
X430474Y362447D03*
X457513Y366347D03*
X447373Y352696D03*
X467653D03*
X430474Y374146D03*
X457513D03*
X447373Y360496D03*
X467653D03*
X421464Y348497D03*
X438363Y346546D03*
X424844D03*
X434983Y348497D03*
X428224D03*
X431604Y346546D03*
X471033Y346847D03*
X464273D03*
X457513Y350747D03*
X430474Y358547D03*
X433854Y356596D03*
X437233Y378047D03*
X440613Y376096D03*
X443993Y374147D03*
Y370247D03*
X481172Y356596D03*
X421456Y529022D03*
X428149D03*
X434842D03*
X441533Y529007D03*
X421456Y547922D03*
Y585722D03*
X438189Y536957D03*
X444882D03*
X428149D03*
X434842D03*
X438189Y574757D03*
X444880Y566822D03*
X444882Y574757D03*
X428149D03*
X421456Y566822D03*
X434842Y574757D03*
X438189Y566822D03*
X431494Y574742D03*
Y547907D03*
X424801D03*
X441533D03*
X431494Y536942D03*
X424801D03*
X441533Y536957D03*
X428149Y555857D03*
X434842D03*
X441533Y555842D03*
Y574742D03*
Y585707D03*
X434842Y566822D03*
X424801Y574742D03*
X431494Y585707D03*
X424801D03*
X441533Y566807D03*
X428149Y566822D03*
X447735Y588394D03*
X421454Y612560D03*
X441533Y612557D03*
Y607292D03*
X434840D03*
X428147D03*
X424801Y609864D03*
X431494D03*
X434842Y593657D03*
X428149D03*
X441533Y593642D03*
X447766Y612659D03*
X483432Y216196D03*
Y220096D03*
X511592Y222047D03*
X514972Y220096D03*
X518352Y222047D03*
X521731Y216196D03*
X531871Y218147D03*
X542011Y208396D03*
X531871Y202547D03*
X525111D03*
X528491Y204496D03*
X538631Y202247D03*
X483432Y212296D03*
X525111Y222047D03*
Y210346D03*
X521731Y212296D03*
X514972Y208397D03*
Y212296D03*
X508212Y216196D03*
X501452Y220096D03*
X504832Y214247D03*
X498072Y218147D03*
Y214247D03*
X494692Y220096D03*
X542011Y216196D03*
X538631Y218147D03*
X535251Y212296D03*
X531871Y210346D03*
Y214247D03*
X525111D03*
X518352D03*
Y210345D03*
X514972Y216196D03*
X511592Y214247D03*
X504832Y222047D03*
Y218147D03*
X501452Y216196D03*
X494692Y212296D03*
Y216196D03*
X542011Y212296D03*
Y220096D03*
X535251D03*
Y208397D03*
X528491Y212296D03*
X535251Y216196D03*
X484552Y272747D03*
Y276646D03*
X501452Y270796D03*
X511592Y268847D03*
X514972Y255196D03*
X501452D03*
Y251296D03*
X521731Y270796D03*
X514972Y282496D03*
X521731D03*
X508212D03*
X494692D03*
X491312Y280547D03*
X486812Y261047D03*
X483432Y262996D03*
X518352Y261047D03*
X525111D03*
X514972Y251296D03*
X518352Y272747D03*
X521731Y255196D03*
Y251296D03*
X498072Y264947D03*
X511592Y245447D03*
X514972Y243496D03*
X483432Y227896D03*
Y231797D03*
X486812Y249347D03*
Y253247D03*
X483432Y247396D03*
Y255196D03*
X498072Y280547D03*
X514972Y274696D03*
X525111Y272747D03*
X518352Y257147D03*
X508212Y274696D03*
X504832Y268847D03*
X491312Y272747D03*
X511592D03*
X504832Y276647D03*
X498072Y245447D03*
X494692Y223996D03*
X504832Y225947D03*
X484552Y280547D03*
X518352Y233746D03*
X531871Y241547D03*
Y249347D03*
X528491Y223996D03*
X531871Y237647D03*
X535251Y223996D03*
X542011D03*
X528491Y270796D03*
Y278596D03*
X542011Y270796D03*
X535251Y255196D03*
X531871Y264947D03*
X494692Y266896D03*
X504832Y257147D03*
X508212Y251296D03*
X504832Y249347D03*
X508212Y247396D03*
X518352Y264947D03*
X508212Y243496D03*
X518352Y245447D03*
X531871Y257147D03*
X528491Y255196D03*
X511592Y253247D03*
X525111Y268847D03*
X518352Y241547D03*
Y237647D03*
X521731Y239596D03*
Y243496D03*
X528491Y262996D03*
Y266896D03*
X498072Y249347D03*
X525111D03*
Y245447D03*
X508212Y266896D03*
X521731Y278596D03*
X498072Y276647D03*
X491312D03*
X511592D03*
X504832Y272747D03*
X498072Y253247D03*
Y257147D03*
X518352Y280547D03*
X535251Y243496D03*
X542011Y266896D03*
X538631Y272747D03*
X531871D03*
X538631Y280547D03*
X542011Y282496D03*
X538631Y276646D03*
X535251Y278596D03*
X531871Y280547D03*
X538631Y241547D03*
X542011Y243496D03*
Y251296D03*
Y255196D03*
Y262996D03*
X538631Y261047D03*
X531871Y245447D03*
X538631Y264947D03*
Y268847D03*
X535251Y270796D03*
X542011Y278596D03*
X535251Y274696D03*
Y282496D03*
X528491D03*
X538631Y245447D03*
Y253247D03*
X542011Y259096D03*
X535251Y262996D03*
X511592Y229847D03*
Y225947D03*
Y237647D03*
X508212Y235696D03*
X498072Y229847D03*
X504832Y233746D03*
X494692Y227896D03*
X501452Y235696D03*
X498072Y237647D03*
Y241547D03*
X542011Y227896D03*
Y235696D03*
X535251Y231797D03*
Y227896D03*
X531871Y229847D03*
X525111Y233746D03*
X521731Y223996D03*
X525111Y229847D03*
X514972Y231797D03*
X508212Y227896D03*
X511592Y233746D03*
X504832Y237647D03*
X501452Y227896D03*
Y231797D03*
X494692D03*
X501452Y239596D03*
X494692D03*
X501452Y243496D03*
X542011Y231797D03*
X538631Y233746D03*
Y229847D03*
X531871Y225947D03*
Y233746D03*
X528491Y231797D03*
X525111Y225947D03*
X518352D03*
X521731Y227896D03*
X525111Y257147D03*
X528491Y259096D03*
X525111Y276646D03*
X504832Y280547D03*
X511592D03*
X518352Y276646D03*
Y268847D03*
X498072Y272747D03*
X531871Y253247D03*
X528491Y251296D03*
X525111Y241547D03*
X528491Y239596D03*
X518352Y249347D03*
X513857Y260881D03*
X501452Y262996D03*
X504832Y261047D03*
X501452Y278596D03*
X498072Y268847D03*
X504832Y264947D03*
X494692Y262996D03*
X491312Y264947D03*
X487932Y266896D03*
X491312Y268847D03*
X487932Y270796D03*
X498072Y261047D03*
X494692Y259096D03*
X483432Y239596D03*
X521731Y262996D03*
X525111Y264947D03*
X494692Y274696D03*
X487932Y313696D03*
X491312Y315647D03*
X484552Y319546D03*
Y331247D03*
X501452Y337096D03*
X531871Y331247D03*
X491312Y288347D03*
Y284447D03*
X498072D03*
Y288347D03*
X501452Y286396D03*
X494692Y290296D03*
X498072Y292247D03*
X504832D03*
X518352Y284447D03*
X504832Y288347D03*
Y284447D03*
X508212Y286396D03*
X531871Y315647D03*
X487932Y286396D03*
X514972Y344896D03*
X511592Y342947D03*
X508212Y340996D03*
Y344896D03*
X487932Y290296D03*
X484552Y288347D03*
Y296147D03*
X498072Y339047D03*
X504832Y327347D03*
X508212Y321496D03*
X514972Y340996D03*
X518352Y331247D03*
X521731Y344896D03*
Y321496D03*
X525111Y339047D03*
X535251Y333196D03*
Y325396D03*
X484552Y284447D03*
X487932Y305896D03*
X491312Y303947D03*
X501452Y305896D03*
X494692Y298096D03*
X498072Y307847D03*
X484552Y303947D03*
X487932Y294196D03*
X491312Y296147D03*
X494692Y301996D03*
X487932D03*
X501452Y309797D03*
X487932Y298096D03*
X525111Y323446D03*
X531871D03*
X525111Y327347D03*
X528491Y333196D03*
X521731Y329296D03*
X518352Y335147D03*
X521731Y340996D03*
X525111Y319547D03*
X528491Y321496D03*
Y325396D03*
Y329296D03*
X525111Y331247D03*
X521731Y333196D03*
Y337096D03*
X511592Y311747D03*
X508212Y309797D03*
X511592Y300047D03*
Y303947D03*
X542011Y286396D03*
X531871Y284447D03*
X542011Y290296D03*
X535251Y286396D03*
X542011Y313696D03*
Y309797D03*
X538631Y307847D03*
Y303947D03*
Y300047D03*
X535251Y298096D03*
Y344896D03*
X542011D03*
Y340996D03*
Y337096D03*
X538631Y331247D03*
Y327347D03*
X535251Y317596D03*
X542011D03*
Y305896D03*
X535251D03*
X542011Y301996D03*
X538631Y296147D03*
X531871D03*
X535251Y340996D03*
X538631Y342947D03*
X542011Y333196D03*
Y329296D03*
Y325396D03*
X538631Y323446D03*
X535251Y313696D03*
X538631Y315647D03*
X484552Y311747D03*
Y315647D03*
X511592Y288347D03*
Y292245D03*
X491312Y323446D03*
X535251Y337096D03*
X528491Y340996D03*
X531871Y339047D03*
Y342947D03*
X528491Y344896D03*
X491312Y342947D03*
X528491Y305896D03*
X518352Y311747D03*
X504832D03*
X508212Y305896D03*
Y301996D03*
X504832Y303947D03*
Y300045D03*
X518352Y303947D03*
X514972Y305896D03*
Y309797D03*
X528491Y301996D03*
Y309797D03*
X525111Y311747D03*
Y307847D03*
Y303947D03*
X521731Y305896D03*
Y309797D03*
X518352Y307847D03*
X514972Y313696D03*
X528491D03*
X521731D03*
X487932Y344896D03*
X484552Y342947D03*
X518352Y296147D03*
Y300047D03*
X521731Y294196D03*
X525111Y288347D03*
X528491Y290296D03*
X525111Y296147D03*
Y292245D03*
X521731Y298096D03*
Y290296D03*
Y286396D03*
X518352Y288347D03*
Y292245D03*
X514972Y298096D03*
X501452Y325396D03*
X498072Y323446D03*
Y315647D03*
X501452Y317596D03*
X498072Y335147D03*
X501452Y321496D03*
X498072Y331247D03*
X501452Y329296D03*
Y313696D03*
X498072Y300047D03*
X508212Y298096D03*
X504832Y296147D03*
X498072D03*
X501452Y294196D03*
X511592Y296147D03*
X498072Y311747D03*
X501452Y301996D03*
X494692Y325396D03*
Y321496D03*
X491312Y319547D03*
X494692Y333196D03*
X491312Y335147D03*
X487932Y333196D03*
Y337096D03*
X484552Y339047D03*
Y335147D03*
X491312Y327347D03*
X494692Y329296D03*
X487932D03*
Y340996D03*
X494692Y313696D03*
X484552Y307847D03*
X491312D03*
Y311747D03*
X494692Y305896D03*
Y317596D03*
X487932Y321496D03*
X484552Y327347D03*
X487932Y325396D03*
X484552Y381947D03*
Y389747D03*
X494692Y395597D03*
Y399496D03*
X491312Y401447D03*
Y393647D03*
X487932Y379996D03*
Y391696D03*
Y383896D03*
Y387796D03*
X484552Y374146D03*
X514972Y352696D03*
Y348796D03*
X511592Y350747D03*
Y346847D03*
X508212Y348796D03*
X504832Y362447D03*
X494692Y368296D03*
Y352696D03*
X508212Y356596D03*
X504832Y350747D03*
X511592Y374146D03*
X501452Y383896D03*
X498072Y389747D03*
X494692Y376096D03*
X508212Y379996D03*
X521731Y368296D03*
X518352Y366347D03*
Y358547D03*
X542011Y364396D03*
X538631Y370247D03*
X542011Y372197D03*
Y352696D03*
X525111Y350747D03*
X514972Y399496D03*
X538631Y381947D03*
X531871Y385847D03*
X528491Y391696D03*
X525111Y397546D03*
X531871Y405347D03*
X511592Y362447D03*
X514972Y368296D03*
X508212Y364396D03*
X504832Y370247D03*
X508212Y376096D03*
X501452Y372197D03*
X498072Y378047D03*
X494692Y379996D03*
Y387796D03*
X518352Y350747D03*
Y354647D03*
X511592Y358547D03*
X514972Y360496D03*
Y364396D03*
X511592Y366347D03*
X508212Y368296D03*
Y372197D03*
X504832Y374146D03*
X501452Y376096D03*
X498072Y381947D03*
X494692Y383896D03*
X518352Y346847D03*
X521731Y352696D03*
X511592Y354647D03*
X498072Y370247D03*
Y374146D03*
X504832Y397546D03*
Y393647D03*
X511592D03*
X501452Y387796D03*
X511592Y385847D03*
X518352D03*
Y381947D03*
Y378047D03*
X508212Y395597D03*
X504832Y389747D03*
X508212Y391696D03*
X504832Y385847D03*
X511592Y381947D03*
X514972Y383896D03*
X521731Y379996D03*
X518352Y374146D03*
Y405347D03*
X525111D03*
Y401447D03*
X528491Y395597D03*
X535251Y399496D03*
X531871Y393647D03*
X538631Y389747D03*
Y385847D03*
X518352Y401447D03*
X521731Y403396D03*
X528491Y399496D03*
X531871Y397546D03*
X535251Y395597D03*
Y391696D03*
Y387796D03*
X542011Y383896D03*
X528491Y387796D03*
X521731D03*
Y391696D03*
X518352Y393647D03*
X514972Y395597D03*
X511592Y389747D03*
X528491Y379996D03*
Y383896D03*
X525111Y385847D03*
X521731Y383896D03*
X525111Y389747D03*
X521731Y395597D03*
X514972Y391696D03*
Y387796D03*
X528491Y376096D03*
X531871Y381947D03*
X542011Y391696D03*
Y395597D03*
Y387796D03*
X535251Y348796D03*
X538631Y346847D03*
X525111Y370247D03*
X531871D03*
X525111Y362447D03*
X528491Y360496D03*
Y356596D03*
X535251Y352696D03*
X525111Y378047D03*
Y374146D03*
Y366347D03*
X528491Y368296D03*
X521731Y364396D03*
X525111Y358547D03*
X531871Y354647D03*
Y350747D03*
X521731Y376096D03*
X528491Y372197D03*
X542011Y379996D03*
X538631Y354647D03*
Y358547D03*
Y362447D03*
X531871D03*
Y366347D03*
X535251Y372197D03*
Y376096D03*
Y379996D03*
X538631Y350747D03*
X542011Y356596D03*
X535251Y360496D03*
X531871Y358547D03*
X535251Y364396D03*
Y368296D03*
X538631Y374146D03*
X531871Y378047D03*
X525111Y346847D03*
X528491Y348796D03*
Y352696D03*
X487932Y356596D03*
X491312Y354647D03*
X511592Y401447D03*
X508212Y383896D03*
X514972Y376096D03*
X504832Y401446D03*
X487932Y352696D03*
X484552Y354647D03*
Y350747D03*
Y358547D03*
X487932Y348796D03*
X598817Y17057D03*
X602163Y9157D03*
Y-1743D03*
Y36057D03*
Y27899D03*
X605510D03*
Y-9901D03*
Y16999D03*
Y-1743D03*
Y9157D03*
Y36057D03*
X598817Y92657D03*
X602163Y84757D03*
Y54799D03*
Y46957D03*
X598817Y54857D03*
X602163Y73857D03*
X605510Y92599D03*
Y65699D03*
Y54799D03*
Y46957D03*
Y84757D03*
Y73857D03*
X603163Y103971D03*
X605028Y119000D03*
X604977Y110200D03*
X558911Y218147D03*
X555531Y220096D03*
X548771D03*
X545391Y218147D03*
Y214247D03*
X552151Y222047D03*
X548771Y216196D03*
X603273Y198896D03*
X600286Y202921D03*
X599773Y199596D03*
X592300Y220500D03*
X552151Y237647D03*
X555531Y231797D03*
X548771Y227896D03*
X552151Y245447D03*
X548771Y251296D03*
X545391Y237647D03*
X548771Y282496D03*
Y270796D03*
Y262996D03*
X545391Y276646D03*
Y245447D03*
Y253247D03*
X548771Y259096D03*
X545391Y241547D03*
X548771Y247396D03*
X545391Y249347D03*
Y257147D03*
Y261047D03*
Y229847D03*
X548771Y231797D03*
X562616Y223996D03*
X555531Y259096D03*
Y266896D03*
X558911Y268847D03*
X552151D03*
Y276646D03*
X555531Y278596D03*
Y282496D03*
X562640Y231735D03*
X555531Y243496D03*
X552151Y253247D03*
X558911Y249347D03*
Y257147D03*
Y225947D03*
X555531Y262996D03*
X552151Y264947D03*
X555531Y270796D03*
X552151Y272747D03*
X548771Y274696D03*
X552151Y280547D03*
X562630Y227896D03*
X558911Y241547D03*
X555531Y251296D03*
X558911Y253247D03*
X555531Y255196D03*
Y227896D03*
Y223996D03*
X548771D03*
Y321496D03*
X545391Y323446D03*
X548771Y337096D03*
X545391Y342947D03*
X548771Y329296D03*
X552151Y331247D03*
Y335147D03*
Y342947D03*
X548771Y344896D03*
Y333196D03*
X552151Y339047D03*
X555531Y340996D03*
X548771Y290296D03*
Y294196D03*
X545391Y284447D03*
X560884Y290296D03*
X555831Y294196D03*
X552151Y292245D03*
X545391Y327347D03*
Y311747D03*
Y339047D03*
X552151Y319547D03*
Y315647D03*
Y311747D03*
X548771Y305896D03*
X552151Y300047D03*
X548771Y301996D03*
X562591Y340996D03*
X558911Y339047D03*
X559211Y331103D03*
X555531Y329296D03*
X559211Y323446D03*
X555531Y321496D03*
X548771Y317596D03*
X555831Y313696D03*
X552151Y307847D03*
Y303947D03*
X555831Y301996D03*
X548771Y298096D03*
X555531Y344896D03*
X562591Y337096D03*
X555531D03*
X559211Y327347D03*
X552151D03*
X555531Y325396D03*
X555831Y317446D03*
X559212Y385847D03*
X552151Y346847D03*
Y393647D03*
X545391Y389747D03*
X548771Y387796D03*
X545391Y393647D03*
X552151Y385847D03*
X559212Y389747D03*
X555531Y352696D03*
Y348796D03*
X552151Y354647D03*
X558911Y350747D03*
X545391Y378047D03*
X552151Y374146D03*
X545391D03*
X548771Y364396D03*
Y360496D03*
Y356596D03*
Y383896D03*
Y376096D03*
Y372196D03*
X545391Y370247D03*
Y362447D03*
X552151Y358547D03*
X548771Y352696D03*
X545391Y381947D03*
X548771Y379996D03*
X559211Y366347D03*
X552151D03*
Y370247D03*
X555531Y379996D03*
X552151Y381947D03*
X558911Y354647D03*
X563500Y360500D03*
X552151Y362447D03*
X555531Y372197D03*
X548990Y403670D03*
X555750Y399770D03*
X545391Y350747D03*
X548771Y348796D03*
X562591D03*
X592216Y445152D03*
X595070Y447970D03*
X602163Y510157D03*
X598817Y518057D03*
X605510Y528899D03*
Y517999D03*
Y510157D03*
X602163Y574857D03*
Y566699D03*
Y555799D03*
X598817Y555857D03*
X602163Y547957D03*
Y537057D03*
Y585757D03*
X605510Y555799D03*
Y566699D03*
Y585757D03*
Y547957D03*
Y574857D03*
Y537057D03*
X598817Y593657D03*
X602163Y612657D03*
X605510Y604499D03*
Y593599D03*
Y612657D03*
X661494Y32946D03*
X657250Y-2050D03*
X608856Y16999D03*
X612203D03*
Y9157D03*
X608856D03*
X615549D03*
X608856Y-9901D03*
X612203D03*
X608856Y-1743D03*
X612203D03*
X615549D03*
Y36057D03*
X608856D03*
X612203D03*
Y27899D03*
X608856D03*
X659747Y-12132D03*
X615549Y27899D03*
Y-9901D03*
Y16999D03*
X659700Y22900D03*
X665396Y23000D03*
X615549Y84757D03*
X608856D03*
X612203D03*
X608856Y92599D03*
X612203D03*
X608856Y46957D03*
X612203D03*
X608856Y54799D03*
X615549Y46957D03*
X612203Y54799D03*
X608856Y65699D03*
X612203D03*
X615549Y73857D03*
X608856D03*
X612203D03*
X652718Y93881D03*
X664471Y86061D03*
X662352Y89566D03*
X615549Y92599D03*
Y65699D03*
Y54799D03*
X626040Y98281D03*
X608600Y103000D03*
X613602Y118047D03*
Y109247D03*
X633800Y119000D03*
X658055Y141493D03*
X647555Y143643D03*
X651055Y142893D03*
X654555Y142193D03*
X642673Y139811D03*
X644055Y144493D03*
X635673Y141318D03*
X639173Y140618D03*
X632173Y142018D03*
X628673Y142718D03*
X609482Y124568D03*
X618800Y100100D03*
X644750Y175650D03*
X660600Y170000D03*
Y175000D03*
X611148Y206994D03*
X618648Y219494D03*
Y214494D03*
X608648Y204494D03*
X613648D03*
X610273Y197496D03*
X613773Y196796D03*
X613082Y200676D03*
X609860Y201356D03*
X654950Y253446D03*
X627529Y280441D03*
X618279Y251393D03*
X624500Y240500D03*
X639320Y268000D03*
X643500Y274868D03*
X633410Y269610D03*
Y274610D03*
X651235Y249165D03*
X641665Y281139D03*
X643100Y253700D03*
X649800Y252600D03*
X656100Y275500D03*
X606148Y229494D03*
X617235Y247735D03*
X614456Y244956D03*
X637681Y337390D03*
X628525Y287832D03*
X631250Y289650D03*
X639622Y290210D03*
X643823Y289650D03*
X658500Y284500D03*
X632869Y293720D03*
X648900Y336600D03*
X646520Y297400D03*
X664267Y292668D03*
X637143Y322000D03*
X637561Y312000D03*
Y317000D03*
X637600Y302000D03*
Y307000D03*
X646700Y308850D03*
X658900Y339150D03*
X628950Y293550D03*
X654600Y296000D03*
X662238Y296146D03*
X659694Y351206D03*
X664194D03*
X649194D03*
X654194D03*
X649600Y391200D03*
X640300Y437600D03*
X608800Y463475D03*
Y468475D03*
X609191Y451454D03*
X615300Y457900D03*
X641150Y484300D03*
X653800Y496600D03*
X618430Y491550D03*
X623400Y476300D03*
X629300Y490000D03*
X648500Y477400D03*
X662640Y528330D03*
X608856Y517999D03*
X612203D03*
Y528899D03*
X608856D03*
X615549Y510157D03*
X608856D03*
X612203D03*
X612515Y498752D03*
X609284Y480055D03*
X636500Y493924D03*
X627000Y478300D03*
X611250Y476750D03*
X618800Y474500D03*
X615549Y517999D03*
Y528899D03*
X639120Y475620D03*
X658900Y509300D03*
X639197Y490367D03*
X623600Y521700D03*
X608856Y574857D03*
X612203D03*
X615549D03*
X612203Y566699D03*
X608856D03*
Y555799D03*
X612203D03*
Y547957D03*
X615549D03*
X608856D03*
Y537057D03*
X615549D03*
X612203D03*
X615549Y585757D03*
X612203D03*
X608856D03*
X660217Y576734D03*
X615549Y555799D03*
Y566699D03*
X662000Y589000D03*
X608856Y593599D03*
X612203D03*
X608856Y604499D03*
X612203D03*
X608856Y612657D03*
X615549D03*
X612203D03*
X615549Y604499D03*
Y593599D03*
X665000Y598500D03*
X631741Y615759D03*
X723715Y23462D03*
X692500Y15300D03*
X708000Y26600D03*
X724837Y13852D03*
X714300Y-1900D03*
X680200Y13100D03*
X719400Y14300D03*
X679936Y18406D03*
X670227Y34277D03*
X670400Y26100D03*
X701100Y8100D03*
X704450Y4950D03*
X720572Y88700D03*
X715130Y79574D03*
X697200Y79500D03*
X697100Y90600D03*
X670795Y89189D03*
X716894Y84047D03*
X701500Y85500D03*
X694600Y85000D03*
X698300Y85300D03*
X709560Y84648D03*
X670503Y115884D03*
X670600Y144900D03*
Y150000D03*
X705292Y195729D03*
X701956Y195294D03*
X701129Y192106D03*
X709341Y190507D03*
X725725Y241560D03*
X697255Y267098D03*
X710500Y224500D03*
X700400Y257200D03*
X710272Y281911D03*
X706800Y281900D03*
X704500Y252500D03*
X700800Y261300D03*
X690130Y277380D03*
X715200Y258900D03*
X704090Y256080D03*
X689960Y260500D03*
X700000Y233700D03*
X710900Y231660D03*
X677800Y254100D03*
X667700Y275600D03*
X710700Y260200D03*
X710675Y263425D03*
X679300Y261700D03*
X712400Y324400D03*
X711900Y327700D03*
X697120Y305349D03*
Y300349D03*
X704404Y315875D03*
Y310875D03*
X697521Y325500D03*
Y320500D03*
X724000Y291700D03*
X686140Y298260D03*
X695000Y289500D03*
X686600Y335600D03*
X670800Y292600D03*
X667900Y339000D03*
X697352Y335500D03*
Y330500D03*
X705800Y301600D03*
X674700Y339200D03*
X688100Y308600D03*
X688924Y288147D03*
X674469Y287375D03*
X674194Y358467D03*
X683417Y364972D03*
X686619Y392600D03*
X683100Y392200D03*
X691240Y390039D03*
X687427Y384926D03*
X676900Y381800D03*
X669194Y351206D03*
X674194D03*
X679194D03*
X684194D03*
X695700Y346300D03*
X680370Y427770D03*
X680200Y432100D03*
X687400Y411200D03*
X674300Y489500D03*
X679700Y489400D03*
X718546Y500283D03*
X696000Y496800D03*
X669300Y504000D03*
X708500Y512500D03*
X721894Y501346D03*
X726040Y506080D03*
X696600Y581400D03*
X722200Y571300D03*
X718200Y581000D03*
X680029Y577503D03*
X680910Y582000D03*
X693200Y575900D03*
X717612Y598554D03*
X722406Y598950D03*
X756176Y-4300D03*
X729500Y23500D03*
X764100Y17100D03*
X760100Y17255D03*
X763500Y23940D03*
X765900Y35800D03*
X765400Y-9800D03*
X766300Y-1800D03*
X729600Y17991D03*
X734256D03*
X755000Y17255D03*
X753100Y92111D03*
X764100Y55100D03*
X751600Y41000D03*
X755500Y55200D03*
X763500Y59700D03*
X766500Y102900D03*
X752900Y101000D03*
X769044Y191348D03*
X770300Y204930D03*
X771232Y214033D03*
X749126Y220843D03*
X761580Y220160D03*
X748700Y257500D03*
X771650Y246451D03*
Y278451D03*
X759700Y232000D03*
X739400Y253400D03*
X739500Y247500D03*
X731662Y247716D03*
X730000Y254675D03*
X737750Y298894D03*
X771600Y310600D03*
X771700Y342501D03*
X729405Y290725D03*
X737912Y315500D03*
X741512Y315538D03*
X736000Y303400D03*
X757956Y328095D03*
X741250Y298856D03*
X743600Y304100D03*
X771400Y374400D03*
X760500Y359800D03*
X765007Y348363D03*
X732000Y380000D03*
X739933Y447401D03*
X756000Y525950D03*
X743483Y492937D03*
X764400Y528600D03*
X738648Y492050D03*
X763544Y522236D03*
X766535Y517900D03*
X763706Y514250D03*
X763300Y566000D03*
X769500Y536983D03*
X755000Y566000D03*
X769500Y574700D03*
X764117Y575658D03*
X765100Y537110D03*
X766535Y555700D03*
X732600Y573950D03*
X763450Y585200D03*
X765900Y587300D03*
X764400Y604600D03*
X739307Y598850D03*
X755800Y604600D03*
X769500Y612583D03*
X766535Y593500D03*
X733032Y604000D03*
X798337Y181216D03*
X799300Y195600D03*
X813700D03*
Y198900D03*
X799620Y186547D03*
X804470Y186814D03*
X824000Y402863D03*
X797000Y404700D03*
X851430Y367468D03*
X805600Y403900D03*
X840871Y391380D03*
X837272Y391420D03*
X827800Y402863D03*
X832300D03*
X805367Y407400D03*
X797780Y423484D03*
X913787Y257860D03*
X913700Y242260D03*
X913787Y261760D03*
Y246160D03*
Y273460D03*
Y335860D03*
Y331960D03*
X882008Y321100D03*
X913787Y351460D03*
Y347560D03*
X957765Y-7180D03*
X957283Y28014D03*
X970669D03*
X974015D03*
Y35957D03*
X963976Y28014D03*
X960629Y35957D03*
Y-9786D03*
X963976Y-1843D03*
X970669Y-1743D03*
X967322Y-9786D03*
X963976Y9114D03*
X970669D03*
Y35957D03*
X967322Y28014D03*
X960629Y17057D03*
X963976Y35957D03*
X960629Y28014D03*
X967322Y17057D03*
Y35957D03*
Y-4536D03*
Y9114D03*
X957536Y67802D03*
X970669Y65814D03*
X974015D03*
Y73757D03*
X963976Y65814D03*
X967322D03*
X960629D03*
X970669Y46914D03*
X967322Y54857D03*
X963976Y46914D03*
X960629Y54857D03*
X963976Y73757D03*
X970669D03*
X967322D03*
Y46914D03*
X963245Y105725D03*
X924227Y205210D03*
X920847Y207159D03*
X927607Y218860D03*
X930987Y216909D03*
X934367Y218860D03*
X947887Y214960D03*
X958026Y216909D03*
Y220809D03*
X944507Y216909D03*
Y220809D03*
X954647Y214960D03*
X951267Y213009D03*
X937747Y220809D03*
X951267Y216909D03*
Y220809D03*
X934367Y203260D03*
Y211060D03*
X944507Y205210D03*
Y209109D03*
X930987Y205210D03*
Y209109D03*
X941127Y203260D03*
Y211060D03*
X937747Y201309D03*
Y213009D03*
Y205210D03*
Y209109D03*
X917467D03*
X927607Y199360D03*
X924227Y201309D03*
X944507Y197409D03*
X924227Y209109D03*
X920847Y203260D03*
X930987Y228610D03*
X937747Y224709D03*
X920847Y257860D03*
X934367Y230559D03*
X937747Y228610D03*
X927607Y222760D03*
X947887D03*
X954647D03*
X920847Y242260D03*
Y261760D03*
Y246160D03*
Y250060D03*
X927607Y226660D03*
X951267Y224709D03*
X920847Y253960D03*
X917467Y248109D03*
X930987Y224709D03*
X934367Y222760D03*
X917467Y255909D03*
X974926Y238360D03*
Y246160D03*
X971546Y240309D03*
Y244209D03*
X930987Y267609D03*
X927607Y238360D03*
X930987Y236409D03*
X934367Y250060D03*
X937747Y248109D03*
X927607Y242260D03*
X934367Y238360D03*
X937747Y263709D03*
X927607Y257860D03*
X930987Y255909D03*
X934367Y269560D03*
X937747Y267609D03*
X927607Y261760D03*
X934367Y257860D03*
X930987Y248109D03*
X937747Y244209D03*
Y259809D03*
X927607Y246160D03*
X937747Y240309D03*
X927607Y265660D03*
X934367Y261760D03*
X930987Y244209D03*
X934367Y242260D03*
X930987Y263709D03*
X947887Y261760D03*
X944507Y232509D03*
X947887Y230559D03*
X951267Y244209D03*
X954647Y242260D03*
X944507Y236409D03*
X951267Y232509D03*
X961406Y230559D03*
X968166Y234460D03*
Y222760D03*
X971546Y224709D03*
X954647Y257860D03*
X961406Y234460D03*
X964786Y236409D03*
Y224709D03*
X971546Y228610D03*
X974926Y257860D03*
Y261760D03*
X944507Y252009D03*
X947887Y250060D03*
X951267Y263709D03*
X954647Y261760D03*
X944507Y255909D03*
X951267Y252009D03*
X947887Y242260D03*
X954647Y238360D03*
Y253960D03*
X944507Y240309D03*
X961406Y226660D03*
X964786Y263709D03*
X954647Y234460D03*
X971546Y232509D03*
X964786Y275409D03*
X944507Y259809D03*
X951267Y255909D03*
X947887Y238360D03*
X964786Y228610D03*
Y267609D03*
X951267Y236409D03*
X968166Y230559D03*
X964786Y271509D03*
X947887Y257860D03*
X961406Y265660D03*
Y273460D03*
X971546Y267609D03*
Y271509D03*
X958026Y267609D03*
Y271509D03*
X968166Y265660D03*
Y273460D03*
X937747Y279310D03*
X917000Y276000D03*
X920847Y277360D03*
X924227Y279310D03*
Y283209D03*
X927607Y281260D03*
X920847D03*
X916967Y279310D03*
X934367Y281260D03*
X930987Y279310D03*
Y283209D03*
X937747D03*
X944507D03*
Y279310D03*
X958026D03*
X954647Y281260D03*
X958026Y283209D03*
X951267Y279310D03*
Y283209D03*
X961406Y281260D03*
X941127D03*
X947887D03*
X917467Y271509D03*
X961406Y242260D03*
X964786Y244209D03*
X961406Y246160D03*
X964786Y248109D03*
X958026D03*
X968166Y250060D03*
X971546Y252009D03*
X944507Y267609D03*
X947887Y269560D03*
X951267Y271509D03*
X947887Y273460D03*
X941127D03*
X927607D03*
X974926Y277360D03*
X971546Y279310D03*
X944507Y271509D03*
X924227D03*
X920847Y335860D03*
Y331960D03*
Y343660D03*
Y339760D03*
X917467Y345609D03*
Y337809D03*
X937747Y333909D03*
X930987Y330009D03*
Y341709D03*
X927607Y339760D03*
X937747Y330009D03*
X934367Y328060D03*
Y339760D03*
X927607Y335860D03*
Y331960D03*
X934367Y335860D03*
X930987Y333909D03*
X937747Y337809D03*
X954647Y339760D03*
X947887Y335860D03*
X954647D03*
X951267Y333909D03*
X944507Y341709D03*
Y337809D03*
X968166Y328060D03*
Y335860D03*
X951267Y341709D03*
X947887Y339760D03*
X968166Y324160D03*
Y331960D03*
X954647Y343660D03*
X964786Y326110D03*
Y333909D03*
X974926Y328060D03*
Y331960D03*
X961406Y328060D03*
Y331960D03*
X971546Y326110D03*
Y333909D03*
X937747Y287109D03*
X920500Y304660D03*
Y300760D03*
X930987Y302709D03*
X924227D03*
X920500Y311960D03*
X927607Y304660D03*
X924227Y306609D03*
X930987D03*
Y310509D03*
X934367Y304660D03*
X924227Y310509D03*
X920500Y308560D03*
Y289060D03*
X934367Y296860D03*
X930987Y294909D03*
X920500Y296860D03*
Y292959D03*
X927607Y296860D03*
X924227Y298809D03*
X930987D03*
X920500Y285500D03*
X924227Y287109D03*
X930987D03*
X934367Y289060D03*
X924227Y291009D03*
X930987D03*
X927607Y289060D03*
X937747Y302709D03*
Y306609D03*
Y310509D03*
Y291009D03*
Y294909D03*
Y298809D03*
Y314409D03*
X924227D03*
X930987D03*
X934367Y312460D03*
X927607D03*
X920847Y324160D03*
X924227Y318309D03*
X920547Y316160D03*
X917167Y318309D03*
Y322209D03*
X917467Y326110D03*
X920847Y320260D03*
X971546Y294909D03*
X964786Y291009D03*
X951267Y287109D03*
X958026D03*
X961406Y296860D03*
X964786Y298809D03*
Y302709D03*
X971546D03*
X961406Y304660D03*
X958026Y302709D03*
X951267D03*
X968166Y308560D03*
X964786Y306609D03*
X968166Y304660D03*
X971546Y306609D03*
X974926Y304660D03*
Y308560D03*
X951267Y310509D03*
X954647Y304660D03*
X958026Y306609D03*
Y310509D03*
X951267Y306609D03*
X944507Y302709D03*
Y306609D03*
Y310509D03*
X941127Y304660D03*
X947887D03*
X944507Y294909D03*
Y287109D03*
X971546Y298809D03*
X974926Y285160D03*
Y296860D03*
Y289060D03*
X968166Y285160D03*
X964786Y287109D03*
X944507Y291009D03*
X941127Y289060D03*
Y296860D03*
X944507Y298809D03*
X947887Y289060D03*
Y296860D03*
X968166D03*
X964786Y294909D03*
X971546Y291009D03*
Y287109D03*
X968166Y289060D03*
X961406D03*
X958026Y298809D03*
X951267D03*
Y291009D03*
X958026D03*
X954647Y289060D03*
Y296860D03*
X958026Y294909D03*
X951267D03*
X944507Y314409D03*
X951267D03*
X958026D03*
X961406Y312460D03*
X954647D03*
X941127D03*
X947887D03*
X951267Y326110D03*
X958026Y322209D03*
X954647Y320260D03*
X961406D03*
X954647Y324160D03*
X951267Y322209D03*
X964786Y318309D03*
X971546D03*
X974926Y320260D03*
X968166Y316360D03*
X974926D03*
X971546Y314409D03*
X947887Y324160D03*
Y320260D03*
X941127D03*
X934367D03*
X937747Y322209D03*
X930987D03*
X941127Y324160D03*
X927607D03*
X944507Y326110D03*
Y330009D03*
X971546Y341709D03*
Y345609D03*
X937747Y372909D03*
X930987Y369010D03*
Y380709D03*
X927607Y378760D03*
X937747Y369010D03*
X934367Y367060D03*
Y378760D03*
X927607Y374860D03*
X947887D03*
Y382660D03*
X958026Y376809D03*
Y380709D03*
X944507Y376809D03*
Y380709D03*
X954647Y374860D03*
Y382660D03*
X920847Y351460D03*
Y347560D03*
X934367Y374860D03*
X951267Y376809D03*
X927607Y370959D03*
X951267Y384609D03*
X937747Y376809D03*
X951267Y372909D03*
X930987D03*
X951267Y380709D03*
X974926Y351460D03*
Y359260D03*
X971546Y353409D03*
Y357309D03*
X934367Y359260D03*
X930987Y361209D03*
X937747Y349509D03*
X934367Y347560D03*
X927607Y355360D03*
Y359260D03*
X934367Y386560D03*
Y394359D03*
X944507Y388509D03*
Y392410D03*
X930987Y388509D03*
Y392410D03*
X941127Y386560D03*
Y394359D03*
X937747Y353409D03*
X930987Y349509D03*
X934367Y355360D03*
X937747Y388509D03*
X927607Y351460D03*
X937747Y396309D03*
Y357309D03*
Y384609D03*
X930987Y353409D03*
X937747Y392410D03*
X951267Y365109D03*
X947887Y367060D03*
X954647Y355360D03*
X951267Y353409D03*
X944507Y361209D03*
Y365109D03*
X968166Y363160D03*
X961406Y367060D03*
X971546Y372909D03*
X968166Y374860D03*
X964786Y361209D03*
X961406Y363160D03*
X971546Y369010D03*
X964786Y372909D03*
X947887Y347560D03*
X944507Y345609D03*
X951267D03*
X954647Y359260D03*
X947887Y355360D03*
X951267Y361209D03*
X968166Y367060D03*
X944507Y357309D03*
X961406Y370959D03*
X954647Y363160D03*
X971546Y365109D03*
X947887Y359260D03*
X964786Y369010D03*
Y349509D03*
Y353409D03*
X961406Y355360D03*
Y347560D03*
Y351460D03*
X924227Y400209D03*
X930987D03*
X920847Y394359D03*
X917467Y392410D03*
X944507Y400209D03*
X964786Y384609D03*
Y380709D03*
X920847Y398260D03*
X927607D03*
X958026Y349509D03*
X924227Y396309D03*
X970669Y529014D03*
X974015D03*
X967322D03*
X961309Y499136D03*
X974015Y536957D03*
X960629D03*
X970669Y566814D03*
X974015D03*
Y574757D03*
X963976Y566814D03*
X960629Y574757D03*
X963976Y536957D03*
X970669D03*
X963976Y547914D03*
X970669D03*
X967322Y555857D03*
X960629D03*
X970669Y585714D03*
Y574757D03*
X963976Y585714D03*
Y574757D03*
X967322Y566814D03*
Y536957D03*
Y574757D03*
Y547914D03*
Y585714D03*
X957765Y607220D03*
X967322Y593657D03*
X963976Y612457D03*
X970669D03*
X960629Y604614D03*
X967322D03*
X960629Y593657D03*
X967322Y609864D03*
X1026700Y1700D03*
X977362Y35957D03*
X984055D03*
X980708Y28014D03*
X1004133Y28022D03*
X1004134Y35957D03*
X1000787Y28022D03*
X997441Y35957D03*
X994094D03*
Y28022D03*
X987401Y35957D03*
X990748Y28022D03*
X984054Y28014D03*
X980708Y-4536D03*
X987401Y-9901D03*
X997441Y-7108D03*
X990748Y-1743D03*
X977362Y-7108D03*
X980708Y9114D03*
X990748Y9122D03*
X977362Y28014D03*
X987401D03*
Y17057D03*
X977362D03*
X990748Y35957D03*
X980708D03*
X997441Y28022D03*
Y17057D03*
X1000787Y-4536D03*
Y9122D03*
X1017519Y-1858D03*
Y-9786D03*
X1007480Y-1858D03*
X1017519Y9114D03*
X1007480Y-9786D03*
X1000787Y35957D03*
X1007480Y17014D03*
Y28014D03*
X1017519D03*
Y35942D03*
X1025670Y6640D03*
X1020866Y-1858D03*
X1027202Y-11005D03*
X1028639Y-6615D03*
X977362Y73757D03*
X984055D03*
X980708Y65814D03*
X1004133Y65822D03*
X1004134Y73757D03*
X1000787Y65822D03*
X997441Y73757D03*
X994094D03*
Y65822D03*
X987401Y73757D03*
X990748Y65822D03*
X984054Y65814D03*
X987401D03*
X977362D03*
X987401Y54857D03*
X977362D03*
X990748Y46922D03*
X980708Y46914D03*
X997441Y65822D03*
Y54857D03*
X990748Y73757D03*
X980708D03*
X1000787Y46922D03*
X1017519Y54842D03*
X1007480Y46914D03*
Y65736D03*
X1016600Y65950D03*
X1000787Y73757D03*
X1035000Y81200D03*
X1008099Y73479D03*
X1017350Y73450D03*
X1030300Y63200D03*
X1022245Y207159D03*
X991826Y205210D03*
X1022245Y211060D03*
X995206Y207159D03*
X991826Y209109D03*
X998586Y205210D03*
X1018865Y213009D03*
X998586Y216909D03*
X1001965Y218860D03*
X995206D03*
X991826Y213009D03*
X988446Y214960D03*
X1025625Y216909D03*
X1015485Y218860D03*
X1022245D03*
X1012105Y216909D03*
X1032385Y213009D03*
X1035765Y211060D03*
X1029005Y207159D03*
X1018865Y216909D03*
X1032385D03*
X1029005Y218860D03*
X1008725Y211060D03*
X1012105Y213009D03*
X1008725Y218860D03*
X1005345Y216909D03*
Y213009D03*
X1035765Y218860D03*
X1025625Y213009D03*
X995206Y203260D03*
X988446Y218860D03*
X995206Y214960D03*
X1001965D03*
X1035765D03*
X1027875Y193507D03*
X1032385Y201309D03*
X1015485Y203260D03*
Y214960D03*
X1022245D03*
X1012105Y205210D03*
X1025625Y205211D03*
X1029005Y214960D03*
X1035765Y207159D03*
X1007595Y193507D03*
X1005345Y205210D03*
X1008725Y214960D03*
X991826Y216909D03*
X985066Y220809D03*
X988446Y207158D03*
Y203258D03*
X995206Y211060D03*
X998586Y213009D03*
X988446Y250060D03*
Y230560D03*
X978306Y236409D03*
Y248109D03*
Y240309D03*
Y244209D03*
X985066Y240309D03*
Y244209D03*
X981686Y238360D03*
Y246160D03*
X991826Y224709D03*
X995206Y230559D03*
X1025625Y224709D03*
X988446Y222760D03*
X1022245D03*
X1015485D03*
X1018865Y224709D03*
X1012105D03*
X1035765Y222760D03*
X1001965D03*
X998586Y224709D03*
X1032385D03*
X1029005Y222760D03*
X1008725D03*
X1005345Y224709D03*
X998586Y228610D03*
X1001965Y230559D03*
X998586Y236409D03*
Y240309D03*
X1029005Y230559D03*
X1015485Y242260D03*
X1001965Y234460D03*
X995206Y242260D03*
Y234460D03*
X991826Y240309D03*
Y228610D03*
Y236409D03*
X1022245Y234460D03*
X1015485D03*
X1022245Y230559D03*
X1015485D03*
X1018865Y236409D03*
X1012105D03*
X1018865Y228610D03*
X1012105D03*
X1032385D03*
Y236409D03*
X978306Y255909D03*
Y263709D03*
X988446Y257860D03*
Y261760D03*
X985066Y255909D03*
Y263709D03*
X981686Y253960D03*
Y265660D03*
Y257860D03*
Y261760D03*
X1025625Y236409D03*
X1018865Y240309D03*
X1001965Y246160D03*
X995206D03*
X1025625Y240309D03*
X1035765Y230559D03*
X1022245Y242260D03*
X1029005Y234460D03*
X1008725Y242260D03*
X1012105Y240309D03*
X1008725Y230559D03*
Y234460D03*
X1005345Y228610D03*
Y236409D03*
X1001965Y242260D03*
X1005345Y240309D03*
X1008725Y246160D03*
X1035765Y234460D03*
X1025625Y228610D03*
X995206Y277360D03*
Y281260D03*
X998586Y267609D03*
Y271509D03*
Y275409D03*
Y279310D03*
Y283209D03*
X1022245Y253960D03*
X1025625Y252009D03*
X1017735Y264300D03*
X1014355Y266300D03*
X1021115Y262300D03*
X1024495Y260300D03*
X1027875Y258400D03*
X1031255Y256400D03*
X1034635Y254259D03*
X1005345Y263709D03*
X1001965Y265660D03*
X1008725Y261760D03*
X1006665Y277360D03*
Y281260D03*
X1015485Y257860D03*
X1018865Y255909D03*
X1012105Y259809D03*
X998586Y244209D03*
Y232509D03*
X991826Y244209D03*
Y232509D03*
X995206Y226660D03*
X1032385Y232509D03*
X1035765Y226660D03*
X1018865Y244209D03*
X1012105D03*
X1018865Y232509D03*
X1015485Y226660D03*
X1022245D03*
X1012105Y232509D03*
X1025625D03*
X1029005Y226660D03*
X1005345Y244209D03*
X1008725Y226660D03*
X1005345Y232509D03*
X1001965Y226660D03*
X995206Y222760D03*
X981686D03*
X978306Y224709D03*
X981686Y226660D03*
X985066Y228610D03*
X978306D03*
X981686Y230559D03*
X985066Y232509D03*
X1012105Y248109D03*
X1008725Y250060D03*
X1001965D03*
X995206D03*
X1005345Y252009D03*
X998586D03*
X1008725Y253960D03*
X1001965D03*
X995206D03*
X1005345Y255909D03*
X998586D03*
X1001965Y257860D03*
X995206D03*
X998586Y259809D03*
X995206Y261760D03*
X988446Y269560D03*
X985066Y271509D03*
X978306D03*
X988446Y273460D03*
X981686D03*
X985066Y275409D03*
X978306D03*
X988446Y277360D03*
X981686D03*
X985066Y279310D03*
X978306D03*
X1032385Y240309D03*
X1035765Y242260D03*
X1029005D03*
X1032385Y244209D03*
X1025625D03*
X1035765Y246160D03*
X1029005D03*
X1022245D03*
X1015485D03*
X1018865Y248109D03*
X1015485Y250060D03*
X1012105Y252009D03*
X991826D03*
Y248109D03*
X998586Y337809D03*
X981686Y335860D03*
Y343660D03*
X991826Y337809D03*
Y341709D03*
X978306Y337809D03*
Y341709D03*
X988446Y335860D03*
Y343660D03*
X985066Y337809D03*
Y333909D03*
Y341709D03*
X995206Y296860D03*
X985066Y294909D03*
Y287109D03*
X988446Y285160D03*
X991826Y287109D03*
X978306Y298809D03*
Y287109D03*
X981686Y285160D03*
X978306Y294909D03*
X981686Y296860D03*
Y289060D03*
X978306Y291009D03*
X998586Y302709D03*
Y306609D03*
Y310509D03*
Y287109D03*
Y294909D03*
Y291009D03*
Y298809D03*
X985066Y302709D03*
X978306D03*
X988446Y304660D03*
Y308560D03*
X985066Y306609D03*
X995206Y304660D03*
Y308560D03*
X991826Y306609D03*
X978306D03*
X981686Y308560D03*
Y304660D03*
X995206Y300760D03*
X991826Y302709D03*
X995206Y292959D03*
X988446Y296860D03*
X991826Y294909D03*
X995206Y289060D03*
X988446D03*
X991826Y291009D03*
X985066D03*
X995206Y285160D03*
X985066Y298809D03*
X991826D03*
X998586Y314409D03*
X995206Y312460D03*
X998586Y318309D03*
Y322209D03*
Y326110D03*
Y330009D03*
X995206Y316360D03*
X1006665Y300760D03*
Y304660D03*
Y308560D03*
Y285160D03*
Y296860D03*
Y289060D03*
Y292959D03*
X1008725Y335860D03*
X1005345Y333909D03*
X1001965Y331960D03*
X1007595Y327609D03*
X1021115Y335409D03*
X1018865Y341709D03*
X1017735Y333460D03*
X1015485Y339760D03*
X1024495Y337360D03*
X1012105Y337809D03*
X1006665Y312460D03*
X1014355Y331509D03*
X1010975Y329560D03*
X1027875Y339309D03*
X1034635Y343209D03*
X1031255Y341260D03*
X1006665Y324160D03*
Y316360D03*
Y320260D03*
X1022245Y343660D03*
X981686Y324160D03*
X988446Y320260D03*
X985066Y322209D03*
Y318309D03*
X988446Y324160D03*
Y328060D03*
X981686D03*
X985066Y326110D03*
X981686Y320260D03*
X978306Y322209D03*
Y318309D03*
X981686Y316360D03*
X978306Y314409D03*
X985066D03*
X998586Y341709D03*
Y345609D03*
X1001965Y343660D03*
Y339760D03*
X1008725Y343660D03*
X1012105Y345609D03*
X1005345Y341709D03*
X991826Y384609D03*
X991500Y396301D03*
X1022245Y390460D03*
X995206Y386560D03*
X978306Y353409D03*
Y361209D03*
Y349509D03*
Y357309D03*
X985066Y353409D03*
Y357309D03*
X981686Y351460D03*
Y359260D03*
X1022245Y386560D03*
X998586Y388509D03*
X991826Y380709D03*
X1000800Y402800D03*
X995206Y378760D03*
X998586Y380709D03*
X1025625Y372909D03*
X1018865Y384609D03*
X995206Y367060D03*
X998586Y372909D03*
X991826D03*
X988446Y374860D03*
Y370959D03*
Y378760D03*
X1018865Y372909D03*
X1012105D03*
X1022245Y378760D03*
X1012105Y380709D03*
X1022245Y374860D03*
X1015485D03*
X1025625Y380709D03*
X1015485Y378760D03*
X1032385Y384609D03*
X1035765Y374860D03*
Y386560D03*
X1029005D03*
X1018865Y380709D03*
X1001965Y378760D03*
Y374860D03*
X1032385Y380709D03*
Y372909D03*
X1029005Y378760D03*
Y374860D03*
X1008725Y386560D03*
X1012105Y384609D03*
X1008725Y378760D03*
X1005345Y380709D03*
X1008725Y374860D03*
X1005345Y372909D03*
X998586Y369010D03*
X1001965Y367060D03*
X1005345Y384609D03*
X1035765Y378760D03*
X1025625Y384609D03*
X995206Y355360D03*
X998586Y357309D03*
X1029005Y367060D03*
X1015485Y355360D03*
X995206Y351460D03*
X998586Y361209D03*
X995206Y363160D03*
X991826Y357309D03*
Y369010D03*
Y361209D03*
X1018865Y369010D03*
X1012105D03*
X1018865Y361209D03*
X1012105D03*
X1022245Y367060D03*
X1015485D03*
X1022245Y363160D03*
X1015485D03*
X1032385Y369010D03*
Y361209D03*
X985066Y345609D03*
X1025625Y361209D03*
X1018865Y357309D03*
X1001965Y351460D03*
Y363160D03*
X1025625Y357309D03*
X1035765Y367060D03*
X1022245Y355360D03*
X1029005Y363160D03*
X1008725Y355360D03*
X1012105Y357309D03*
X1008725Y363160D03*
Y367060D03*
X1005345Y361209D03*
Y369010D03*
X1001965Y355360D03*
X1005345Y357309D03*
X1008725Y351460D03*
X1035765Y363160D03*
X1025625Y369010D03*
X988446Y367060D03*
X998586Y365109D03*
Y353409D03*
X991826Y365109D03*
X995206Y370959D03*
X991826Y353409D03*
X998586Y392410D03*
X988446Y382660D03*
X995206D03*
X1005345Y365109D03*
X1008725Y370959D03*
X1001965D03*
X1005345Y353409D03*
X1018865Y365109D03*
X1012105D03*
X1025625D03*
X1022245Y370959D03*
X1015485D03*
X1018865Y353409D03*
X1012105D03*
X1025625D03*
X1029005Y370959D03*
X1035765D03*
X1032385Y365109D03*
X1007595Y402800D03*
X1008725Y382660D03*
X1001965D03*
X1005345Y392410D03*
X1029005Y390460D03*
X1025625Y392410D03*
X1022245Y382660D03*
X1015485D03*
X1012105Y392410D03*
X1018865D03*
X1029005Y382660D03*
X1035765D03*
X1027875Y402800D03*
X1005345Y345609D03*
X1018865Y349509D03*
X1032385Y353409D03*
X1035765Y355360D03*
X998586Y384609D03*
X985066Y376809D03*
X981686Y374860D03*
X995206D03*
X978306Y372909D03*
X981686Y370959D03*
X978306Y369010D03*
X985066D03*
X981686Y367060D03*
X985066Y365109D03*
X988446Y363160D03*
X1032385Y357309D03*
X1029005Y355360D03*
X1015485Y351460D03*
X1022245D03*
X1029005D03*
X991826Y349509D03*
X1012105D03*
X1025625D03*
X995206Y347560D03*
X1001965D03*
X1015485D03*
X1008725D03*
X980708Y529014D03*
X1004133Y529022D03*
X1000787D03*
X994094D03*
X990748D03*
X984054Y529014D03*
X977362D03*
X987401D03*
X997441Y529022D03*
X1017519Y529057D03*
X1007480Y528942D03*
X1035000Y521556D03*
X977362Y536957D03*
X984055D03*
X1004134D03*
X997441D03*
X994094D03*
X987401D03*
X977362Y574757D03*
X984055D03*
X980708Y566814D03*
X1004133Y566822D03*
X1004134Y574757D03*
X1000787Y566822D03*
X997441Y574757D03*
X994094D03*
Y566822D03*
X987401Y574757D03*
X990748Y566822D03*
X984054Y566814D03*
X990748Y536957D03*
X980708D03*
X990748Y547922D03*
X980708Y547914D03*
X977362Y555857D03*
X987401D03*
X997441D03*
X977362Y566814D03*
X990748Y574757D03*
Y585722D03*
X980708Y585714D03*
Y574757D03*
X997441Y566822D03*
X987401Y566814D03*
X1000787Y536957D03*
Y547922D03*
X1017300Y536200D03*
Y547914D03*
X1007518Y536727D03*
X1019277Y585714D03*
X1000787Y585722D03*
Y574757D03*
X1007518Y555842D03*
Y566814D03*
X1007480Y574742D03*
X1026500Y581000D03*
X1026400Y543700D03*
X977362Y593657D03*
X987401D03*
X997441D03*
Y607292D03*
X977362D03*
X990748Y612457D03*
X980708Y609864D03*
X987401Y604499D03*
X1007480Y612242D03*
X1000787Y609864D03*
X1007480Y604614D03*
X1029777Y613581D03*
X1020800Y612600D03*
X1071062Y-1817D03*
X1071064Y9122D03*
X1054331Y28022D03*
X1050985Y35957D03*
X1087797D03*
X1064371Y28022D03*
X1094488D03*
X1094490Y35957D03*
X1054331D03*
X1077757D03*
X1064371D03*
X1071064Y28022D03*
X1084450Y35957D03*
X1087797Y28022D03*
X1044292Y35957D03*
X1047637Y-4536D03*
X1057676Y-1743D03*
X1050983Y-7108D03*
X1050985Y28022D03*
X1047637Y35942D03*
X1050984Y17042D03*
X1057677Y35942D03*
X1061023Y-9786D03*
X1067716Y-4536D03*
Y-9901D03*
X1081102Y-4536D03*
X1074409D03*
X1084448Y-7108D03*
X1077755D03*
X1091141Y-1843D03*
X1067716Y9107D03*
X1091141D03*
X1074409D03*
X1081102D03*
X1071064Y35957D03*
X1061024Y17057D03*
Y28022D03*
X1067716Y35942D03*
Y28007D03*
Y17042D03*
X1091141Y35942D03*
Y17042D03*
X1081102Y35942D03*
X1077757Y28022D03*
X1074409Y35942D03*
X1084450Y28098D03*
Y17057D03*
X1077757D03*
X1091141Y28007D03*
X1097834Y11100D03*
X1061024Y35957D03*
X1061023Y-4536D03*
X1071064Y46922D03*
Y73757D03*
X1054331Y65822D03*
X1050985Y73757D03*
X1087797D03*
X1064371Y65822D03*
X1094488D03*
X1054331Y73757D03*
X1077757D03*
X1064371D03*
X1071064Y65822D03*
X1084450Y73757D03*
X1087797Y65822D03*
X1050984Y54842D03*
X1050985Y65822D03*
X1057677Y73742D03*
X1047637D03*
X1061024Y54857D03*
Y65822D03*
X1067716Y54842D03*
Y46907D03*
Y65807D03*
X1091141Y54842D03*
X1084450Y54857D03*
X1077757D03*
X1081102Y46907D03*
X1074409D03*
X1091141D03*
X1084450Y65822D03*
X1077757D03*
X1091141Y65807D03*
X1067716Y73742D03*
X1074409D03*
X1081102D03*
X1091141D03*
X1061024Y73757D03*
X1044290Y68964D03*
X1049284Y207159D03*
X1085721Y220096D03*
X1095861Y222047D03*
X1082341D03*
X1092481Y220096D03*
X1089101Y218147D03*
Y222047D03*
X1042524Y211060D03*
X1039145Y213009D03*
X1045904D03*
Y216909D03*
X1049284Y218860D03*
X1057314Y216909D03*
X1065242Y220096D03*
Y216196D03*
X1075582Y222047D03*
X1072202Y220096D03*
X1068822Y218147D03*
Y222047D03*
X1042524Y218860D03*
X1039145Y216909D03*
X1042524Y214960D03*
X1042506Y195041D03*
X1045904Y197359D03*
X1054000Y199100D03*
X1042524Y203260D03*
X1049284Y214960D03*
Y203260D03*
Y211060D03*
X1065242Y239596D03*
Y243496D03*
X1068822Y245447D03*
X1045904Y244209D03*
Y240309D03*
X1085721Y227896D03*
X1095861Y225947D03*
X1082341D03*
X1092481Y227896D03*
X1089101Y229847D03*
Y225947D03*
X1045904Y228610D03*
X1039145Y224709D03*
X1049284Y222760D03*
X1075582Y225947D03*
X1065242Y227896D03*
Y231797D03*
X1072202Y227896D03*
X1068822Y225947D03*
Y229847D03*
X1042524Y222760D03*
X1045904Y224709D03*
X1057314Y236409D03*
X1039145D03*
X1049284Y230559D03*
Y234460D03*
X1042524Y230559D03*
X1057314Y224709D03*
Y228610D03*
X1075582Y233746D03*
Y241547D03*
X1085721Y235696D03*
Y239596D03*
X1072202Y235696D03*
Y239596D03*
X1082341Y233746D03*
Y241547D03*
X1095861Y233746D03*
Y241547D03*
X1092481Y235696D03*
Y239596D03*
X1078962Y231797D03*
X1099241D03*
X1078962Y243496D03*
X1099241D03*
X1078962Y235696D03*
X1099241D03*
X1078962Y239596D03*
X1099241D03*
X1049284Y238360D03*
X1042524Y234460D03*
X1039145Y228610D03*
X1045904Y236409D03*
X1038015Y256500D03*
X1041395Y254259D03*
X1048154D03*
X1051534Y256500D03*
X1044774Y256400D03*
X1054914Y254500D03*
X1067692Y254000D03*
X1071072Y255728D03*
X1087971Y257800D03*
X1091351Y259600D03*
X1094731Y261500D03*
X1098111Y263400D03*
X1084591Y255497D03*
X1081212Y257600D03*
X1092481Y247396D03*
X1089101Y245447D03*
X1085721Y247396D03*
X1089101Y249347D03*
X1092481Y251296D03*
X1095861Y249347D03*
Y253247D03*
X1042524Y226660D03*
X1039145Y232509D03*
X1057314Y240309D03*
X1049284Y226660D03*
X1045904Y232509D03*
X1057314D03*
X1072202Y247396D03*
X1079859Y265000D03*
X1049284Y242260D03*
X1039145Y240309D03*
X1042524Y242260D03*
X1039145Y244209D03*
X1042524Y246160D03*
X1057314Y244209D03*
X1049284Y246160D03*
X1038015Y345160D03*
X1044774D03*
X1051534D03*
X1098111Y344597D03*
X1044256Y338341D03*
X1076435Y343595D03*
X1042524Y355360D03*
X1045904Y357309D03*
X1039145D03*
X1045904Y384609D03*
X1093601Y381947D03*
Y389747D03*
X1090221Y383896D03*
Y387796D03*
X1096981Y383896D03*
Y391696D03*
Y379996D03*
Y387796D03*
X1042524Y386560D03*
X1039145Y384609D03*
X1049284Y390460D03*
X1045904Y380709D03*
X1049284Y378760D03*
X1045904Y369010D03*
X1039145Y372909D03*
X1052664Y380709D03*
X1049284Y374860D03*
X1073322Y389747D03*
Y393647D03*
X1083462Y383896D03*
Y387796D03*
X1073322Y378047D03*
Y381947D03*
X1080082D03*
Y389747D03*
X1076702Y383896D03*
Y391696D03*
Y379996D03*
Y387796D03*
X1042524Y378760D03*
Y374860D03*
X1039145Y380709D03*
X1045904Y372909D03*
X1052664Y361209D03*
X1039145D03*
X1049284Y367060D03*
Y363160D03*
X1042524Y367060D03*
X1052664Y372909D03*
Y369010D03*
X1076702Y364396D03*
X1073322Y370247D03*
X1086841Y366347D03*
Y370247D03*
X1073322Y358547D03*
Y366347D03*
X1083462Y364396D03*
Y372197D03*
X1093601Y354647D03*
Y362447D03*
X1090221Y356596D03*
Y360496D03*
X1080082Y366347D03*
X1096981Y356596D03*
X1080082Y370247D03*
X1096981Y364396D03*
X1080082Y362447D03*
X1096981Y352696D03*
X1080082Y374146D03*
X1096981Y360496D03*
X1049284Y359260D03*
X1042524Y363160D03*
X1039145Y369010D03*
X1045904Y361209D03*
X1041395Y347109D03*
X1048154D03*
X1071072Y348497D03*
X1087971Y346546D03*
X1074452D03*
X1081212D03*
X1077832Y348497D03*
X1084591D03*
X1052664Y357309D03*
X1049284Y370959D03*
X1042524D03*
X1045904Y365109D03*
X1039145D03*
X1052664D03*
Y392410D03*
X1040265Y394359D03*
X1049284Y382660D03*
X1042524D03*
Y390460D03*
X1056176Y402471D03*
X1041395Y402800D03*
X1061039Y359351D03*
X1060963Y370959D03*
X1060694Y355360D03*
X1061055Y363160D03*
X1052664Y353409D03*
X1064371Y367060D03*
X1052664Y396309D03*
X1060694Y394359D03*
Y390460D03*
X1049284Y386560D03*
X1060694D03*
Y382660D03*
Y378760D03*
X1048154Y402900D03*
X1086841Y378047D03*
X1090221Y376096D03*
X1093601Y374146D03*
Y370247D03*
X1049284Y355360D03*
X1080082Y358547D03*
X1083462Y356596D03*
X1052500Y400400D03*
X1054331Y529022D03*
X1071064D03*
X1050985D03*
X1061024D03*
X1091141Y529007D03*
X1084450Y529022D03*
X1077757D03*
X1067716Y529007D03*
X1044195Y529026D03*
X1071064Y547922D03*
Y585722D03*
X1050985Y536957D03*
X1087797D03*
X1094490D03*
X1054331D03*
X1077757D03*
X1064371D03*
X1084450D03*
X1054331Y566822D03*
X1050985Y574757D03*
X1087797D03*
X1064371Y566822D03*
X1094488D03*
X1094490Y574757D03*
X1054331D03*
X1077757D03*
X1064371D03*
X1071064Y566822D03*
X1084450Y574757D03*
X1087797Y566822D03*
X1044292Y574757D03*
X1067716Y547907D03*
X1057677Y536942D03*
X1047637D03*
X1057677Y574742D03*
X1047637D03*
X1050985Y566822D03*
X1050984Y555842D03*
X1074409Y547907D03*
X1081102D03*
X1091141D03*
Y536942D03*
X1074409D03*
X1081102D03*
X1067716D03*
X1071064Y574757D03*
X1061024Y555857D03*
Y566822D03*
X1077757Y555857D03*
X1084450D03*
X1091141Y555842D03*
X1067716D03*
X1081102Y574742D03*
Y585707D03*
X1074409D03*
X1091141Y574742D03*
Y585707D03*
X1067716Y574742D03*
Y585599D03*
Y566807D03*
X1091141D03*
X1074409Y574742D03*
X1084450Y566822D03*
X1077757D03*
X1097343Y588394D03*
X1061024Y536957D03*
Y574757D03*
X1044290Y569492D03*
X1071062Y612560D03*
X1091141Y612557D03*
X1057676Y612657D03*
X1050984Y593642D03*
X1047637Y609864D03*
X1050983Y607292D03*
X1061024Y593657D03*
X1061023Y604614D03*
X1077757Y593657D03*
X1084450D03*
X1067716Y593642D03*
Y609864D03*
Y604499D03*
X1081102Y609864D03*
X1091141Y593642D03*
Y607292D03*
X1084448D03*
X1077755D03*
X1074409Y609864D03*
X1097374Y612659D03*
X1061023Y609864D03*
X1044290Y607292D03*
X1106001Y220096D03*
X1116141Y222047D03*
X1102621D03*
X1112761Y220096D03*
X1126280D03*
X1122900Y222047D03*
X1133040Y216196D03*
Y220096D03*
X1109381Y218147D03*
X1129660D03*
X1109381Y222047D03*
X1129660D03*
Y210346D03*
X1133040Y212296D03*
X1144300Y216196D03*
Y212296D03*
X1147680Y218147D03*
X1154440Y214247D03*
X1151060Y220096D03*
X1157820Y216196D03*
X1144300Y220096D03*
X1147680Y214247D03*
X1151060Y216196D03*
X1154440Y218147D03*
Y222047D03*
X1161200Y214247D03*
X1134160Y272747D03*
Y276646D03*
X1151060Y270796D03*
Y255196D03*
Y251296D03*
X1154440Y280547D03*
X1157820Y282496D03*
X1144300D03*
X1140920Y280547D03*
X1136420Y261047D03*
X1133040Y262996D03*
X1147680Y264947D03*
X1106001Y227896D03*
X1116141Y225947D03*
X1102621D03*
X1112761Y227896D03*
X1126280D03*
X1133040D03*
Y231797D03*
X1122900Y225947D03*
X1109381Y229847D03*
X1129660Y225947D03*
X1109381D03*
X1129660Y229847D03*
X1116141Y233746D03*
Y241547D03*
X1126280Y235696D03*
Y239596D03*
X1112761Y235696D03*
Y239596D03*
X1122900Y233746D03*
Y241547D03*
X1119521Y231797D03*
Y243496D03*
Y235696D03*
Y239596D03*
X1106001Y235696D03*
Y239596D03*
X1102621Y233746D03*
Y241547D03*
X1106001Y247396D03*
Y255196D03*
X1116141Y249347D03*
Y253247D03*
X1102621Y249347D03*
Y253247D03*
X1112761Y247396D03*
Y255196D03*
X1126280Y247396D03*
Y255196D03*
X1136420Y249347D03*
Y253247D03*
X1122900Y249347D03*
Y253247D03*
X1133040Y247396D03*
Y255196D03*
X1109381Y245447D03*
X1129660D03*
X1109381Y257147D03*
X1129660D03*
X1109381Y249347D03*
X1129660D03*
X1109381Y253247D03*
X1129660D03*
X1147680Y280547D03*
X1157820Y274696D03*
X1154440Y268847D03*
X1140920Y272747D03*
X1114340Y280560D03*
X1154440Y276647D03*
X1101491Y265400D03*
X1104871Y267300D03*
X1119521Y282496D03*
X1116141Y268847D03*
X1112761Y262996D03*
X1116141Y261047D03*
X1119521Y278596D03*
X1144300Y223996D03*
X1154440Y225947D03*
X1147680Y245447D03*
X1127400Y280547D03*
Y276646D03*
X1134160Y280547D03*
X1102336Y274819D03*
X1108125Y276799D03*
X1144300Y266896D03*
X1154440Y257147D03*
X1157820Y251296D03*
X1154440Y249347D03*
X1157820Y247396D03*
X1107600Y271900D03*
X1147680Y249347D03*
X1157820Y266896D03*
X1147680Y276647D03*
X1140920D03*
X1161200Y276646D03*
X1154440Y272747D03*
X1147680Y253247D03*
Y257147D03*
X1109381Y264947D03*
X1151060Y243496D03*
X1144300Y239596D03*
X1151060Y235696D03*
X1144300Y227896D03*
X1154440Y233746D03*
X1147680Y229847D03*
X1154440Y237647D03*
X1157820Y227896D03*
X1147680Y241547D03*
Y237647D03*
X1151060Y239596D03*
X1144300Y231797D03*
X1151060D03*
Y227896D03*
X1157820Y235696D03*
X1161200Y237647D03*
Y280547D03*
X1130780Y282496D03*
X1119521Y266896D03*
Y262996D03*
X1122900Y261047D03*
X1119521Y259096D03*
X1157820Y243496D03*
X1147680Y272747D03*
X1151060Y278596D03*
X1133040Y239596D03*
X1137540Y266896D03*
X1147680Y268847D03*
X1137540Y270796D03*
X1140920Y268847D03*
Y264947D03*
X1144300Y262996D03*
X1126280Y266896D03*
X1129660Y264947D03*
X1122900D03*
Y268847D03*
X1126280Y262996D03*
X1154440Y264947D03*
X1147680Y261047D03*
X1144300Y259096D03*
X1151060Y262996D03*
X1154440Y261047D03*
X1144300Y274696D03*
X1124021Y344896D03*
X1130780Y321496D03*
X1137540Y313696D03*
X1130780Y325396D03*
X1140920Y315647D03*
X1134160Y319547D03*
X1130780Y317596D03*
Y333196D03*
X1134160Y331247D03*
X1151060Y337096D03*
X1140920Y288347D03*
Y284447D03*
X1147680D03*
Y288347D03*
X1151060Y286396D03*
X1144300Y290296D03*
X1147680Y292247D03*
X1154440D03*
Y288347D03*
Y284447D03*
X1157820Y286396D03*
X1114839Y320075D03*
X1113132Y291702D03*
X1113500Y323400D03*
X1137540Y286396D03*
X1101491Y342646D03*
X1119521Y301996D03*
Y298096D03*
Y294196D03*
Y290296D03*
X1118391Y332897D03*
X1127400Y284447D03*
Y300047D03*
X1130780Y294196D03*
X1127400Y296147D03*
Y292247D03*
X1130780Y298096D03*
Y305896D03*
X1137540Y290296D03*
X1134160Y296147D03*
Y288347D03*
X1124021Y325396D03*
X1127400Y323446D03*
X1124021Y329296D03*
Y333196D03*
X1154440Y327347D03*
X1147680Y339047D03*
X1157820Y321496D03*
X1134160Y284447D03*
X1157820Y309797D03*
X1120641Y339047D03*
X1113881Y342947D03*
X1130780Y329296D03*
Y286396D03*
X1134160Y311747D03*
Y315647D03*
X1161200Y288347D03*
Y292247D03*
X1140920Y323446D03*
X1147680Y307847D03*
X1151060Y309797D03*
Y305896D03*
X1144300Y301996D03*
Y298096D03*
X1137540Y301996D03*
X1134160Y303947D03*
X1137540Y298096D03*
X1140920Y303947D03*
X1137540Y305896D03*
X1140920Y296147D03*
X1137540Y294196D03*
X1120641Y342947D03*
X1140920D03*
X1110501Y344896D03*
X1119521Y309797D03*
Y313696D03*
Y317596D03*
X1127400Y311747D03*
X1154440D03*
X1157820Y305896D03*
X1154440Y303947D03*
X1157820Y301996D03*
X1154440Y300047D03*
X1134160Y307847D03*
X1151060Y294196D03*
X1147680Y300047D03*
Y296147D03*
X1140920Y307847D03*
Y311747D03*
X1151060Y301996D03*
X1144300Y305896D03*
X1147680Y311747D03*
X1157820Y298096D03*
X1154440Y296147D03*
X1134160Y335147D03*
Y339047D03*
X1140920Y319547D03*
X1144300Y313696D03*
X1151060D03*
X1144300Y325396D03*
Y321496D03*
X1151060Y329296D03*
X1147680Y335147D03*
Y331247D03*
X1140920Y335147D03*
X1144300Y333196D03*
X1151060Y325396D03*
Y321496D03*
X1147680Y323446D03*
X1137540Y329296D03*
X1144300D03*
X1140920Y327347D03*
X1130780Y340996D03*
Y337096D03*
X1127400Y331247D03*
Y335147D03*
Y339047D03*
X1147680Y315647D03*
X1151060Y317596D03*
X1137540Y337096D03*
Y340996D03*
Y333196D03*
X1134160Y342947D03*
X1137540Y344896D03*
X1144300Y317596D03*
X1137540Y321496D03*
X1134160Y327347D03*
X1137540Y325396D03*
X1109200Y325100D03*
X1127400Y346847D03*
X1130780Y348796D03*
X1127400Y350747D03*
X1103741Y383896D03*
Y387796D03*
X1100361Y381947D03*
Y389747D03*
X1113881Y381947D03*
Y389747D03*
X1124021Y383896D03*
Y387796D03*
X1110501Y383896D03*
Y387796D03*
X1120641Y381947D03*
Y389747D03*
X1134160Y381947D03*
Y389747D03*
X1144300Y395597D03*
Y399496D03*
X1130780Y383896D03*
Y387796D03*
X1140920Y401447D03*
Y393647D03*
X1117261Y379996D03*
X1137540D03*
X1117261Y391696D03*
X1137540D03*
X1117261Y383896D03*
X1137540D03*
X1117261Y387796D03*
X1137540D03*
X1124021Y368296D03*
Y376096D03*
X1130780Y364396D03*
X1134160Y374146D03*
X1120641Y370247D03*
Y374146D03*
X1130780Y368296D03*
Y376096D03*
X1127400Y370247D03*
Y378047D03*
Y366347D03*
Y374146D03*
X1103741Y368296D03*
Y376096D03*
X1113881Y370247D03*
Y374146D03*
X1100361Y370247D03*
Y374146D03*
X1110501Y368296D03*
Y376096D03*
X1103741Y356596D03*
Y360496D03*
X1100361Y354647D03*
Y362447D03*
X1113881Y354647D03*
Y362447D03*
X1124021Y356596D03*
Y360496D03*
X1110501Y356596D03*
Y360496D03*
X1120641Y354647D03*
Y362447D03*
X1107121Y370247D03*
X1117261Y356596D03*
X1107121Y378047D03*
X1117261Y364396D03*
X1107121Y366347D03*
X1117261Y352696D03*
X1107121Y374146D03*
X1117261Y360496D03*
X1157820Y356596D03*
X1144300Y352696D03*
X1154440Y350747D03*
Y362447D03*
X1144300Y368296D03*
X1157820Y379996D03*
X1147680Y389747D03*
X1144300Y376096D03*
X1151060Y383896D03*
X1161200Y362447D03*
X1157820Y364396D03*
X1154440Y370246D03*
X1157820Y376096D03*
X1151060Y372196D03*
X1147680Y378047D03*
X1144300Y379996D03*
Y387796D03*
X1161200Y358547D03*
Y366347D03*
X1157820Y368296D03*
Y372196D03*
X1154440Y374146D03*
X1151060Y376096D03*
X1147680Y381947D03*
X1144300Y383896D03*
X1161200Y354647D03*
X1107121Y350747D03*
X1113881Y346847D03*
X1147680Y370247D03*
Y374146D03*
X1120641Y346847D03*
X1161200Y389747D03*
X1154440Y397546D03*
Y393647D03*
X1151060Y387796D03*
X1157820Y395597D03*
X1154440Y389747D03*
X1157820Y391696D03*
X1154440Y385847D03*
X1140920Y354647D03*
X1161201Y401447D03*
X1157820Y383896D03*
X1137540Y356596D03*
X1156699Y401447D03*
X1134160Y358547D03*
X1137540Y352696D03*
X1130780Y356596D03*
X1134160Y354647D03*
Y350747D03*
X1137540Y348796D03*
X1208519Y218147D03*
X1167960Y222047D03*
X1164580Y220096D03*
X1161200Y222047D03*
X1171339Y216196D03*
X1181479Y218147D03*
X1191619Y208397D03*
X1209033Y183907D03*
X1188239Y202247D03*
X1181479Y202547D03*
X1174719D03*
X1178099Y204496D03*
X1181479Y214247D03*
X1178099Y212296D03*
X1184859Y208397D03*
Y220096D03*
X1191619Y216196D03*
X1194999Y214247D03*
Y218147D03*
X1198379Y220096D03*
X1201759Y222047D03*
X1164580Y212296D03*
Y208397D03*
X1167960Y214247D03*
X1174719Y210346D03*
X1184859Y216196D03*
X1181479Y210346D03*
X1184859Y212296D03*
X1188239Y218147D03*
X1191619Y220096D03*
Y212296D03*
X1198379Y216196D03*
X1205139Y220096D03*
X1164580Y216196D03*
X1167960Y210346D03*
X1171339Y212296D03*
X1174719Y214247D03*
Y222047D03*
X1221767Y175858D03*
X1220580Y179810D03*
X1161200Y268847D03*
X1164580Y255196D03*
X1171339Y270796D03*
X1164580Y282496D03*
X1167960Y280547D03*
X1171339Y282496D03*
X1167960Y261047D03*
X1174719D03*
X1164580Y251296D03*
X1167960Y272747D03*
X1171339Y255196D03*
Y251296D03*
X1161200Y245447D03*
X1164580Y243496D03*
Y274696D03*
X1174719Y272747D03*
X1167960Y257147D03*
X1161200Y272747D03*
X1191619Y223996D03*
X1178099D03*
X1167960Y233746D03*
X1178099Y270796D03*
Y278596D03*
X1181479Y249347D03*
Y237647D03*
Y241547D03*
X1184859Y223996D03*
X1201759Y237647D03*
X1198379Y227896D03*
X1205139Y231797D03*
X1201759Y245447D03*
X1194999Y237647D03*
X1198379Y251296D03*
X1181479Y264947D03*
X1184859Y255196D03*
X1191619Y270796D03*
X1198379Y262996D03*
X1194999Y276646D03*
X1198379Y282496D03*
Y270796D03*
X1178099Y266896D03*
X1162300Y264947D03*
X1167960Y249347D03*
X1181479Y257147D03*
X1178099Y255196D03*
X1161200Y253247D03*
X1174719Y268847D03*
X1167960Y241547D03*
Y245447D03*
Y237647D03*
X1171339Y239596D03*
Y243496D03*
X1174719Y241547D03*
X1178099Y239596D03*
X1174719Y249347D03*
Y245447D03*
X1171339Y278596D03*
X1178099Y262996D03*
X1205139Y255196D03*
X1208519Y249347D03*
X1201759Y253247D03*
X1205139Y243496D03*
X1212199Y239596D03*
X1205139Y235696D03*
X1212199Y227896D03*
X1208519Y225947D03*
X1205139Y282496D03*
X1201759Y280547D03*
X1198379Y274696D03*
X1201759Y272747D03*
X1205139Y270796D03*
X1201759Y264947D03*
X1205139Y262996D03*
X1208519Y257147D03*
Y253247D03*
X1205139Y251296D03*
X1208519Y241547D03*
Y237647D03*
X1205139Y239596D03*
X1212199Y231797D03*
Y223996D03*
X1205139Y278596D03*
X1201759Y276646D03*
Y268847D03*
X1208519D03*
X1205139Y266896D03*
Y259096D03*
Y223996D03*
X1198379D03*
X1205139Y227896D03*
X1178099Y282496D03*
X1184859Y262996D03*
X1191619Y259096D03*
X1194999Y261047D03*
Y257147D03*
X1188239Y253247D03*
X1194999Y249347D03*
X1198379Y247396D03*
X1191619Y243496D03*
X1188239Y241547D03*
X1181479Y245447D03*
X1184859Y278596D03*
X1188239Y276646D03*
Y280547D03*
X1181479Y272747D03*
X1188239Y268847D03*
X1191619Y266896D03*
X1181479Y280547D03*
X1188239Y261047D03*
X1191619Y262996D03*
X1198379Y259096D03*
X1191619Y255196D03*
Y251296D03*
X1194999Y253247D03*
Y245447D03*
Y241547D03*
X1188239Y245447D03*
X1184859Y243496D03*
Y282496D03*
Y274696D03*
X1191619Y282496D03*
Y278596D03*
X1184859Y270796D03*
X1188239Y272747D03*
Y264947D03*
X1174719Y229847D03*
X1167960Y225947D03*
X1174719Y233746D03*
X1181479Y229847D03*
X1184859Y227896D03*
Y231797D03*
X1191619Y235696D03*
Y227896D03*
X1198379Y231797D03*
X1161200Y233746D03*
Y229847D03*
X1171339Y227896D03*
Y223996D03*
X1174719Y225947D03*
X1178099Y231797D03*
X1181479Y233746D03*
Y225947D03*
X1188239Y229847D03*
Y233746D03*
X1191619Y231797D03*
X1194999Y229847D03*
X1161200Y225947D03*
X1164580Y231797D03*
X1174719Y257147D03*
X1178099Y259096D03*
X1174719Y276646D03*
X1167960D03*
Y268847D03*
X1181479Y253247D03*
X1178099Y251296D03*
X1167960Y264947D03*
X1171339Y262996D03*
X1174719Y264947D03*
X1208519Y229847D03*
X1184859Y337096D03*
X1178099Y340996D03*
X1181479Y339047D03*
Y342947D03*
X1178099Y344896D03*
X1201759Y331247D03*
Y335147D03*
Y342947D03*
X1198379Y344896D03*
Y333196D03*
X1201759Y339047D03*
X1205139Y340996D03*
X1181479Y331247D03*
X1167960Y284447D03*
X1198379Y321496D03*
X1194999Y323446D03*
X1181479Y315647D03*
X1171339Y344896D03*
X1174719Y339047D03*
X1164580Y340996D03*
X1167960Y331247D03*
X1171339Y321496D03*
X1184859Y325396D03*
Y333196D03*
X1198379Y337096D03*
Y329296D03*
X1194999Y342947D03*
X1174719Y323446D03*
X1181479D03*
X1174719Y327347D03*
X1178099Y333196D03*
X1171339Y329296D03*
X1167960Y335147D03*
X1171339Y340996D03*
X1174719Y319547D03*
X1178099Y321496D03*
Y325396D03*
Y329296D03*
X1174719Y331247D03*
X1171339Y333196D03*
Y337096D03*
X1161200Y311747D03*
X1198379Y290296D03*
Y294196D03*
X1161200Y300047D03*
Y303947D03*
X1201759Y292247D03*
X1205439Y290296D03*
Y294196D03*
Y286596D03*
X1208819Y284447D03*
X1184859Y286396D03*
X1191619D03*
X1194999Y284447D03*
X1181479D03*
X1191619Y290296D03*
Y313696D03*
Y309797D03*
X1188239Y307847D03*
Y303947D03*
Y300047D03*
X1184859Y298096D03*
Y344896D03*
X1191619D03*
Y340996D03*
Y337096D03*
X1188239Y331247D03*
X1194999Y327347D03*
X1188239D03*
X1184859Y317596D03*
X1191619D03*
X1194999Y311747D03*
X1191619Y305896D03*
X1184859D03*
X1191619Y301996D03*
X1188239Y296147D03*
X1181479D03*
X1184859Y340996D03*
X1188239Y342947D03*
X1194999Y339047D03*
X1191619Y333196D03*
Y329296D03*
Y325396D03*
X1188239Y323446D03*
X1184859Y313696D03*
X1188239Y315647D03*
X1174719Y303947D03*
X1167960D03*
X1178099Y309797D03*
X1171339Y305896D03*
X1164580Y309797D03*
Y305896D03*
X1167960Y307847D03*
Y311747D03*
X1171339Y309797D03*
X1178099Y301996D03*
X1174719Y311747D03*
Y307847D03*
X1178099Y305896D03*
Y313696D03*
X1171339D03*
X1164580D03*
X1174719Y292247D03*
Y288347D03*
X1171339Y286396D03*
Y290296D03*
X1167960Y300047D03*
X1164580Y298096D03*
X1167960Y296147D03*
Y292247D03*
Y288347D03*
X1161200Y296147D03*
X1178099Y290296D03*
X1171339Y298096D03*
Y294196D03*
X1174719Y296147D03*
Y346847D03*
X1178099Y348796D03*
Y352696D03*
X1201759Y346847D03*
X1167960Y358547D03*
X1174719Y350747D03*
X1167960Y366347D03*
X1171339Y368296D03*
X1161200Y374146D03*
X1178099Y391696D03*
X1174719Y397546D03*
X1164580Y399496D03*
X1188239Y370247D03*
X1191619Y372197D03*
Y364396D03*
Y352696D03*
X1181479Y385847D03*
Y405347D03*
X1188239Y381947D03*
X1208819Y385847D03*
X1164580Y368296D03*
X1167960Y350747D03*
Y354647D03*
X1164580Y360496D03*
Y364396D03*
X1167960Y346847D03*
X1171339Y352696D03*
X1184859Y348796D03*
X1188239Y346847D03*
X1178099Y387796D03*
X1171339D03*
Y391696D03*
X1167960Y393647D03*
X1164580Y395597D03*
X1178099Y379996D03*
Y383896D03*
X1174719Y385847D03*
X1171339Y383896D03*
X1174719Y389747D03*
X1171339Y395596D03*
X1164580Y391696D03*
Y387796D03*
X1178099Y376096D03*
X1181479Y381947D03*
X1188239Y354647D03*
Y358547D03*
Y362447D03*
X1181479D03*
Y366347D03*
X1184859Y372197D03*
Y376096D03*
Y379996D03*
X1188239Y350747D03*
X1191619Y356596D03*
X1184859Y360496D03*
X1181479Y358547D03*
X1184859Y364396D03*
Y368296D03*
X1188239Y374146D03*
X1181479Y378047D03*
X1174719Y370247D03*
X1181479D03*
X1171339Y364396D03*
X1178099Y360496D03*
Y356596D03*
X1184859Y352696D03*
X1161200Y393647D03*
Y385847D03*
X1167960D03*
Y381947D03*
Y378047D03*
X1174719D03*
Y374146D03*
Y366347D03*
X1178099Y368296D03*
X1174719Y362447D03*
Y358547D03*
X1181479Y354647D03*
Y350747D03*
X1161200Y381947D03*
X1164580Y383896D03*
X1171339Y379996D03*
X1167960Y374146D03*
X1171339Y376096D03*
X1178099Y372197D03*
X1167960Y405347D03*
X1194999Y378047D03*
X1201759Y374146D03*
X1194999D03*
X1198379Y364396D03*
Y360496D03*
Y356596D03*
X1174719Y405347D03*
Y401447D03*
X1178099Y395596D03*
X1184859Y399496D03*
X1181479Y393647D03*
X1188239Y389747D03*
Y385847D03*
X1191619Y379996D03*
X1198379Y383896D03*
X1167960Y401447D03*
X1198379Y376096D03*
Y372197D03*
X1194999Y370247D03*
Y362447D03*
X1201759Y358547D03*
X1198379Y352696D03*
X1171339Y403396D03*
X1178099Y399496D03*
X1181479Y397546D03*
X1184859Y395596D03*
Y391696D03*
Y387796D03*
X1191619Y383896D03*
X1194999Y381947D03*
X1198379Y379996D03*
X1164580Y376096D03*
X1194999Y350747D03*
X1198379Y348796D03*
X1251771Y27899D03*
Y36057D03*
X1248425Y17057D03*
X1258464Y36057D03*
Y27899D03*
X1265157Y36057D03*
X1261811D03*
Y27899D03*
Y16999D03*
X1258464D03*
X1265157Y9157D03*
X1251771D03*
Y-1743D03*
X1261811Y-9901D03*
X1258464D03*
X1261811Y-1743D03*
X1265157D03*
X1258464D03*
X1255118Y-9901D03*
Y27899D03*
Y16999D03*
Y-1743D03*
Y36057D03*
Y9157D03*
X1265157Y27899D03*
Y-9901D03*
Y16999D03*
X1276346Y-10250D03*
X1251771Y54799D03*
X1248425Y54857D03*
X1251771Y46957D03*
X1258464D03*
Y54799D03*
X1261811Y46957D03*
Y54799D03*
Y65699D03*
X1258464D03*
X1251771Y84757D03*
X1248425Y92657D03*
X1265157Y73857D03*
X1261811D03*
X1258464D03*
X1261811Y84757D03*
X1258464D03*
X1265157D03*
X1251771Y73857D03*
X1261811Y92599D03*
X1258464D03*
X1255118Y65699D03*
Y54799D03*
Y92599D03*
Y46957D03*
Y84757D03*
Y73857D03*
X1265157Y65699D03*
Y92599D03*
Y54799D03*
X1270350Y98300D03*
X1268111Y58040D03*
X1251344Y127925D03*
X1259950Y144650D03*
X1277100Y122670D03*
X1272100Y141603D03*
X1264550Y114670D03*
X1277100Y114800D03*
X1261030Y105350D03*
X1277600Y106200D03*
X1248616Y133817D03*
X1237704Y148423D03*
X1268576Y117788D03*
X1250200Y122900D03*
X1251980Y106960D03*
X1262569Y147201D03*
X1243948Y154916D03*
X1269810Y154398D03*
X1275470Y99390D03*
X1252000Y145300D03*
X1257800Y120800D03*
X1255400Y108000D03*
X1252437Y140192D03*
X1249025Y130460D03*
X1240000Y129500D03*
X1259200Y168350D03*
X1281799Y193190D03*
X1267800Y161800D03*
X1271400Y161900D03*
X1240309D03*
X1267050Y169800D03*
X1233902Y173337D03*
X1241381Y172040D03*
X1246655Y176395D03*
X1263300Y169450D03*
X1268404Y246304D03*
X1279393Y247602D03*
X1270478Y243490D03*
X1277504Y250346D03*
X1272761Y240220D03*
X1283720Y223870D03*
X1249230Y402022D03*
X1262700Y461804D03*
X1262900Y466504D03*
X1277978Y491571D03*
X1278573Y519596D03*
X1265157Y510157D03*
X1261811Y517999D03*
X1258464Y510157D03*
Y517999D03*
X1261811Y510157D03*
X1248425Y518057D03*
X1251771Y510157D03*
X1258464Y528899D03*
X1261811D03*
X1255120Y518000D03*
Y510158D03*
X1271300Y510600D03*
X1271105Y498516D03*
X1274576Y510235D03*
X1265157Y528876D03*
Y517999D03*
X1262843Y497553D03*
X1258140Y474540D03*
X1271571Y479000D03*
X1271662Y487326D03*
X1256320Y490660D03*
X1258126Y469540D03*
X1271640Y474420D03*
X1271647Y482500D03*
X1256350Y486080D03*
X1265157Y547957D03*
X1261811D03*
X1258464D03*
X1251771D03*
X1265157Y537057D03*
X1261811D03*
X1251771D03*
X1258464D03*
X1265157Y585757D03*
X1261811D03*
X1258464D03*
X1251771D03*
X1261811Y555799D03*
X1258464D03*
X1251771D03*
X1248425Y555857D03*
X1251771Y566699D03*
Y574857D03*
X1265157D03*
X1261811D03*
X1258464D03*
X1261811Y566699D03*
X1258464D03*
X1273200Y582200D03*
X1255120Y555144D03*
Y574834D03*
Y537034D03*
X1265157Y566676D03*
Y555799D03*
X1277200Y539100D03*
X1270400Y593600D03*
X1258464Y593599D03*
X1261811D03*
X1248425Y593657D03*
X1251771Y612657D03*
X1258464Y604499D03*
X1261811D03*
X1265157Y612657D03*
X1261811D03*
X1258464D03*
X1255120Y593600D03*
Y612634D03*
X1265157Y604476D03*
Y593599D03*
X1293600Y-17000D03*
X1293816Y-13533D03*
X1292692Y1008D03*
X1296908Y36900D03*
X1287700Y-16700D03*
X1303774Y-18842D03*
X1298422Y74000D03*
X1330300Y83500D03*
X1336850Y76450D03*
X1327168Y61483D03*
X1304685Y78827D03*
X1298754Y83233D03*
X1336900Y61600D03*
X1343260Y53770D03*
X1327500Y51547D03*
X1327452Y55544D03*
X1309700Y83300D03*
X1336500Y81100D03*
X1324127Y50827D03*
X1337400Y72000D03*
X1301219Y89141D03*
X1304500Y40066D03*
X1296935Y51335D03*
X1323000Y83000D03*
X1308400Y79600D03*
X1306900Y131744D03*
X1301900Y124400D03*
X1310098Y150040D03*
X1293700Y121800D03*
X1295700Y144450D03*
X1327900Y142918D03*
X1301770Y101300D03*
X1320500Y145000D03*
X1325100D03*
X1287790Y156575D03*
X1310175Y154696D03*
X1299907Y159808D03*
X1295500Y159970D03*
X1300300Y169900D03*
X1315130Y164870D03*
X1315180Y169950D03*
X1326474Y216500D03*
X1338224Y209051D03*
X1305171Y164767D03*
X1310061Y165235D03*
X1344462Y209272D03*
X1323030Y216531D03*
X1330100Y165000D03*
Y170000D03*
X1340100Y165000D03*
X1345100D03*
Y170000D03*
X1340100D03*
X1335100D03*
Y165000D03*
X1320100D03*
X1325100D03*
X1320100Y170000D03*
X1325100D03*
X1345050Y272350D03*
X1300444Y267919D03*
X1309462Y240229D03*
X1288800Y233900D03*
X1320400Y232118D03*
X1331400D03*
X1342400D03*
X1314900D03*
X1325900D03*
X1336900D03*
X1331650Y317250D03*
X1338700Y284700D03*
X1323750Y319750D03*
X1320900Y321300D03*
X1335250Y344250D03*
X1319310Y300795D03*
X1336336Y333825D03*
X1302768Y296942D03*
X1331720Y334810D03*
X1326300Y341309D03*
X1341375Y314675D03*
Y319675D03*
X1316600Y305500D03*
X1306290Y298255D03*
X1308887Y285015D03*
X1319888Y290205D03*
X1323688D03*
X1345700Y285300D03*
X1335400Y284900D03*
X1302203Y314439D03*
X1315496Y361190D03*
X1342570Y368220D03*
X1326014Y347732D03*
X1296468Y437500D03*
X1325100Y457500D03*
Y452500D03*
X1320100Y457500D03*
Y452500D03*
X1315100D03*
X1310100D03*
X1315100Y457500D03*
X1305100D03*
Y452500D03*
X1310100Y457500D03*
X1330100D03*
Y452500D03*
X1300315Y427902D03*
X1335100Y427500D03*
Y432500D03*
X1300438Y433001D03*
X1318054Y460507D03*
X1340100Y432500D03*
X1304200Y466600D03*
Y462030D03*
X1329419Y464337D03*
X1344761Y498282D03*
X1309870Y499254D03*
X1287770Y501897D03*
X1340986Y511187D03*
X1341050Y498275D03*
X1299450Y484950D03*
X1320300Y498300D03*
X1322260Y477492D03*
X1329419Y469337D03*
X1322360Y472592D03*
X1316100Y543400D03*
X1308500Y540784D03*
X1324707Y545493D03*
X1327956Y545655D03*
X1318500Y539900D03*
X1305500Y542500D03*
X1296295Y615596D03*
X1301384Y618119D03*
X1400616Y13795D03*
X1376094Y4406D03*
X1380678Y-422D03*
X1380950Y30232D03*
X1379025Y-9799D03*
X1407422Y13139D03*
X1377009Y39753D03*
X1355500Y83000D03*
X1358500Y74500D03*
X1363500Y77400D03*
X1370975Y67225D03*
X1370849Y59349D03*
X1371910Y48800D03*
X1351500Y83000D03*
X1367700Y86450D03*
X1371500Y63200D03*
X1351488Y74000D03*
X1372300Y86400D03*
X1406546Y43116D03*
X1383171Y57549D03*
X1401300Y149600D03*
X1384600Y108500D03*
X1381359Y108496D03*
X1388100Y108500D03*
X1371500Y101000D03*
X1404200Y119200D03*
X1402500Y116300D03*
X1399100Y166900D03*
X1396933Y215763D03*
X1353569Y208960D03*
X1348569D03*
X1367789Y209216D03*
X1384671Y214832D03*
X1402020Y165561D03*
X1350100Y170000D03*
X1380100Y165000D03*
X1355100Y170000D03*
X1360100D03*
X1355100Y165000D03*
X1360100D03*
X1350100D03*
X1365100Y170000D03*
Y165000D03*
X1370100D03*
X1375100Y170000D03*
X1370100D03*
X1375100Y165000D03*
X1380100Y170000D03*
X1399852Y252353D03*
X1407274Y245652D03*
X1353400Y232118D03*
X1364400D03*
X1375400D03*
X1347900D03*
X1358900D03*
X1369900D03*
X1380900D03*
X1365246Y285931D03*
X1363700Y321600D03*
X1367200D03*
X1352400Y285000D03*
X1396470Y330014D03*
X1392400Y330800D03*
X1400400Y335400D03*
X1388450Y331250D03*
X1359200Y322200D03*
X1364260Y331619D03*
X1349134Y317436D03*
X1360294Y315025D03*
X1371090Y315395D03*
X1380904Y315947D03*
X1392226Y315658D03*
X1400558Y320157D03*
X1349134Y321145D03*
X1360294Y318825D03*
X1371090Y319195D03*
X1380904Y319747D03*
X1392226Y319458D03*
X1400558Y316357D03*
X1368200Y284000D03*
X1353672Y299605D03*
X1347892Y299741D03*
X1355300Y321675D03*
X1381431Y284259D03*
X1394370Y384230D03*
X1378207Y394568D03*
X1394260Y351170D03*
X1389500Y360500D03*
X1391845Y348325D03*
X1388300Y346200D03*
X1371600Y368700D03*
X1380872Y378098D03*
X1380900Y383164D03*
X1388900Y387800D03*
X1378200Y346900D03*
X1377028Y458125D03*
X1372028D03*
X1360100Y447500D03*
Y452500D03*
Y457500D03*
X1385100Y452500D03*
Y447500D03*
X1390100Y457500D03*
X1389900Y447400D03*
X1390100Y452500D03*
X1395100Y432500D03*
Y447500D03*
Y427500D03*
X1349800Y458200D03*
X1350100Y447500D03*
Y452500D03*
X1375100Y447500D03*
X1362560Y463478D03*
X1370100Y452500D03*
X1375100D03*
X1385100Y427500D03*
Y442500D03*
Y437500D03*
X1390100Y432500D03*
X1389900Y427400D03*
X1385100Y432500D03*
X1365100D03*
Y427500D03*
Y437500D03*
X1380100Y442500D03*
Y437500D03*
X1370100D03*
X1375100D03*
X1370100Y447500D03*
X1403027Y520231D03*
X1355800Y508500D03*
X1395242Y520301D03*
X1347546Y476897D03*
X1380741Y487489D03*
X1360863Y481673D03*
X1362841Y492823D03*
X1383263Y493673D03*
X1381041Y482575D03*
X1360741Y486523D03*
X1362880Y497556D03*
X1383241Y498595D03*
X1347081Y507919D03*
X1396035Y514863D03*
X1347196Y472941D03*
X1354462Y474141D03*
X1350500Y475100D03*
X1399721Y537509D03*
X1379053Y581864D03*
X1390595Y549328D03*
X1382000Y589500D03*
X1375600Y589700D03*
X1396158Y537595D03*
X1380890Y615820D03*
X1386921Y620689D03*
X1390851D03*
X1382100Y592800D03*
X1410600Y9100D03*
X1425081Y48412D03*
X1411546Y43116D03*
X1453700Y83750D03*
X1457000Y82000D03*
X1420337Y45477D03*
X1416837D03*
X1451021Y151626D03*
X1438348Y155908D03*
X1468700Y163100D03*
X1458569Y192143D03*
X1458908Y187699D03*
X1459548Y221731D03*
X1446331Y197285D03*
X1422281Y221479D03*
X1447999Y205645D03*
X1451366Y165296D03*
X1408247Y206270D03*
X1422196Y218052D03*
X1452728Y243306D03*
X1452200Y254500D03*
X1430365Y262624D03*
X1448500Y257700D03*
X1458318Y243000D03*
X1426905Y267045D03*
X1464150Y235550D03*
X1455600Y254826D03*
X1433057Y257388D03*
X1447154Y251710D03*
X1441750Y236800D03*
X1467040Y260357D03*
X1466006Y265300D03*
X1461400Y264700D03*
X1426658Y274252D03*
X1461348Y244350D03*
X1444850Y242730D03*
X1440910Y316693D03*
X1458400Y318500D03*
X1408250Y333000D03*
X1463610Y321329D03*
X1413387Y320033D03*
Y316233D03*
X1443500Y327900D03*
X1468399Y324930D03*
X1444311Y324366D03*
X1462776Y318200D03*
X1466970Y320235D03*
X1420075Y388402D03*
X1413735Y391302D03*
X1420075Y383375D03*
X1420515Y368585D03*
X1420075Y393402D03*
X1413735Y396302D03*
X1420075Y378375D03*
X1420515Y373585D03*
X1452699Y404060D03*
X1457300Y373600D03*
X1444400Y371600D03*
X1413400Y361300D03*
X1464400Y390800D03*
X1450400Y354300D03*
X1448000Y431500D03*
X1431900Y437100D03*
X1447700Y442500D03*
X1431900Y448000D03*
X1448000Y437000D03*
X1431900Y442600D03*
X1447500Y448000D03*
X1431900Y453500D03*
X1414107Y447267D03*
X1458300Y442675D03*
X1431690Y521530D03*
X1410486Y529792D03*
X1458060Y495020D03*
X1464553Y508872D03*
X1428500Y521000D03*
X1461267Y489790D03*
X1412941Y489523D03*
X1413193Y482532D03*
X1436600Y482900D03*
X1436541Y494423D03*
X1412741Y494223D03*
X1413041Y477423D03*
X1436396Y477691D03*
X1436441Y489323D03*
X1451533Y527867D03*
X1460661Y484891D03*
X1441252Y548631D03*
X1451150Y569900D03*
Y573200D03*
X1439822Y537382D03*
X1429026Y541026D03*
X1428281Y546119D03*
X1413600Y531300D03*
X1432560Y561160D03*
X1436160Y561200D03*
X1428791Y535512D03*
X1419600Y531500D03*
X1410950Y589670D03*
X1441409Y561117D03*
X1453533Y532667D03*
X1426870Y530800D03*
X1423800Y534800D03*
X1425243Y562260D03*
X1421560Y563455D03*
X1460200Y606200D03*
X1477100Y2400D03*
X1522600Y-6500D03*
X1504400Y20300D03*
X1481600Y5300D03*
X1501900Y-9124D03*
X1485242Y4589D03*
X1506300Y-6600D03*
X1521092Y21665D03*
X1520700Y7100D03*
X1513700Y7082D03*
X1470862Y38209D03*
X1519599Y86117D03*
X1524557Y88336D03*
X1505673Y146346D03*
X1473354Y153246D03*
X1485210Y134837D03*
X1476761Y157400D03*
X1483366Y120746D03*
Y115902D03*
X1484113Y128513D03*
X1485755Y131671D03*
X1518376Y111499D03*
X1476761Y152725D03*
X1490178Y112315D03*
X1518438Y100926D03*
X1494939Y159500D03*
X1510184Y142614D03*
X1503466Y142486D03*
X1500703Y158233D03*
X1514425Y134180D03*
X1520150Y127600D03*
X1475200Y142600D03*
X1496038Y154229D03*
X1488300Y158300D03*
X1500643Y154819D03*
X1513136Y157081D03*
X1496726Y120588D03*
X1496658Y115088D03*
X1500700Y127250D03*
X1500806Y133339D03*
X1518514Y130991D03*
X1524900Y139100D03*
X1526310Y142190D03*
X1524284Y112773D03*
X1474717Y110370D03*
X1482455Y124222D03*
X1502000Y147500D03*
X1490674Y98787D03*
X1524744Y133656D03*
X1496713Y174853D03*
X1504706Y164871D03*
X1511100Y186275D03*
X1492597Y172636D03*
X1488900Y172576D03*
X1474883Y182275D03*
X1478089Y182650D03*
X1470382Y188372D03*
X1472758Y216495D03*
X1513900Y218000D03*
X1519243Y191627D03*
X1487716Y218650D03*
X1477388Y172988D03*
X1497237Y217281D03*
X1497493Y162078D03*
X1512700Y205100D03*
X1488300Y161700D03*
X1498022Y221900D03*
X1512525Y208944D03*
X1492136Y199125D03*
X1493200Y162700D03*
X1512500Y199837D03*
X1510638Y166240D03*
X1516872Y208863D03*
X1491438Y221137D03*
X1510800Y193330D03*
X1515060Y192443D03*
X1507524Y218600D03*
X1472200Y243000D03*
X1482004Y222483D03*
X1525650Y248700D03*
X1470950Y229669D03*
X1526150Y234300D03*
X1486926Y247834D03*
X1496030Y267665D03*
X1516549Y234278D03*
X1516613Y240656D03*
X1521962Y278650D03*
X1512790Y240099D03*
X1499681Y279910D03*
X1486574Y267127D03*
X1507003Y272249D03*
X1492753Y273724D03*
X1484000Y257500D03*
X1492697Y267303D03*
X1475004Y246287D03*
X1474520Y251740D03*
X1482400Y248000D03*
X1487500Y244500D03*
X1505946Y254432D03*
X1519300Y245196D03*
X1499070Y255934D03*
X1470556Y256900D03*
X1469829Y266909D03*
X1484700Y251800D03*
X1527657Y278700D03*
X1503842Y245678D03*
X1504772Y259229D03*
X1523580Y237960D03*
X1496812Y273718D03*
X1479700Y224801D03*
X1504461Y274426D03*
X1520413Y239498D03*
X1489546Y279902D03*
X1491265Y226492D03*
X1483457Y244568D03*
X1474096Y256706D03*
X1497082Y277987D03*
X1526936Y307015D03*
X1529734Y319714D03*
X1473231Y320250D03*
X1499723Y300106D03*
X1471562Y325531D03*
X1512182Y293317D03*
X1497179Y306372D03*
X1508455Y313041D03*
X1523935Y318901D03*
X1493400Y300800D03*
X1514067Y315626D03*
X1484100Y330115D03*
X1501550Y293750D03*
X1482550Y333600D03*
X1487000Y333300D03*
X1503538Y318068D03*
X1518006Y286706D03*
X1499987Y288487D03*
X1496628Y288440D03*
X1520766Y341000D03*
X1505000Y340990D03*
X1508650Y287500D03*
X1510851Y340113D03*
X1497509Y303120D03*
X1500840Y319870D03*
X1504370Y330970D03*
X1518060Y317520D03*
X1470276Y330774D03*
X1493268Y293943D03*
X1496900Y293900D03*
X1525677Y311835D03*
X1499829Y341250D03*
X1530500Y287700D03*
X1510584Y330640D03*
X1526900Y292866D03*
X1470257Y321929D03*
X1495300Y297300D03*
X1493290Y287984D03*
X1478524Y318900D03*
X1483506Y326061D03*
X1493500Y304400D03*
X1514100Y321792D03*
X1517115Y330005D03*
X1507025Y391034D03*
X1493375Y380894D03*
X1505075D03*
X1501175Y394414D03*
X1499225Y391034D03*
Y384274D03*
X1487525Y397794D03*
X1493375Y394414D03*
X1489475D03*
X1487525Y384274D03*
X1489475Y387654D03*
X1514265Y355542D03*
X1499225Y377514D03*
X1495325Y391034D03*
X1493375Y387654D03*
X1505075Y394414D03*
X1501175Y387654D03*
X1495325Y377514D03*
X1524575Y394414D03*
X1530425Y384274D03*
X1487525Y377514D03*
X1517367Y349964D03*
X1472940Y384030D03*
X1473255Y372654D03*
X1525561Y350253D03*
X1511000Y350627D03*
X1505075Y387654D03*
Y401174D03*
X1501175D03*
X1507025Y404554D03*
X1522625Y391034D03*
X1495325Y397794D03*
X1499225D03*
Y404554D03*
X1493375Y401174D03*
X1489475D03*
X1507025Y384274D03*
X1501175Y380894D03*
X1522625Y404554D03*
X1481000Y350000D03*
X1502970Y350610D03*
X1496000Y350000D03*
X1528475Y380894D03*
X1522625Y397794D03*
X1528475Y401174D03*
Y387654D03*
X1529829Y362655D03*
X1516775Y380894D03*
X1526659Y397500D03*
X1528475Y394414D03*
X1524575Y380894D03*
X1522476Y361907D03*
X1507025Y377514D03*
X1520675Y394414D03*
X1522625Y377514D03*
X1530425D03*
X1518725Y397794D03*
Y391034D03*
Y384274D03*
X1510925Y397794D03*
X1512875Y401174D03*
Y394414D03*
X1530425Y391034D03*
X1514925Y358844D03*
X1484600Y394100D03*
X1495325Y384274D03*
X1483868Y390233D03*
X1483664Y362914D03*
X1520675Y401174D03*
X1516775D03*
Y394414D03*
X1510925Y377514D03*
X1512875Y380894D03*
X1515328Y363389D03*
X1518725Y377514D03*
X1522625Y384274D03*
X1510925Y391034D03*
X1516775Y387654D03*
X1512875D03*
X1510925Y384274D03*
X1478163Y354940D03*
X1530425Y397794D03*
X1489475Y380894D03*
X1524575Y387654D03*
X1503878Y364717D03*
X1485300Y443484D03*
X1489475Y450306D03*
X1491425Y453686D03*
X1493375Y457066D03*
X1499225Y460446D03*
X1493375Y450306D03*
X1489475Y457066D03*
X1495325Y460446D03*
X1497275Y463826D03*
X1483375Y458375D03*
X1530425Y467206D03*
X1516700Y409900D03*
X1528475Y407934D03*
X1512875Y463826D03*
X1510925Y467206D03*
X1507025D03*
X1508975Y463826D03*
X1501175Y428214D03*
X1495325Y418074D03*
X1499225Y424834D03*
X1516775Y463826D03*
X1505075D03*
X1524575D03*
X1493375Y414694D03*
X1489475D03*
X1491425Y411314D03*
X1487525D03*
X1493375Y443546D03*
X1489475D03*
X1491425Y440166D03*
X1487525D03*
X1516775Y457066D03*
X1528475Y463826D03*
X1524575Y407624D03*
X1514825Y467206D03*
X1499225Y411314D03*
X1501175Y407934D03*
X1499225Y440166D03*
X1524575Y457066D03*
X1505075D03*
X1501175Y443546D03*
X1485250Y408017D03*
X1501200Y450600D03*
X1521800Y419900D03*
X1508975Y457066D03*
X1505715Y441368D03*
X1497200Y421200D03*
X1491425Y446926D03*
X1493375Y428214D03*
X1489475D03*
X1493375Y436786D03*
X1489475D03*
X1499225Y446926D03*
Y453686D03*
X1491425Y460446D03*
X1499225Y467206D03*
X1489475Y463826D03*
X1491425Y467206D03*
X1487525Y460446D03*
X1495325Y467206D03*
X1485030Y463690D03*
X1491400Y424600D03*
X1487500D03*
X1489475Y421454D03*
X1493375D03*
X1520675Y463826D03*
X1505075Y407934D03*
X1497273Y407610D03*
X1489475Y407934D03*
X1493375D03*
X1520675Y470586D03*
X1503400Y524663D03*
X1524575Y470586D03*
X1520675Y477346D03*
X1512875Y470586D03*
X1472500Y509810D03*
X1474400Y517200D03*
X1482200Y477800D03*
X1497275Y470586D03*
Y477346D03*
X1489475D03*
X1499225Y473966D03*
X1493375Y470586D03*
X1495325Y473966D03*
X1493375Y477346D03*
X1491425Y480726D03*
X1501175Y477346D03*
X1530425Y487486D03*
X1528475Y484106D03*
X1520675D03*
X1524575Y477346D03*
X1512875D03*
X1497275Y484106D03*
X1499225Y487486D03*
X1503125Y473966D03*
X1507025D03*
X1501175Y484106D03*
X1505075D03*
X1503125Y480726D03*
X1505075Y477346D03*
X1508975Y484106D03*
X1507025Y480726D03*
X1510925Y487486D03*
X1512875Y484106D03*
X1493375D03*
X1491425Y487486D03*
X1495325Y480726D03*
Y487486D03*
X1526525Y480726D03*
X1530425D03*
X1524575Y484106D03*
X1522625Y480726D03*
X1516775Y477346D03*
X1472250Y485100D03*
X1470643Y495299D03*
X1482958Y486118D03*
X1485100Y469900D03*
X1487525Y480726D03*
X1478700Y533700D03*
X1500445Y619956D03*
X1549600Y-10800D03*
X1538520Y11911D03*
X1590431Y-6702D03*
X1544882Y-6900D03*
X1592829Y24460D03*
X1589623Y24528D03*
X1543500Y3400D03*
X1540000D03*
X1581947Y-6702D03*
X1545111Y24172D03*
X1580398Y-600D03*
Y5400D03*
X1571500Y-1406D03*
X1556200Y94800D03*
X1545572Y38188D03*
X1579100Y69000D03*
X1577269Y95344D03*
X1535300Y78490D03*
X1590949Y97850D03*
X1583374Y81319D03*
X1574780Y90992D03*
X1587359Y84348D03*
X1545250Y88360D03*
X1546370Y84180D03*
X1592715Y70817D03*
X1575018Y71213D03*
X1556810Y71760D03*
X1541413Y155259D03*
X1588176Y157600D03*
X1541765Y114000D03*
X1541421Y106742D03*
X1580275Y101041D03*
X1553500Y157000D03*
X1552171Y133000D03*
X1563108Y126423D03*
X1582500Y109900D03*
X1577700Y140149D03*
X1567520Y133354D03*
X1549000Y115571D03*
X1549187Y104713D03*
X1589200Y121800D03*
X1589622Y112876D03*
X1557981Y141470D03*
X1541390Y136498D03*
X1591950Y158250D03*
X1573153Y103721D03*
X1576606Y104392D03*
X1588500Y106788D03*
X1588000Y100500D03*
X1542685Y133321D03*
X1574197Y127915D03*
X1531726Y123800D03*
X1576506Y143416D03*
X1572395Y110754D03*
X1558100Y128926D03*
X1554627Y100877D03*
X1558136D03*
X1558100Y138025D03*
Y133526D03*
X1590569Y152464D03*
X1541434Y139871D03*
X1542000Y126246D03*
X1591800Y164900D03*
X1566486Y181270D03*
X1535065Y164300D03*
X1552051Y172053D03*
X1571501Y180031D03*
X1568488Y164058D03*
X1562150Y160700D03*
X1583874Y217746D03*
X1582249Y191716D03*
X1572817Y169910D03*
X1570294Y167384D03*
X1535425Y188016D03*
X1535000Y207200D03*
X1557979Y188844D03*
X1543100Y184128D03*
X1553500Y165400D03*
X1548178Y190880D03*
X1558000Y205100D03*
X1545023Y161675D03*
X1561925Y192675D03*
X1566858Y175192D03*
X1549693Y196707D03*
X1552063Y202031D03*
X1558042Y172448D03*
X1593218Y191776D03*
X1557787Y192236D03*
X1561538Y174649D03*
X1587549Y192000D03*
X1582699Y252646D03*
X1561104Y234255D03*
X1537972Y236000D03*
X1532237Y247801D03*
X1567000Y259560D03*
X1552900Y281700D03*
X1579867Y265445D03*
X1563157Y258164D03*
X1533596Y273504D03*
X1542751Y240477D03*
X1542690Y236050D03*
X1531935Y224160D03*
X1541325Y245090D03*
X1568120Y251710D03*
X1545802Y233529D03*
X1584568Y281339D03*
X1571876Y255800D03*
X1558700Y252000D03*
X1568365Y247761D03*
X1551404Y309376D03*
X1533228Y325000D03*
X1550619Y303087D03*
X1534400Y296029D03*
X1587800Y308200D03*
X1538450Y314300D03*
X1578790Y290920D03*
X1550800Y296200D03*
X1577486Y307621D03*
X1532850Y303950D03*
X1548024Y322145D03*
X1585479Y316610D03*
X1570574Y341776D03*
X1554932Y332171D03*
X1538406Y330157D03*
X1573950Y338050D03*
X1537500Y292800D03*
X1581834Y318591D03*
X1559800Y285300D03*
X1559500Y290300D03*
X1575645Y320664D03*
X1588551Y341410D03*
X1548334Y325497D03*
X1581940Y295820D03*
X1582800Y312100D03*
X1548273Y313227D03*
X1565000Y290500D03*
X1543864Y311399D03*
X1590212Y315425D03*
X1551250Y320303D03*
X1590176Y331844D03*
X1554775Y295328D03*
X1548100Y342200D03*
X1534833Y309798D03*
X1560500Y350000D03*
X1553825Y377514D03*
X1557534Y353400D03*
X1533589Y366361D03*
X1553825Y391034D03*
X1546025D03*
X1532367Y356530D03*
X1581822Y365770D03*
X1569584Y378002D03*
X1563575Y394414D03*
X1557725Y397794D03*
X1571375Y387654D03*
X1569425Y397794D03*
X1550639Y350200D03*
X1563575Y401174D03*
X1569425Y391034D03*
X1553825Y397794D03*
X1542300Y376717D03*
X1546025Y397794D03*
X1551875Y394414D03*
Y387654D03*
X1549950Y404490D03*
X1565525Y384274D03*
X1587684Y362653D03*
X1557725Y377514D03*
X1586500Y354900D03*
X1559675Y401174D03*
X1542125Y397794D03*
X1583208Y404941D03*
X1565525Y391034D03*
X1547975Y394414D03*
X1540175Y387654D03*
Y380894D03*
Y401174D03*
X1542932Y355740D03*
X1547975Y387654D03*
X1571450Y359650D03*
X1536275Y401174D03*
Y387654D03*
X1534325Y384274D03*
X1536275Y380894D03*
X1534325Y397794D03*
X1540175Y394414D03*
X1534325Y391034D03*
X1582600Y389300D03*
X1559675Y387654D03*
Y394414D03*
X1551875Y380894D03*
X1557725Y391034D03*
X1536275Y394414D03*
X1557725Y404554D03*
X1563575Y387654D03*
X1567475Y401174D03*
X1566922Y359681D03*
X1567121Y363217D03*
X1551875Y401174D03*
X1565525Y397794D03*
Y377514D03*
X1559675Y380894D03*
X1571375Y394414D03*
X1532375Y401174D03*
X1563575Y380894D03*
X1546182Y355446D03*
X1534325Y377514D03*
X1542125Y460446D03*
X1538225D03*
X1549925Y467206D03*
X1557725D03*
X1569425Y453686D03*
X1559675Y407934D03*
X1561625Y446926D03*
X1551875Y450306D03*
X1536275Y463826D03*
X1532375D03*
X1534325Y467206D03*
X1538225D03*
X1585560Y421324D03*
X1583773Y436137D03*
X1544075Y463826D03*
X1543850Y451400D03*
X1553825Y411314D03*
X1544150Y409900D03*
X1553825Y440166D03*
Y446926D03*
X1549926Y411312D03*
X1540175Y407934D03*
X1536275D03*
X1532375D03*
X1555775D03*
Y414694D03*
X1565525Y418074D03*
X1561625D03*
Y411314D03*
X1565525D03*
X1561625Y440166D03*
X1557725D03*
X1565525Y424834D03*
X1569425D03*
X1536300Y455200D03*
X1553825Y453686D03*
X1547000Y435650D03*
X1551875Y436786D03*
X1549925Y440166D03*
X1540653Y454588D03*
X1532349Y455200D03*
X1549925Y460446D03*
X1583208Y416752D03*
X1591350Y445300D03*
X1542125Y467206D03*
X1559595Y450631D03*
X1569425Y446926D03*
X1591430Y409440D03*
X1565525Y453686D03*
X1551875Y443546D03*
X1571375Y436786D03*
X1587573Y445300D03*
X1587550Y456550D03*
X1565525Y467206D03*
X1561625D03*
X1567475Y463826D03*
X1569425Y467206D03*
X1553825Y460446D03*
X1567475Y443546D03*
X1571375D03*
X1563575Y450306D03*
X1567475Y436786D03*
X1569425Y440166D03*
X1565525Y460446D03*
X1563575Y463826D03*
X1582300Y446100D03*
X1565525Y446926D03*
X1559675Y457066D03*
X1546025Y460446D03*
X1557725D03*
X1551875Y470586D03*
X1549925Y480726D03*
X1551875Y477346D03*
X1546025Y473966D03*
X1547975Y477346D03*
X1559675Y470586D03*
X1533595Y505530D03*
X1559675Y484106D03*
X1561625Y480726D03*
X1557725Y487486D03*
X1561625D03*
X1567475Y484106D03*
X1563575D03*
X1559675Y477346D03*
X1565525Y487486D03*
X1563575Y477346D03*
X1571375D03*
X1590580Y472370D03*
X1536275Y477346D03*
X1534325Y480726D03*
Y473966D03*
X1538225Y480726D03*
X1532375Y484106D03*
Y477346D03*
X1540175Y470586D03*
X1563575D03*
X1561625Y473966D03*
X1565525D03*
X1567475Y477346D03*
X1584970Y472370D03*
X1542125Y487486D03*
X1540175Y484106D03*
X1546025Y487486D03*
X1551875Y484106D03*
X1538225Y487486D03*
X1542125Y480726D03*
X1544075Y484106D03*
X1547975D03*
X1550990Y586588D03*
X1554358Y587258D03*
X1592934Y592396D03*
X1587610Y579550D03*
X1585155Y538574D03*
X1581730Y537170D03*
X1565389Y585721D03*
X1535565Y591658D03*
X1579900Y606050D03*
X1586700Y620100D03*
X1540477Y620308D03*
X1540700Y613700D03*
X1545407Y598393D03*
X1541384Y601262D03*
X1546075Y618145D03*
X1544050Y615296D03*
X1579680Y610279D03*
X1534968Y597268D03*
X1573500Y619500D03*
X1577000D03*
X1572950Y593950D03*
X1601650Y24160D03*
X1617500Y-14500D03*
X1597800Y24300D03*
X1637482Y21623D03*
X1653100Y11500D03*
X1638550Y7200D03*
X1623900Y4600D03*
X1598602Y3437D03*
X1599000Y61500D03*
X1596050Y75400D03*
X1632006Y94500D03*
X1640900Y66900D03*
X1630826Y88087D03*
X1614997Y84403D03*
X1625075Y80182D03*
X1597867Y93900D03*
X1597987Y79500D03*
X1619000Y38500D03*
X1606579Y86726D03*
X1614169Y95004D03*
X1617347Y94581D03*
X1599500Y75000D03*
X1649900Y78600D03*
X1653000Y77600D03*
X1643500Y80400D03*
X1635337Y73500D03*
X1604000Y93925D03*
X1627489Y74960D03*
X1632020Y97871D03*
X1632000Y73500D03*
X1628788Y97800D03*
X1621100Y69600D03*
X1620900Y81300D03*
X1593241Y134295D03*
X1598300Y116477D03*
X1598449Y120760D03*
X1600148Y142262D03*
X1604292Y150137D03*
X1596427Y157975D03*
X1600490Y158010D03*
X1604169Y156407D03*
X1600000Y104243D03*
X1616900Y143880D03*
X1653111Y102240D03*
X1648000Y100597D03*
X1594452Y111377D03*
X1600900Y131900D03*
X1608000Y99400D03*
X1607441Y106042D03*
X1635750Y128240D03*
X1642087Y143837D03*
X1637363Y149484D03*
X1593756Y129048D03*
X1642087Y153286D03*
X1632639Y124940D03*
X1647852Y197374D03*
X1651000Y178628D03*
X1603300Y185100D03*
X1600490Y167459D03*
X1627326Y182759D03*
X1654015Y217239D03*
X1615362Y213507D03*
X1622217Y177809D03*
X1650600Y186300D03*
X1648349Y182276D03*
X1645700Y214050D03*
X1602185Y180709D03*
X1635351Y185444D03*
X1608731Y180819D03*
X1598006Y192421D03*
X1595291Y166423D03*
X1644290Y196383D03*
X1648320Y172690D03*
X1635621Y208259D03*
X1643662Y172609D03*
X1601870Y270470D03*
X1643106Y233913D03*
X1600810Y266006D03*
X1636914Y270900D03*
X1596300Y250320D03*
X1627024Y253387D03*
X1631300Y280400D03*
X1637281Y260922D03*
X1597201Y238188D03*
X1643775Y246137D03*
X1637281Y254322D03*
X1617498Y273433D03*
X1632128Y225472D03*
X1637269Y264421D03*
X1622000Y279495D03*
X1627043Y256900D03*
X1636684Y283141D03*
X1610290Y265352D03*
X1638216Y246021D03*
X1604222Y268107D03*
X1608764Y322440D03*
X1608850Y343835D03*
X1638086Y319664D03*
X1625400Y327667D03*
X1602776Y331304D03*
X1652991Y321341D03*
X1620159Y332004D03*
X1638063Y326504D03*
X1631015Y328350D03*
X1635355Y324228D03*
X1639040Y316343D03*
X1625846Y286154D03*
X1609172Y339630D03*
X1636800Y287956D03*
X1602215Y363981D03*
X1610140Y358350D03*
X1609271Y348166D03*
X1621727Y395374D03*
X1612825Y405438D03*
X1622100Y400600D03*
X1630400Y391800D03*
X1629300Y385400D03*
X1630750Y404800D03*
X1613452Y387098D03*
X1638991Y352037D03*
X1621800Y381500D03*
Y386300D03*
X1595800Y405900D03*
X1639750Y445477D03*
X1630219Y446000D03*
X1621000Y440500D03*
X1621044Y433364D03*
X1621182Y427091D03*
X1603719Y412000D03*
X1611638Y454809D03*
X1612100Y446000D03*
X1646480Y443880D03*
X1611642Y461877D03*
X1630150Y427663D03*
X1593400Y432200D03*
X1639774Y439486D03*
X1623705Y467855D03*
X1639822Y453140D03*
X1647200Y430450D03*
X1640625Y429460D03*
X1621226Y445026D03*
X1615061Y463157D03*
X1596500Y455500D03*
X1617900Y409900D03*
X1595200Y412700D03*
X1651754Y488025D03*
X1626518Y528029D03*
X1627622Y524928D03*
X1631975Y527700D03*
X1597380Y495416D03*
X1600780D03*
X1617300Y519000D03*
X1625485Y494188D03*
X1623551Y525015D03*
X1621783Y498617D03*
X1620030Y525066D03*
X1645969Y514870D03*
X1617700Y475957D03*
X1614000Y475970D03*
X1639271Y491135D03*
X1639391Y513065D03*
X1629778Y507294D03*
X1642670Y514939D03*
X1629500Y491500D03*
X1649336Y511502D03*
X1641470Y506403D03*
X1644651Y505500D03*
X1649545Y515215D03*
X1601540Y588793D03*
X1622330Y592325D03*
X1594110Y611510D03*
X1619700Y617300D03*
X1617600Y619800D03*
X1680033Y-16711D03*
X1666500Y10500D03*
X1680034Y2863D03*
X1697300Y73296D03*
X1689250Y86000D03*
X1692300Y56900D03*
X1658600Y44700D03*
X1667000Y88000D03*
X1693900Y73300D03*
X1708610Y85121D03*
X1713900Y87900D03*
X1696870Y86093D03*
X1711000Y55525D03*
X1712600Y46100D03*
X1707268Y77668D03*
X1669000Y92000D03*
X1709184Y88811D03*
X1678627Y54616D03*
X1684248Y56746D03*
X1690500Y73950D03*
X1715100Y70500D03*
X1659000Y88000D03*
X1661900Y92400D03*
X1704824Y90049D03*
X1664500Y99000D03*
X1672200Y112200D03*
X1696907Y99077D03*
X1678400Y103000D03*
X1667348Y156500D03*
X1674800Y103100D03*
X1659643Y213505D03*
X1687550Y213751D03*
X1674912Y183000D03*
X1673530Y209974D03*
X1708350Y175050D03*
X1660800Y181900D03*
X1663400Y179475D03*
X1667140Y182300D03*
X1669849Y193067D03*
X1665063Y172608D03*
X1702400Y193450D03*
X1664321Y195244D03*
X1658082Y195298D03*
X1655978Y207827D03*
X1705666Y198055D03*
X1671688Y182925D03*
X1688046Y174447D03*
X1664390Y201163D03*
X1660440Y200789D03*
X1667356Y213096D03*
X1691439Y174354D03*
X1713000Y185000D03*
X1674019Y175990D03*
X1713596Y175795D03*
X1676750Y206050D03*
X1681116Y238614D03*
X1657500Y259700D03*
X1657567Y264600D03*
X1657498Y269700D03*
Y274700D03*
Y279900D03*
X1715837Y246178D03*
X1715078Y250231D03*
X1657494Y292816D03*
X1657498Y284900D03*
X1664453Y308557D03*
X1660972Y401447D03*
X1660834Y404934D03*
X1660890Y397300D03*
X1673074Y453185D03*
X1675120Y439731D03*
X1679145Y461950D03*
X1667588Y434149D03*
X1668100Y418700D03*
X1678303Y442765D03*
X1667946Y412987D03*
X1673550Y442696D03*
X1714530Y519900D03*
X1710594D03*
X1676800Y483800D03*
X1681650Y510673D03*
X1687606Y500938D03*
X1672265Y473600D03*
X1681115Y525218D03*
X1716490Y506970D03*
X1681500Y482000D03*
X1671050Y487000D03*
Y490850D03*
X1672159Y494042D03*
X1655790Y476593D03*
X1705767Y482434D03*
X1698354Y486873D03*
X1701617Y482706D03*
X1680133Y535489D03*
X1710389Y577787D03*
X1699600Y578100D03*
X1710000Y604500D03*
Y600000D03*
X1701291Y602268D03*
X1741544Y9151D03*
X1749085Y9177D03*
X1744900Y9100D03*
X1725474Y69250D03*
X1746328Y59011D03*
X1760016Y65774D03*
X1771707Y86500D03*
X1767250Y94500D03*
Y89500D03*
X1766333Y59116D03*
X1775000Y53500D03*
X1750400Y47400D03*
X1720100Y46100D03*
X1720500Y52440D03*
X1717014Y97550D03*
X1757998Y73637D03*
X1731350Y92140D03*
X1757772Y90174D03*
X1765015Y119100D03*
X1776828Y155211D03*
X1735989Y133250D03*
X1728789Y136250D03*
X1735989Y149050D03*
X1726539Y139450D03*
X1734989Y142750D03*
X1726464Y111150D03*
X1731789Y139450D03*
X1717014Y142650D03*
X1746189Y153250D03*
X1748425Y119190D03*
X1745768Y111743D03*
X1745363Y108004D03*
X1742214Y114300D03*
X1720164Y117451D03*
X1745364Y117450D03*
X1717014Y133200D03*
Y111150D03*
X1745500Y104500D03*
X1768886Y156173D03*
X1719000Y190500D03*
X1719080Y236152D03*
X1718820Y249032D03*
X1727896Y246175D03*
X1719080Y232852D03*
X1720651Y246141D03*
X1749462Y232955D03*
X1746900Y249804D03*
X1751900Y249700D03*
X1722251Y250532D03*
X1724181Y246159D03*
X1730996Y442804D03*
X1737150Y450850D03*
X1719089Y472104D03*
X1728700Y470200D03*
X1719560Y501770D03*
X1766100Y521124D03*
X1722347Y471811D03*
X1750800Y516100D03*
X1762715Y521085D03*
X1753807Y548183D03*
X1757478Y548192D03*
X1767529Y566200D03*
X1764300Y570900D03*
X1742200Y552863D03*
X1724899Y584748D03*
X1733000Y557000D03*
X1767141Y555500D03*
X1756578Y586743D03*
X1724250Y588250D03*
X1743000Y574500D03*
X1730759Y548162D03*
X1722500Y562000D03*
X1754897Y578750D03*
X1742381Y588530D03*
X1767500Y559800D03*
X1738498Y554255D03*
X1750399Y603201D03*
X1739714Y604967D03*
X1716950Y603450D03*
X1735000Y621002D03*
X1764823Y613600D03*
X1725133Y614896D03*
X1766400Y599400D03*
X1770600Y600800D03*
X1764912Y618718D03*
X1728341Y614851D03*
X1819800Y2100D03*
X1813913Y2287D03*
X1799462Y8830D03*
X1804462D03*
X1790078Y11860D03*
X1795078Y11900D03*
X1792700Y36871D03*
X1797700Y36804D03*
X1831000Y-16300D03*
X1828874Y-13520D03*
X1815150Y26650D03*
X1779750Y36530D03*
X1791500Y26918D03*
X1808100Y21800D03*
X1813795Y12165D03*
X1819837Y21700D03*
X1786865Y22375D03*
X1823600Y8800D03*
X1797700Y21018D03*
X1837500Y35700D03*
X1838850Y13160D03*
X1836700Y-18900D03*
X1804800Y-1500D03*
X1816723Y9781D03*
X1826414Y35486D03*
X1835600Y3900D03*
X1824240Y83680D03*
X1802119Y56581D03*
X1799438Y44328D03*
X1827000Y94550D03*
X1827150Y97800D03*
X1827100Y81600D03*
X1798454Y82256D03*
X1788216Y59197D03*
X1821350Y98270D03*
X1803300Y39900D03*
X1808363Y40033D03*
X1812352Y36949D03*
X1838500Y40400D03*
X1820457Y39128D03*
X1829580Y38620D03*
X1810100Y114700D03*
X1808226Y136171D03*
X1803509Y128500D03*
X1807818Y124179D03*
X1813118Y127976D03*
X1815026Y121478D03*
X1788000Y129000D03*
X1815883Y133277D03*
X1808313Y111705D03*
X1807509Y128500D03*
X1814900Y116900D03*
X1783252Y109044D03*
X1796500Y120000D03*
X1815348Y143437D03*
X1803058Y143733D03*
X1830316Y102163D03*
X1827500Y144900D03*
X1837090Y149830D03*
X1839667Y151994D03*
X1809810Y155858D03*
X1800792Y122691D03*
X1824990Y103620D03*
X1787373Y120188D03*
X1816418Y127976D03*
X1807166Y147401D03*
X1800420Y148240D03*
X1821261Y170012D03*
X1824200Y176900D03*
X1830415Y196567D03*
X1785500Y164000D03*
X1836100Y179700D03*
X1836900Y165800D03*
X1787000Y175500D03*
X1778900Y165800D03*
X1834103Y176021D03*
X1833629Y170807D03*
X1836932Y170486D03*
X1816125Y169492D03*
X1834400Y216900D03*
X1785500Y168000D03*
X1822877Y235852D03*
X1826085Y236034D03*
X1822638Y232106D03*
X1826662Y232191D03*
X1784440Y232938D03*
X1804388Y249904D03*
X1831700Y252272D03*
X1837857Y468630D03*
X1834100Y523900D03*
X1814852Y519901D03*
X1810350Y525650D03*
X1809700Y506875D03*
X1820400Y501100D03*
X1837200Y525700D03*
X1813500Y526500D03*
X1816584Y530542D03*
X1810200Y513300D03*
X1837300Y472276D03*
X1825900Y523500D03*
X1815200Y501500D03*
X1794100Y521900D03*
X1798250Y529200D03*
X1803900Y491500D03*
X1795200Y525700D03*
X1836600Y521600D03*
X1831600Y529000D03*
X1833700Y497300D03*
X1781300Y537800D03*
X1837475Y573835D03*
X1829051Y591299D03*
X1809600Y582800D03*
X1793660Y560570D03*
X1811100Y586800D03*
X1816458Y587480D03*
X1829300Y572900D03*
X1793100Y578500D03*
X1816020Y571448D03*
X1812802Y578693D03*
X1780394Y561076D03*
X1837534Y579322D03*
X1792805Y574675D03*
X1832500Y539500D03*
X1829000Y536315D03*
X1832200Y567760D03*
X1791349Y589122D03*
X1788300Y585100D03*
X1810863Y560637D03*
X1816175Y567669D03*
X1838224Y586650D03*
X1783700Y576400D03*
X1785050Y584550D03*
X1792100Y566900D03*
X1816330Y545260D03*
X1816100Y576200D03*
X1829176Y584287D03*
X1809309Y555713D03*
X1839126Y583354D03*
X1831500Y544500D03*
Y548000D03*
X1831800Y552300D03*
X1837000Y534900D03*
X1782300Y555900D03*
X1778675Y592224D03*
X1794500Y612500D03*
X1791500Y606500D03*
X1782700Y610900D03*
X1795000Y599600D03*
X1791323Y594030D03*
X1805000Y606500D03*
X1787500Y600500D03*
X1784200Y593924D03*
X1900256Y-14760D03*
X1841060Y35540D03*
X1882999Y7383D03*
X1883041Y15814D03*
X1893094Y-12642D03*
X1876792Y18461D03*
X1876881Y22181D03*
X1878000Y73950D03*
X1843107Y97988D03*
X1848208Y49427D03*
X1889218Y51030D03*
Y46030D03*
Y61030D03*
Y56030D03*
X1842250Y84000D03*
X1858600Y74300D03*
X1849426Y90700D03*
Y95500D03*
X1883200Y76600D03*
X1850600Y41348D03*
X1875600Y156300D03*
X1857110Y113600D03*
X1881324Y153250D03*
X1890974Y105600D03*
X1898102Y107325D03*
X1885700Y141200D03*
X1897536Y114600D03*
Y120510D03*
X1887497Y105444D03*
X1878753Y139893D03*
X1867280Y135406D03*
X1881165Y105561D03*
X1885102Y101134D03*
X1866606Y109967D03*
X1857849Y148079D03*
X1872254Y138618D03*
X1872400Y144619D03*
X1871521Y153593D03*
X1888639Y147042D03*
X1893640D03*
X1894855Y142122D03*
X1899855D03*
X1861932Y146431D03*
X1857919Y156123D03*
X1869668Y146750D03*
X1864904Y114735D03*
X1895060Y136099D03*
X1897507Y124450D03*
X1895673Y151800D03*
X1868843Y207920D03*
X1874236Y213800D03*
X1893238Y208042D03*
X1863650Y189750D03*
X1877880Y203780D03*
X1847200Y202050D03*
X1884340Y217866D03*
X1840900Y179700D03*
X1845700D03*
X1896710Y194380D03*
X1882452Y195888D03*
X1901100Y194200D03*
X1889400Y191200D03*
X1886200Y161000D03*
X1875700Y184800D03*
X1864637Y201861D03*
X1876700Y207600D03*
X1872100Y207900D03*
X1861243Y183100D03*
X1862000Y177500D03*
X1884000Y188100D03*
X1884400Y183700D03*
X1858686Y180377D03*
X1858500Y200100D03*
X1864000Y184900D03*
X1878789Y213663D03*
X1891880Y204370D03*
X1856874Y219443D03*
X1864464Y198466D03*
X1885465Y166285D03*
X1855000Y167100D03*
X1850723Y219250D03*
X1865100Y174600D03*
X1877517Y217988D03*
X1840149Y244425D03*
X1843449D03*
X1899816Y235035D03*
X1844444Y224035D03*
X1854374Y248790D03*
X1854720Y253700D03*
X1846517Y253500D03*
X1850220D03*
X1896529Y235080D03*
X1892274D03*
X1842857Y468630D03*
X1878100Y450200D03*
X1868167Y467855D03*
X1863137Y452710D03*
X1859059Y448076D03*
X1858633Y452803D03*
X1901574Y454422D03*
X1875900Y453600D03*
X1867500Y447900D03*
X1859530Y516430D03*
X1842400Y516800D03*
X1841900Y498800D03*
X1900890Y477200D03*
X1864339Y509560D03*
X1863000Y480000D03*
X1859600Y476200D03*
X1852719Y487575D03*
Y492575D03*
X1876945Y471316D03*
X1877407Y479046D03*
X1857450Y473654D03*
X1855206Y471112D03*
X1847000Y487500D03*
X1860000Y495500D03*
X1842764Y528136D03*
X1869914Y517225D03*
X1866688Y517128D03*
X1870100Y561150D03*
X1844018Y586482D03*
X1868200Y590939D03*
X1858528Y544528D03*
X1875850Y567200D03*
X1840690Y557190D03*
X1878500Y553500D03*
X1858500Y540000D03*
X1852250Y547900D03*
X1858681Y568087D03*
X1879862Y581862D03*
X1896899Y557790D03*
X1900729Y569557D03*
X1864580Y537060D03*
X1878736Y533040D03*
X1868110Y536000D03*
X1845407Y533178D03*
X1900250Y533700D03*
X1856573Y576534D03*
X1895523Y586365D03*
X1857812Y557245D03*
X1866800Y588000D03*
X1869800Y557100D03*
X1878875Y565475D03*
X1847070Y537610D03*
X1882300Y565550D03*
X1885100Y584300D03*
X1848900Y590750D03*
X1845000Y590800D03*
X1873510Y541710D03*
X1875600Y588500D03*
X1840700Y563800D03*
X1854530Y533132D03*
X1896358Y595255D03*
X1916078Y-16368D03*
X1918352Y89300D03*
X1923300Y94300D03*
X1920300Y68300D03*
X1917600Y66000D03*
X1948472Y80362D03*
X1933914Y96040D03*
X1946500Y104974D03*
X1940700Y136300D03*
X1908327Y149353D03*
X1904215Y142812D03*
X1909216D03*
X1943752Y137548D03*
X1947078Y139300D03*
X1963400Y141100D03*
X1921264Y153000D03*
X1937900Y153600D03*
X1923800Y151000D03*
X1927000Y152200D03*
X1934544Y127957D03*
X1929000Y158600D03*
X1926952Y156049D03*
X1952726Y102950D03*
X1914500Y113300D03*
X1940500Y157600D03*
X1932998Y119438D03*
X1923329Y99475D03*
X1947000Y142600D03*
X1923837Y118800D03*
X1937728Y99441D03*
X1925358Y140685D03*
X1903150Y217250D03*
X1910123Y217349D03*
X1957334Y201269D03*
X1939300Y204300D03*
X1917568Y201215D03*
X1917024Y193600D03*
X1929700Y163400D03*
X1921500Y193600D03*
X1940240Y169970D03*
X1939550Y165600D03*
X1931483Y199350D03*
X1940647Y161600D03*
X1909438Y204307D03*
X1904042Y204895D03*
X1903917Y201472D03*
X1925400Y196300D03*
X1929090Y193190D03*
X1939400Y198400D03*
X1934100Y193400D03*
X1935600Y176300D03*
X1932837Y186700D03*
X1925000Y192000D03*
X1918489Y212513D03*
X1943500Y209500D03*
X1930500Y209464D03*
X1918143Y219848D03*
X1927064Y207564D03*
X1938400Y178200D03*
X1939200Y194300D03*
X1935600Y198700D03*
X1950981Y191218D03*
X1963300Y191000D03*
X1952717Y198614D03*
X1943217Y221154D03*
Y217645D03*
X1942000Y440500D03*
X1937430Y464785D03*
X1904724Y447930D03*
X1939845Y445055D03*
X1947550Y485350D03*
X1956500Y507470D03*
X1938300Y486250D03*
X1957250Y512050D03*
X1937300Y508900D03*
X1919230Y483430D03*
X1919000Y487210D03*
X1919510Y475100D03*
Y479200D03*
X1939000Y476600D03*
X1956606Y526671D03*
X1957212Y479521D03*
X1957063Y474769D03*
X1945000Y474000D03*
X1948200Y474300D03*
X1928620Y482710D03*
X1956300Y515900D03*
X1959300Y518000D03*
X1908300Y514500D03*
X1942328Y508712D03*
X1963000Y573000D03*
X1921244Y533750D03*
X1951900Y534900D03*
X1963097Y551000D03*
X1934200Y573700D03*
X1935400Y583000D03*
X1940800Y537300D03*
X1945900Y549900D03*
X1923500Y579500D03*
X1948100Y538700D03*
X1923400Y583000D03*
X1923600Y575500D03*
X1926600Y559500D03*
X1923600Y565100D03*
X1923000Y568700D03*
X1959120Y547050D03*
X1958940Y538890D03*
X1961715Y555639D03*
X1918880Y586460D03*
X1961771Y591744D03*
X1962950Y566600D03*
X1956191Y548700D03*
X1962500Y578500D03*
X1958500Y535000D03*
X1907500Y545600D03*
X1907200Y551600D03*
X1932390Y590100D03*
X1959400Y601100D03*
X1934350Y609250D03*
X1923504Y592500D03*
X1911750Y592800D03*
X1927000Y614500D03*
X1914700Y594600D03*
X1963300Y612800D03*
X1938130Y601480D03*
X1967580Y104721D03*
X1972598Y165236D03*
X1967200Y521600D03*
X1964270Y511410D03*
X1968375Y509375D03*
X1972700Y576400D03*
Y549950D03*
X1964890Y534940D03*
X1965400Y619500D03*
X1456000Y360700D03*
X1460400Y353000D03*
X1459111Y356353D03*
X1467597Y363000D03*
X1463870Y367869D03*
X1453900Y353350D03*
X1453251Y356676D03*
X1552500Y358500D03*
X1550417Y362607D03*
G54D95*
X1854501Y195587D03*
X1859854Y501441D03*
X1952756Y589960D03*
X1944882Y582086D03*
X1952756D03*
X1944882Y574212D03*
X1952756D03*
X1944882Y566338D03*
X1952756D03*
X1944882Y558464D03*
Y589960D03*
X1952756Y558464D03*
X1944882Y605708D03*
X1952756D03*
X1944882Y597834D03*
X1952756D03*
G54D86*
X1638131Y475946D03*
G54D71*
X-4488Y425472D03*
X99980Y136909D03*
X1472000Y-5000D03*
Y-15000D03*
X1462000Y-5000D03*
Y-15000D03*
X1452000Y-5000D03*
Y-15000D03*
X1442000Y-5000D03*
Y-15000D03*
X1525000D03*
X1515000D03*
X1505000D03*
X1482000D03*
X1492000Y-5000D03*
Y-15000D03*
X1482000Y-5000D03*
X1575000Y-15000D03*
X1565000D03*
X1555000D03*
X1545000D03*
X1535000D03*
X1713503Y-5000D03*
Y-15000D03*
X1703503Y-5000D03*
Y-15000D03*
X1743503D03*
X1733503Y-5000D03*
Y-15000D03*
X1743503Y-5000D03*
X1779504D03*
X1769504D03*
Y-15000D03*
X1809504D03*
X1799504Y-5000D03*
Y-15000D03*
X1789504Y-5000D03*
Y-15000D03*
X1819504Y-5000D03*
Y-15000D03*
X1809504Y-5000D03*
G54D48*
X40500Y-42250D03*
Y-52250D03*
X60500Y-42250D03*
X80500D03*
X100500D03*
X60500Y-52250D03*
X80500D03*
X100500D03*
X120500Y-42250D03*
X140500D03*
X120500Y-52250D03*
X140500D03*
X467246Y-52301D03*
Y-42301D03*
X487246Y-52301D03*
Y-42301D03*
X507246Y-52301D03*
Y-42301D03*
X527246Y-52301D03*
Y-42301D03*
X547246Y-52301D03*
Y-42301D03*
X567246Y-52301D03*
Y-42301D03*
X798984Y-52057D03*
Y-42057D03*
X818984Y-52057D03*
Y-42057D03*
X838984Y-52057D03*
Y-42057D03*
X858984Y-52057D03*
Y-42057D03*
X878984Y-52057D03*
Y-42057D03*
X898984Y-52057D03*
Y-42057D03*
X1135583Y-52285D03*
Y-42285D03*
X1155583Y-52285D03*
Y-42285D03*
X1392258Y-52257D03*
Y-42257D03*
X1412258Y-52257D03*
Y-42257D03*
X1432258Y-52257D03*
Y-42257D03*
X1452258Y-52257D03*
Y-42257D03*
G54D98*
X1922248Y518328D03*
G54D92*
X1724807Y451179D03*
X1851250Y584622D03*
Y576748D03*
Y568874D03*
Y561000D03*
G54D88*
X1674921Y528523D03*
X1773347D03*
Y545059D03*
G54D78*
X638541Y171945D03*
Y454425D03*
X752641Y159945D03*
X1288068Y171945D03*
Y454425D03*
X1402168Y159945D03*
Y442425D03*
G54D68*
X40512Y458744D03*
G54D61*
X-15748Y116969D03*
Y132717D03*
X787D03*
X28740Y124843D03*
Y140591D03*
G54D70*
X30512Y467244D03*
X40512D03*
G54D94*
X1809665Y618663D03*
X1819665D03*
X1829665D03*
G54D73*
X63093Y202300D03*
X72936D03*
X82779D03*
X1914911Y495775D03*
X1934597D03*
X1924754D03*
G54D63*
X-14488Y434094D03*
X-4488D03*
X5512D03*
X15512D03*
X89980Y145531D03*
X99980D03*
X109980D03*
X119980D03*
G54D80*
X1401516Y23976D03*
G54D56*
X1466694Y375787D03*
G54D59*
X1705772Y567874D03*
G54D90*
X1775525Y204577D03*
X1771525D03*
X1763497D03*
X1759497D03*
X1750589Y204321D03*
X1746589D03*
G54D76*
X163777Y4023D03*
X133659D03*
X143699D03*
X163777Y79623D03*
Y41823D03*
X133659Y79623D03*
X143699D03*
X133659Y41823D03*
X143699D03*
X163777Y505023D03*
X143699D03*
X133659D03*
X163777Y580623D03*
Y542823D03*
X143699Y580623D03*
X133659D03*
X143699Y542823D03*
X133659D03*
X217321Y4023D03*
X207281D03*
X193895D03*
X187203D03*
X173817Y22133D03*
X177163D03*
Y4023D03*
X217321Y79623D03*
Y41823D03*
X187203Y79623D03*
X193895D03*
X207281D03*
X193895Y41823D03*
X207281D03*
X187203D03*
X173817Y97733D03*
X177163D03*
Y79623D03*
Y41823D03*
X173817Y59933D03*
X177163D03*
X217321Y505023D03*
X173817Y523133D03*
X177163D03*
Y505023D03*
X207281D03*
X187203D03*
X193895D03*
X217321Y580623D03*
Y542823D03*
X207281Y580623D03*
X193895D03*
X187203D03*
X177163D03*
Y560933D03*
X173817D03*
X177163Y542823D03*
X207281D03*
X187203D03*
X193895D03*
X177163Y598733D03*
X173817D03*
X280903Y4023D03*
X290943D03*
X247439Y22133D03*
X250785D03*
Y4023D03*
X260825D03*
X237399D03*
X267517D03*
X280903Y79623D03*
X290943D03*
Y41823D03*
X280903D03*
X267517Y79623D03*
X250785Y97733D03*
X247439D03*
X237399Y79623D03*
X250785D03*
X260825D03*
X250785Y59933D03*
X247439D03*
X260825Y41823D03*
X237399D03*
X250785D03*
X267517D03*
X280903Y505023D03*
X290943D03*
X267517D03*
X247439Y523133D03*
X250785D03*
X260825Y505023D03*
X237399D03*
X250785D03*
X280903Y580623D03*
X290943D03*
X280903Y542823D03*
X290943D03*
X260825Y580623D03*
X250785Y560933D03*
X247439D03*
X237399Y580623D03*
X250785D03*
X267517D03*
X260825Y542823D03*
X237399D03*
X250785D03*
X267517D03*
X247439Y598733D03*
X250785D03*
X468305Y22133D03*
X454919Y4023D03*
X468305D03*
X471651D03*
X454919Y79623D03*
X468305D03*
X471651D03*
X468305Y97733D03*
Y41823D03*
X471651D03*
X468305Y59933D03*
X454919Y41823D03*
Y505023D03*
X468305Y523133D03*
Y505023D03*
X471651D03*
Y580623D03*
X468305Y560933D03*
Y580623D03*
X454919D03*
Y542823D03*
X468305D03*
X471651D03*
X468305Y598733D03*
X541927Y22133D03*
X515155Y4023D03*
X541927D03*
X528541D03*
X501769Y22133D03*
X498423Y4023D03*
X485037D03*
X541927Y79623D03*
Y97733D03*
X528541Y79623D03*
X515155D03*
X541927Y41823D03*
Y59933D03*
X528541Y41823D03*
X515155D03*
X501769Y97733D03*
X498423Y79623D03*
X485037D03*
X501769Y59933D03*
X498423Y41823D03*
X485037D03*
X541927Y505023D03*
Y523133D03*
X528541Y505023D03*
X515155D03*
X485037D03*
X501769Y523133D03*
X498423Y505023D03*
X541927Y580623D03*
X528541D03*
X541927Y560933D03*
X515155Y580623D03*
X528541Y542823D03*
X541927D03*
X515155D03*
X501769Y560933D03*
X498423Y580623D03*
X485037D03*
X498423Y542823D03*
X485037D03*
X541927Y598733D03*
X501769D03*
X575391Y22133D03*
X588777Y4023D03*
X558659D03*
X572045D03*
X545273D03*
X575391Y97733D03*
X588777Y79623D03*
X575391Y59933D03*
X588777Y41823D03*
X545273Y79623D03*
X572045D03*
X558659D03*
X572045Y41823D03*
X545273D03*
X558659D03*
X575391Y523133D03*
X588777Y505023D03*
X545273D03*
X572045D03*
X558659D03*
X575391Y560933D03*
X588777Y580623D03*
Y542823D03*
X545273Y580623D03*
X572045D03*
X558659D03*
Y542823D03*
X545273D03*
X572045D03*
X575391Y598733D03*
X783267Y4023D03*
Y79623D03*
Y41823D03*
Y505023D03*
Y580623D03*
Y542823D03*
X826771Y22133D03*
X823425D03*
X826771Y4023D03*
X836811D03*
X843503D03*
X793307D03*
X813385D03*
X826771Y97733D03*
Y79623D03*
X843503D03*
X836811D03*
X823425Y97733D03*
X836811Y41823D03*
X823425Y59933D03*
X826771D03*
Y41823D03*
X843503D03*
X793307Y79623D03*
X813385D03*
X793307Y41823D03*
X813385D03*
X843503Y505023D03*
X836811D03*
X826771Y523133D03*
Y505023D03*
X823425Y523133D03*
X793307Y505023D03*
X813385D03*
X843503Y580623D03*
X836811D03*
X826771D03*
X823425Y560933D03*
X826771D03*
X836811Y542823D03*
X826771D03*
X843503D03*
X793307Y580623D03*
X813385D03*
Y542823D03*
X793307D03*
X826771Y598733D03*
X823425D03*
X887007Y4023D03*
X900393D03*
X897047Y22133D03*
X900393D03*
X910433Y4023D03*
X866929D03*
X856889D03*
X910433Y79623D03*
X887007D03*
X900393Y97733D03*
X897047D03*
X900393Y79623D03*
Y59933D03*
X897047D03*
X887007Y41823D03*
X900393D03*
X910433D03*
X856889Y79623D03*
X866929D03*
X856889Y41823D03*
X866929D03*
X900393Y505023D03*
X910433D03*
X900393Y523133D03*
X897047D03*
X887007Y505023D03*
X856889D03*
X866929D03*
X910433Y580623D03*
X887007D03*
X900393D03*
Y560933D03*
X897047D03*
X910433Y542823D03*
X900393D03*
X887007D03*
X856889Y580623D03*
X866929D03*
Y542823D03*
X856889D03*
X897047Y598733D03*
X900393D03*
X940551Y4023D03*
X917125D03*
X930511D03*
X940551Y79623D03*
Y41823D03*
X917125Y79623D03*
X930511D03*
Y41823D03*
X917125D03*
X940551Y505023D03*
X930511D03*
X917125D03*
X940551Y580623D03*
Y542823D03*
X917125Y580623D03*
X930511D03*
Y542823D03*
X917125D03*
X1151377Y22133D03*
X1148031Y4023D03*
X1121259D03*
X1134645D03*
X1117913Y22133D03*
X1104527Y4023D03*
X1117913D03*
X1134645Y79623D03*
X1121259D03*
X1151377Y97733D03*
X1148031Y79623D03*
Y41823D03*
X1151377Y59933D03*
X1134645Y41823D03*
X1121259D03*
X1104527Y79623D03*
X1117913D03*
Y97733D03*
Y59933D03*
X1104527Y41823D03*
X1117913D03*
X1121259Y505023D03*
X1151377Y523133D03*
X1134645Y505023D03*
X1148031D03*
X1117913D03*
X1104527D03*
X1117913Y523133D03*
X1121259Y580623D03*
X1148031D03*
X1151377Y560933D03*
X1134645Y580623D03*
X1121259Y542823D03*
X1148031D03*
X1134645D03*
X1117913Y580623D03*
X1104527D03*
X1117913Y560933D03*
X1104527Y542823D03*
X1117913D03*
X1151377Y598733D03*
X1117913D03*
X1191535Y22133D03*
Y4023D03*
X1194881D03*
X1221653D03*
X1208267D03*
X1164763D03*
X1178149D03*
X1191535Y97733D03*
Y79623D03*
X1194881D03*
X1221653D03*
X1208267D03*
Y41823D03*
X1191535D03*
Y59933D03*
X1194881Y41823D03*
X1221653D03*
X1178149Y79623D03*
X1164763D03*
X1178149Y41823D03*
X1164763D03*
X1191535Y505023D03*
X1194881D03*
X1191535Y523133D03*
X1221653Y505023D03*
X1208267D03*
X1178149D03*
X1164763D03*
X1191535Y560933D03*
Y580623D03*
X1194881D03*
X1208267D03*
X1221653D03*
X1194881Y542823D03*
X1191535D03*
X1221653D03*
X1208267D03*
X1178149Y580623D03*
X1164763D03*
Y542823D03*
X1178149D03*
X1191535Y598733D03*
X1238385Y4023D03*
X1224999Y22133D03*
Y97733D03*
X1238385Y79623D03*
X1224999Y59933D03*
X1238385Y41823D03*
Y505023D03*
X1224999Y523133D03*
Y560933D03*
X1238385Y580623D03*
Y542823D03*
X1224999Y598733D03*
G54D72*
X94683Y31978D03*
Y13078D03*
Y69778D03*
Y50878D03*
Y532955D03*
Y514079D03*
Y570755D03*
Y589679D03*
Y551879D03*
Y608555D03*
X637793Y-5822D03*
Y13078D03*
Y69778D03*
Y50878D03*
Y88678D03*
Y532955D03*
Y514079D03*
Y570755D03*
Y589679D03*
Y551879D03*
Y608555D03*
X744293Y-5822D03*
Y31978D03*
Y13078D03*
Y69778D03*
Y88678D03*
Y50878D03*
Y532955D03*
Y514079D03*
Y570755D03*
Y589679D03*
Y551879D03*
Y608555D03*
X1287403Y-5822D03*
Y31978D03*
Y13078D03*
Y69778D03*
Y88678D03*
Y50878D03*
Y532955D03*
Y514079D03*
Y551879D03*
Y608555D03*
G54D62*
X-7874Y216181D03*
Y325315D03*
G54D60*
X0Y0D03*
G54D93*
X1788300Y204277D03*
X1784300D03*
X1801200Y204877D03*
X1797200D03*
X1826100Y204677D03*
X1822100D03*
X1813600Y204777D03*
X1809600D03*
G54D83*
X1518860Y116361D03*
Y120361D03*
G54D82*
X1519321Y104358D03*
Y108358D03*
X1581505Y502596D03*
Y497596D03*
G54D75*
X170470Y4023D03*
X150392D03*
X157084D03*
X137006Y22133D03*
X140352D03*
X126966Y4023D03*
X140352D03*
X137006Y97733D03*
X140352D03*
X157084Y79623D03*
X150392D03*
Y41823D03*
X157084D03*
X126966Y79623D03*
X140352D03*
X137006Y59933D03*
X140352D03*
X126966Y41823D03*
X140352D03*
X170470Y79623D03*
Y41823D03*
X157084Y505023D03*
X170470D03*
X150392D03*
X126966D03*
X140352D03*
Y523133D03*
X137006D03*
X157084Y580623D03*
X170470D03*
X150392D03*
X157084Y542823D03*
X170470D03*
X150392D03*
X140352Y560933D03*
X137006D03*
X140352Y580623D03*
X126966D03*
X140352Y542823D03*
X126966D03*
X137006Y598733D03*
X140352D03*
X213974Y22133D03*
X210628D03*
X213974Y4023D03*
X230706D03*
X224014D03*
X200588D03*
X180510D03*
X210628Y97733D03*
X213974D03*
Y79623D03*
X230706D03*
X224014D03*
X213974Y59933D03*
Y41823D03*
X224014D03*
X230706D03*
X210628Y59933D03*
X200588Y79623D03*
Y41823D03*
X180510Y79623D03*
Y41823D03*
X230706Y505023D03*
X224014D03*
X213974Y523133D03*
Y505023D03*
X210628Y523133D03*
X200588Y505023D03*
X180510D03*
X213974Y580623D03*
Y560933D03*
X210628D03*
X230706Y580623D03*
X224014D03*
X213974Y542823D03*
X230706D03*
X224014D03*
X200588Y580623D03*
X180510D03*
Y542823D03*
X200588D03*
X210628Y598733D03*
X213974D03*
X287596Y22133D03*
X284250D03*
X274210Y4023D03*
X287596D03*
X254132D03*
X244092D03*
X274210Y79623D03*
X287596D03*
X284250Y97733D03*
X287596D03*
Y41823D03*
X274210D03*
X284250Y59933D03*
X287596D03*
X244092Y79623D03*
X254132D03*
X244092Y41823D03*
X254132D03*
X274210Y505023D03*
X287596Y523133D03*
X284250D03*
X287596Y505023D03*
X244092D03*
X254132D03*
X274210Y580623D03*
X287596D03*
Y560933D03*
X284250D03*
X274210Y542823D03*
X287596D03*
X244092Y580623D03*
X254132D03*
Y542823D03*
X244092D03*
X287596Y598733D03*
X284250D03*
X304330Y4023D03*
X297636D03*
Y79623D03*
X304330D03*
X297636Y41823D03*
X304330D03*
Y505023D03*
X297636D03*
Y580623D03*
X304330D03*
Y542823D03*
X297636D03*
X464958Y22133D03*
X478344Y4023D03*
X461612D03*
Y79623D03*
X478344D03*
X464958Y97733D03*
X461612Y41823D03*
X464958Y59933D03*
X478344Y41823D03*
X461612Y505023D03*
X464958Y523133D03*
X478344Y505023D03*
Y580623D03*
X464958Y560933D03*
X461612Y580623D03*
X478344Y542823D03*
X461612D03*
X464958Y598733D03*
X538580Y22133D03*
X521848Y4023D03*
X535234D03*
X505116Y22133D03*
X508462Y4023D03*
X505116D03*
X491730D03*
X521848Y79623D03*
X538580Y97733D03*
X535234Y79623D03*
X521848Y41823D03*
X535234D03*
X538580Y59933D03*
X505116Y97733D03*
X508462Y79623D03*
X505116D03*
X491730D03*
X505116Y59933D03*
X508462Y41823D03*
X491730D03*
X505116D03*
X521848Y505023D03*
X538580Y523133D03*
X535234Y505023D03*
X505116D03*
X508462D03*
X505116Y523133D03*
X491730Y505023D03*
X535234Y580623D03*
X538580Y560933D03*
X521848Y580623D03*
Y542823D03*
X535234D03*
X505116Y560933D03*
X491730Y580623D03*
X505116D03*
X508462D03*
X491730Y542823D03*
X505116D03*
X508462D03*
X538580Y598733D03*
X505116D03*
X578738Y22133D03*
Y4023D03*
X582084D03*
X595470D03*
X565352D03*
X551966D03*
X582084Y79623D03*
X578738D03*
Y97733D03*
X595470Y79623D03*
X578738Y59933D03*
X582084Y41823D03*
X578738D03*
X595470D03*
X565352Y79623D03*
X551966D03*
X565352Y41823D03*
X551966D03*
X578738Y523133D03*
X595470Y505023D03*
X582084D03*
X578738D03*
X551966D03*
X565352D03*
X578738Y560933D03*
X595470Y580623D03*
X578738D03*
X582084D03*
X595470Y542823D03*
X578738D03*
X582084D03*
X565352Y580623D03*
X551966D03*
Y542823D03*
X565352D03*
X578738Y598733D03*
X786614Y22133D03*
X789960D03*
Y4023D03*
X776574D03*
X786614Y97733D03*
X789960D03*
Y79623D03*
X776574D03*
X789960Y41823D03*
Y59933D03*
X786614D03*
X776574Y41823D03*
X789960Y505023D03*
Y523133D03*
X786614D03*
X776574Y505023D03*
X786614Y560933D03*
X789960D03*
X776574Y580623D03*
X789960D03*
X776574Y542823D03*
X789960D03*
X786614Y598733D03*
X789960D03*
X820078Y4023D03*
X830118D03*
X850196D03*
X800000D03*
X806692D03*
X850196Y79623D03*
X830118D03*
X820078D03*
X850196Y41823D03*
X830118D03*
X820078D03*
X800000Y79623D03*
X806692D03*
X800000Y41823D03*
X806692D03*
X850196Y505023D03*
X830118D03*
X820078D03*
X800000D03*
X806692D03*
X850196Y580623D03*
X830118D03*
X820078D03*
X830118Y542823D03*
X820078D03*
X850196D03*
X806692Y580623D03*
X800000D03*
X806692Y542823D03*
X800000D03*
X903740Y4023D03*
X880314D03*
X893700D03*
X863582Y22133D03*
X860236D03*
X863582Y4023D03*
X873622D03*
X880314Y79623D03*
X893700D03*
X903740D03*
X880314Y41823D03*
X903740D03*
X893700D03*
X863582Y97733D03*
X860236D03*
X863582Y79623D03*
X873622D03*
X863582Y41823D03*
Y59933D03*
X860236D03*
X873622Y41823D03*
X893700Y505023D03*
X903740D03*
X880314D03*
X863582D03*
X873622D03*
X863582Y523133D03*
X860236D03*
X903740Y580623D03*
X880314D03*
X893700D03*
X903740Y542823D03*
X893700D03*
X880314D03*
X863582Y580623D03*
X860236Y560933D03*
X863582D03*
X873622Y580623D03*
Y542823D03*
X863582D03*
Y598733D03*
X860236D03*
X953938Y4023D03*
X947244D03*
X937204Y22133D03*
Y4023D03*
X933858Y22133D03*
X923818Y4023D03*
X947244Y79623D03*
X953938D03*
Y41823D03*
X947244D03*
X937204Y79623D03*
Y97733D03*
X923818Y79623D03*
X933858Y97733D03*
Y59933D03*
X937204Y41823D03*
Y59933D03*
X923818Y41823D03*
X953938Y505023D03*
X947244D03*
X937204Y523133D03*
Y505023D03*
X933858Y523133D03*
X923818Y505023D03*
X953938Y580623D03*
X947244D03*
Y542823D03*
X953938D03*
X923818Y580623D03*
X933858Y560933D03*
X937204Y580623D03*
Y560933D03*
Y542823D03*
X923818D03*
X937204Y598733D03*
X933858D03*
X1154724Y22133D03*
X1127952Y4023D03*
X1141338D03*
X1158070D03*
X1154724D03*
X1114566Y22133D03*
X1111220Y4023D03*
X1141338Y79623D03*
X1154724Y97733D03*
Y79623D03*
X1158070D03*
X1127952D03*
Y41823D03*
X1154724D03*
X1158070D03*
X1154724Y59933D03*
X1141338Y41823D03*
X1111220Y79623D03*
X1114566Y97733D03*
Y59933D03*
X1111220Y41823D03*
X1154724Y523133D03*
X1141338Y505023D03*
X1127952D03*
X1158070D03*
X1154724D03*
X1111220D03*
X1114566Y523133D03*
X1127952Y580623D03*
X1154724D03*
X1158070D03*
X1154724Y560933D03*
X1141338Y580623D03*
X1154724Y542823D03*
X1158070D03*
X1141338D03*
X1127952D03*
X1111220Y580623D03*
X1114566Y560933D03*
X1111220Y542823D03*
X1154724Y598733D03*
X1114566D03*
X1188188Y22133D03*
X1201574Y4023D03*
X1214960D03*
X1184842D03*
X1171456D03*
X1188188Y97733D03*
X1201574Y79623D03*
X1214960D03*
X1184842D03*
Y41823D03*
X1188188Y59933D03*
X1201574Y41823D03*
X1214960D03*
X1171456Y79623D03*
Y41823D03*
X1201574Y505023D03*
X1188188Y523133D03*
X1184842Y505023D03*
X1214960D03*
X1171456D03*
X1188188Y560933D03*
X1201574Y580623D03*
X1184842D03*
X1214960D03*
X1201574Y542823D03*
X1184842D03*
X1214960D03*
X1171456Y580623D03*
Y542823D03*
X1188188Y598733D03*
X1228346Y4023D03*
X1231692D03*
X1228346Y22133D03*
X1245078Y4023D03*
X1231692Y79623D03*
X1228346Y97733D03*
Y79623D03*
Y59933D03*
Y41823D03*
X1231692D03*
X1245078D03*
Y79623D03*
X1228346Y523133D03*
X1231692Y505023D03*
X1228346D03*
X1245078D03*
X1228346Y560933D03*
Y580623D03*
X1231692D03*
X1228346Y542823D03*
X1231692D03*
X1245078Y580623D03*
Y542823D03*
X1228346Y598733D03*
G54D66*
X18228Y178386D03*
X-1969D03*
X44291D03*
G54D51*
X1866923Y235400D03*
G54D47*
X-3937Y-43307D03*
X1956693D03*
X-13780Y598560D03*
X-3937Y646063D03*
X1956693D03*
G54D91*
X1737600Y204150D03*
X1734100D03*
X1743500Y456880D03*
X1747500D03*
X1756000D03*
X1760000D03*
X1768500D03*
X1772500D03*
X1781500D03*
X1785500D03*
X1810500D03*
X1819000D03*
X1823000D03*
X1832000D03*
X1836000D03*
X1794000D03*
X1798000D03*
X1806500D03*
G54D67*
X50580Y399920D03*
X71980Y403380D03*
Y396080D03*
Y392580D03*
X53380Y395520D03*
Y385820D03*
X53360Y382340D03*
X67980Y428480D03*
Y424980D03*
X56240Y423170D03*
Y419670D03*
X71980Y417680D03*
Y414180D03*
Y406880D03*
X1518356Y93976D03*
Y97976D03*
G54D58*
X1710125Y556866D03*
X1714125D03*
G54D50*
X1955506Y454297D03*
X1699600D03*
Y235400D03*
G54D57*
X1674000Y557250D03*
X1670000D03*
X1659500Y557150D03*
X1663000D03*
X1684000Y557650D03*
X1680000D03*
G54D54*
X133563Y183126D03*
Y419626D03*
X783171Y183126D03*
Y419626D03*
G54D53*
X1657750Y594000D03*
X1609250Y593000D03*
X1617750Y587000D03*
Y590500D03*
X1630350Y555200D03*
X1616750D03*
X1630350Y559200D03*
X1616750D03*
X1619750Y572500D03*
Y576500D03*
X1610850Y578620D03*
X1617750Y603000D03*
Y599500D03*
X1609250Y596500D03*
X1608650Y604700D03*
X1665930Y590500D03*
Y587000D03*
X1657750Y582000D03*
Y578500D03*
Y597500D03*
X1665750Y606000D03*
X1657750Y610000D03*
X1665750Y602500D03*
X1657750Y613500D03*
G54D100*
X1698029Y557141D03*
G54D55*
X1454685Y338189D03*
X1600355Y527165D03*
G54D85*
X1613069Y302692D03*
G54D77*
X224410Y301378D03*
X326772Y163582D03*
Y439173D03*
X500000Y163582D03*
Y439173D03*
X602362Y214764D03*
Y387992D03*
X874016Y301378D03*
X976378Y163582D03*
Y439173D03*
X1149606Y163582D03*
Y439173D03*
X1251969Y214764D03*
Y387992D03*
%LPD*%
G75*
G36*
G01X13800Y269464D02*
Y336848D01*
X16232Y339280D01*
X38761D01*
X39734Y338307D01*
Y275251D01*
X39717Y275212D01*
G03Y274082I1283J-565D01*
G01X39734Y274043D01*
Y265954D01*
X39717Y265915D01*
G03Y264785I1283J-565D01*
G01X39734Y264746D01*
Y199495D01*
X37239Y197000D01*
X13236D01*
X12100Y198136D01*
Y232736D01*
X9032Y235804D01*
Y264669D01*
X13796Y269435D01*
Y269460D01*
X13800Y269464D01*
G37*
G36*
G01X52969Y223191D02*
X51653Y224507D01*
Y258920D01*
X59873Y267140D01*
X72987D01*
X75079Y265048D01*
Y224661D01*
X73609Y223191D01*
X52969D01*
G37*
G36*
G01X312597Y83250D02*
G02X312266Y83874I0J400D01*
G03X310649Y86169I-1245J840D01*
G02X310150Y86557I-99J388D01*
G01Y88311D01*
X307834Y90627D01*
G02X308019Y91298I283J283D01*
G03X308893Y93352I-344J1359D01*
G02X309240Y93950I347J198D01*
G01X312689D01*
G02X313042Y93362I0J-400D01*
G03X315694I1326J-705D01*
G02X316047Y93950I353J188D01*
G01X319332D01*
G02X319696Y93383I0J-400D01*
G03X322426I1365J-626D01*
G02X322790Y93950I364J167D01*
G01X332718D01*
G02X333082Y93383I0J-400D01*
G03X335812I1365J-626D01*
G02X336176Y93950I364J167D01*
G01X339411D01*
G02X339775Y93383I0J-400D01*
G03X342505I1365J-626D01*
G02X342869Y93950I364J167D01*
G01X352686D01*
G02X353050Y93383I0J-400D01*
G03X355780I1365J-626D01*
G02X356144Y93950I364J167D01*
G01X361206D01*
G02X361540Y93329I0J-400D01*
G03X363904Y91490I1253J-829D01*
G02X364495I296J-269D01*
G03X366859Y93329I1111J1010D01*
G02X367193Y93950I334J221D01*
G01X368289D01*
X368850Y93389D01*
Y83411D01*
X368689Y83250D01*
X346062D01*
G02X345731Y83874I0J400D01*
G03X343241I-1245J840D01*
G02X342910Y83250I-331J-224D01*
G01X339441D01*
G02X339095Y83850I0J400D01*
G03X336491I-1302J749D01*
G02X336145Y83250I-346J-200D01*
G01X326055D01*
G02X325709Y83850I0J400D01*
G03X323105I-1302J749D01*
G02X322759Y83250I-346J-200D01*
G01X319168D01*
G02X318845Y83886I0J400D01*
G03X316583I-1131J828D01*
G02X316260Y83250I-323J-236D01*
G01X312597D01*
G37*
G36*
G01X312359Y509432D02*
G03X310649Y511569I-1338J682D01*
G02X310150Y511957I-99J388D01*
G01Y513711D01*
X307834Y516027D01*
G02X308019Y516698I283J283D01*
G03X308845Y518830I-344J1359D01*
G02X309179Y519450I334J220D01*
G01X312746D01*
G02X313087Y518841I0J-400D01*
G03X315649I1281J-784D01*
G02X315990Y519450I341J209D01*
G01X319382D01*
G02X319735Y518862I0J-400D01*
G03X322387I1326J-705D01*
G02X322740Y519450I353J188D01*
G01X332768D01*
G02X333121Y518862I0J-400D01*
G03X335773I1326J-705D01*
G02X336126Y519450I353J188D01*
G01X339461D01*
G02X339814Y518862I0J-400D01*
G03X342466I1326J-705D01*
G02X342819Y519450I353J188D01*
G01X352847D01*
G02X353200Y518862I0J-400D01*
G03X355852I1326J-705D01*
G02X356205Y519450I353J188D01*
G01X368289D01*
X368650Y519089D01*
Y509211D01*
X368289Y508850D01*
X365959D01*
G02X365603Y509432I0J400D01*
G03X363180Y511153I-1338J682D01*
G02X362603I-289J277D01*
G03X360180Y509432I-1085J-1039D01*
G02X359824Y508850I-356J-182D01*
G01X346180D01*
G02X345824Y509432I0J400D01*
G03X343148I-1338J682D01*
G02X342792Y508850I-356J-182D01*
G01X339541D01*
G02X339174Y509407I1J400D01*
G03X336412I-1381J592D01*
G02X336045Y508850I-368J-157D01*
G01X326155D01*
G02X325788Y509407I1J400D01*
G03X323026I-1381J592D01*
G02X322659Y508850I-368J-157D01*
G01X319295D01*
G02X318944Y509442I0J400D01*
G03X316484I-1230J672D01*
G02X316133Y508850I-351J-192D01*
G01X312715D01*
G02X312359Y509432I0J400D01*
G37*
G36*
G01X395784Y7550D02*
Y7574D01*
X394486D01*
X393550Y8511D01*
Y10037D01*
G02X394104Y10406I400J0D01*
G03X395874Y12707I579J1386D01*
G02X396191Y13350I317J243D01*
G01X404289D01*
X406889Y10750D01*
X408689D01*
X409150Y10289D01*
Y8411D01*
X408289Y7550D01*
X405824D01*
Y7574D01*
X405390D01*
Y7884D01*
X405482Y7943D01*
G03X403962I-760J1178D01*
G01X404054Y7884D01*
Y7574D01*
X403620D01*
Y7550D01*
X402478D01*
Y7574D01*
X402044D01*
Y7884D01*
X402136Y7943D01*
G03X400616I-760J1178D01*
G01X400708Y7884D01*
Y7574D01*
X400274D01*
Y7550D01*
X395784D01*
G37*
G36*
G01Y83150D02*
Y83174D01*
X394787D01*
X393850Y84111D01*
Y85540D01*
G02X394341Y85929I400J0D01*
G03X394712Y88894I340J1463D01*
G02X394437Y89576I8J400D01*
G01X398811Y93950D01*
X406339D01*
G02X406703Y93383I0J-400D01*
G03X409433I1365J-626D01*
G02X409797Y93950I364J167D01*
G01X413032D01*
G02X413396Y93383I0J-400D01*
G03X416126I1365J-626D01*
G02X416490Y93950I364J167D01*
G01X419725D01*
G02X420089Y93383I0J-400D01*
G03X422819I1365J-626D01*
G02X423183Y93950I364J167D01*
G01X442389D01*
X442950Y93389D01*
Y92411D01*
X441950Y91411D01*
Y88589D01*
X442550Y87989D01*
Y86811D01*
X440362Y84623D01*
G02X439681Y84866I-283J283D01*
G03X437260Y83532I-1494J-152D01*
G01X437337Y83472D01*
Y83174D01*
X437086D01*
Y83150D01*
X435942D01*
Y83174D01*
X433738D01*
Y83150D01*
X429248D01*
Y83174D01*
X427046D01*
Y83150D01*
X415864D01*
Y83174D01*
X413660D01*
Y83150D01*
X412791D01*
G02X412485Y83808I0J400D01*
G03X410345I-1070J906D01*
G02X410039Y83150I-306J-258D01*
G01X405824D01*
Y83575D01*
X405871Y83631D01*
G03X403573I-1149J968D01*
G01X403620Y83575D01*
Y83150D01*
X402478D01*
Y83174D01*
X400274D01*
Y83150D01*
X395784D01*
G37*
G36*
G01Y45350D02*
Y45374D01*
X394186D01*
X393650Y45911D01*
Y47798D01*
G02X394183Y48175I400J0D01*
G03X395930Y50428I499J1417D01*
G02X396263Y51050I333J222D01*
G01X404389D01*
X406889Y48550D01*
X408789D01*
X409250Y48089D01*
Y46111D01*
X408489Y45350D01*
X405824D01*
Y45374D01*
X405389D01*
Y45684D01*
X405481Y45743D01*
G03X403965I-758J1179D01*
G01X404057Y45684D01*
Y45374D01*
X403620D01*
Y45350D01*
X402478D01*
Y45374D01*
X402043D01*
Y45684D01*
X402135Y45743D01*
G03X400619I-758J1179D01*
G01X400711Y45684D01*
Y45374D01*
X400274D01*
Y45350D01*
X395784D01*
G37*
G36*
G01Y508550D02*
Y508574D01*
X394686D01*
X394050Y509211D01*
Y510904D01*
G02X394499Y511301I400J0D01*
G03X394301Y514245I183J1491D01*
G01X394276Y514238D01*
X394050D01*
Y514689D01*
X396350Y516989D01*
Y518889D01*
X397011Y519550D01*
X406446D01*
G02X406787Y518941I0J-400D01*
G03X409349I1281J-784D01*
G02X409690Y519550I341J209D01*
G01X413139D01*
G02X413480Y518941I0J-400D01*
G03X416042I1281J-784D01*
G02X416383Y519550I341J209D01*
G01X419832D01*
G02X420173Y518941I0J-400D01*
G03X422735I1281J-784D01*
G02X423076Y519550I341J209D01*
G01X445389D01*
X446350Y518589D01*
Y516936D01*
G02X445725Y516606I-400J1D01*
G03X444935Y513863I-845J-1242D01*
G02X445350Y513463I15J-400D01*
G01Y512015D01*
G02X444935Y511615I-400J0D01*
G03X443953Y508932I-55J-1501D01*
G01X444030Y508872D01*
Y508574D01*
X443778D01*
Y508550D01*
X439288D01*
Y508574D01*
X439037D01*
Y508872D01*
X439114Y508932D01*
G03X437260I-927J1182D01*
G01X437337Y508872D01*
Y508574D01*
X437086D01*
Y508550D01*
X435942D01*
Y508574D01*
X433738D01*
Y508550D01*
X429248D01*
Y508574D01*
X427046D01*
Y508550D01*
X415864D01*
Y508574D01*
X413660D01*
Y508550D01*
X412791D01*
G02X412485Y509208I0J400D01*
G03X410345I-1070J906D01*
G02X410039Y508550I-306J-258D01*
G01X405824D01*
Y508975D01*
X405871Y509031D01*
G03X403573I-1149J968D01*
G01X403620Y508975D01*
Y508550D01*
X402478D01*
Y508574D01*
X400274D01*
Y508550D01*
X395784D01*
G37*
G36*
G01X394411Y584250D02*
X393750Y584911D01*
Y586566D01*
G02X394262Y586950I400J0D01*
G03X396183Y588351I420J1442D01*
G02X396583Y588740I400J-11D01*
G01X405535D01*
X407025Y587250D01*
X408689D01*
X409050Y586889D01*
Y584911D01*
X408389Y584250D01*
X406171D01*
G02X405850Y584888I0J400D01*
G03X403596I-1127J834D01*
G02X403275Y584250I-321J-238D01*
G01X402825D01*
G02X402504Y584888I0J400D01*
G03X400250I-1127J834D01*
G02X399929Y584250I-321J-238D01*
G01X394411D01*
G37*
G36*
G01X395784Y546350D02*
Y546374D01*
X394286D01*
X393850Y546811D01*
Y548740D01*
G02X394341Y549129I400J0D01*
G03X396180Y550480I341J1463D01*
G02X396579Y550850I399J-30D01*
G01X405589D01*
X406889Y549550D01*
X408689D01*
X409250Y548989D01*
Y547311D01*
X408289Y546350D01*
X405824D01*
Y546374D01*
X405389D01*
Y546684D01*
X405481Y546743D01*
G03X403965I-758J1179D01*
G01X404057Y546684D01*
Y546374D01*
X403620D01*
Y546350D01*
X402478D01*
Y546374D01*
X402042D01*
Y546684D01*
X402134Y546743D01*
G03X400618I-758J1179D01*
G01X400710Y546684D01*
Y546374D01*
X400274D01*
Y546350D01*
X395784D01*
G37*
G36*
G01X689914Y25500D02*
X688414Y27000D01*
X681414D01*
X678000Y30414D01*
Y35414D01*
X676639Y36775D01*
X676636Y36853D01*
G03X675291Y38198I-1401J-56D01*
G01X675213Y38201D01*
X673500Y39914D01*
Y47086D01*
X674914Y48500D01*
X682414D01*
X685414Y51500D01*
X687586D01*
X689000Y50086D01*
Y43586D01*
X690586Y42000D01*
X701086D01*
X701500Y41586D01*
Y38586D01*
X702500Y37586D01*
Y32914D01*
X701500Y31914D01*
Y26414D01*
X700586Y25500D01*
X689914D01*
G37*
G36*
G01X678086Y509900D02*
X675314D01*
X675300Y509914D01*
Y517914D01*
X674114Y519100D01*
X672414D01*
X672000Y519514D01*
Y526086D01*
X674514Y528600D01*
X699586D01*
X702000Y526186D01*
Y520414D01*
X701400Y519814D01*
Y511014D01*
X701186Y510800D01*
X678986D01*
X678086Y509900D01*
G37*
G36*
G01X962205Y83250D02*
G02X961874Y83874I0J400D01*
G03X960330Y86186I-1245J840D01*
G02X959850Y86578I-80J392D01*
G01Y88111D01*
X957354Y90607D01*
G02X957558Y91282I283J283D01*
G03X958398Y93507I-275J1375D01*
G02X958716Y94150I318J243D01*
G01X962419D01*
G02X962747Y93520I1J-400D01*
G03X965205I1229J-863D01*
G02X965533Y94150I327J230D01*
G01X969047D01*
G02X969388Y93541I0J-400D01*
G03X971950I1281J-784D01*
G02X972291Y94150I341J209D01*
G01X982433D01*
G02X982774Y93541I0J-400D01*
G03X985336I1281J-784D01*
G02X985677Y94150I341J209D01*
G01X989126D01*
G02X989467Y93541I0J-400D01*
G03X992029I1281J-784D01*
G02X992370Y94150I341J209D01*
G01X1002401D01*
G02X1002742Y93541I0J-400D01*
G03X1005304I1281J-784D01*
G02X1005645Y94150I341J209D01*
G01X1010967D01*
G02X1011268Y93487I0J-400D01*
G03X1013512Y91490I1131J-988D01*
G02X1014103I296J-269D01*
G03X1016347Y93487I1113J1009D01*
G02X1016648Y94150I301J263D01*
G01X1017689D01*
X1018550Y93289D01*
Y84411D01*
X1017389Y83250D01*
X995670D01*
G02X995339Y83874I0J400D01*
G03X992849I-1245J840D01*
G02X992518Y83250I-331J-224D01*
G01X989049D01*
G02X988703Y83850I0J400D01*
G03X986099I-1302J749D01*
G02X985753Y83250I-346J-200D01*
G01X975663D01*
G02X975317Y83850I0J400D01*
G03X972713I-1302J749D01*
G02X972367Y83250I-346J-200D01*
G01X968776D01*
G02X968453Y83886I0J400D01*
G03X966191I-1131J828D01*
G02X965868Y83250I-323J-236D01*
G01X962205D01*
G37*
G36*
G01X961730Y508450D02*
Y508574D01*
X961479D01*
Y508872D01*
X961556Y508932D01*
G03X960251Y511568I-927J1182D01*
G02X959750Y511955I-101J387D01*
G01Y513400D01*
G03X959530Y513930I-750J-1D01*
G01X957435Y516026D01*
G02X957621Y516696I283J282D01*
G03X958072Y519216I-338J1361D01*
G01X957984Y519276D01*
Y519582D01*
X958384D01*
Y519650D01*
X962874D01*
Y519582D01*
X963107D01*
Y519286D01*
X963033Y519226D01*
G03X964919I943J-1169D01*
G01X964845Y519286D01*
Y519582D01*
X965078D01*
Y519650D01*
X969568D01*
Y519181D01*
X969520Y519125D01*
G03X971818I1149J-968D01*
G01X971770Y519181D01*
Y519650D01*
X972914D01*
Y519582D01*
X975116D01*
Y519650D01*
X979606D01*
Y519582D01*
X981810D01*
Y519650D01*
X982954D01*
Y519181D01*
X982906Y519125D01*
G03X985204I1149J-968D01*
G01X985156Y519181D01*
Y519650D01*
X989646D01*
Y519181D01*
X989599Y519125D01*
G03X991897I1149J-968D01*
G01X991850Y519181D01*
Y519650D01*
X992992D01*
Y519582D01*
X995196D01*
Y519650D01*
X999686D01*
Y519582D01*
X1001888D01*
Y519650D01*
X1003032D01*
Y519180D01*
X1002985Y519124D01*
G03X1005282Y519126I1149J-967D01*
G01X1005234Y519182D01*
Y519650D01*
X1009724D01*
Y519582D01*
X1011928D01*
Y519650D01*
X1013072D01*
Y519582D01*
X1015274D01*
Y519650D01*
X1017489D01*
X1018550Y518589D01*
Y510011D01*
X1016989Y508450D01*
X1015274D01*
Y508593D01*
G02X1015076Y509214I122J381D01*
G03X1012788Y511153I-1203J900D01*
G02X1012211I-288J277D01*
G03X1009923Y509214I-1085J-1039D01*
G02X1009724Y508593I-320J-240D01*
G01Y508450D01*
X1005234D01*
Y508574D01*
X1003032D01*
Y508450D01*
X998542D01*
Y508574D01*
X996340D01*
Y508450D01*
X995196D01*
Y508574D01*
X994944D01*
Y508872D01*
X995021Y508932D01*
G03X993167I-927J1182D01*
G01X993244Y508872D01*
Y508574D01*
X992992D01*
Y508450D01*
X988502D01*
Y508975D01*
X988550Y509031D01*
G03X986252I-1149J968D01*
G01X986300Y508975D01*
Y508450D01*
X985156D01*
Y508574D01*
X982954D01*
Y508450D01*
X978464D01*
Y508574D01*
X976260D01*
Y508450D01*
X975116D01*
Y508975D01*
X975164Y509031D01*
G03X972866I-1149J968D01*
G01X972914Y508975D01*
Y508450D01*
X968606D01*
G02X968321Y509131I0J400D01*
G03X966323I-999J983D01*
G02X966038Y508450I-285J-281D01*
G01X961730D01*
G37*
G36*
G01X1043811Y7850D02*
X1043150Y8511D01*
Y10040D01*
G02X1043706Y10408I400J0D01*
G03X1045417Y12785I584J1384D01*
G02X1045716Y13450I300J265D01*
G01X1053889D01*
X1056589Y10750D01*
X1058289D01*
X1058850Y10189D01*
Y8311D01*
X1058389Y7850D01*
X1055908D01*
G02X1055558Y8444I0J400D01*
G03X1053104I-1227J678D01*
G02X1052754Y7850I-350J-194D01*
G01X1052562D01*
G02X1052212Y8444I0J400D01*
G03X1049758I-1227J678D01*
G02X1049408Y7850I-350J-194D01*
G01X1043811D01*
G37*
G36*
G01X1045392Y83150D02*
Y83174D01*
X1044686D01*
X1043550Y84311D01*
Y85521D01*
G02X1044021Y85914I400J0D01*
G03X1043813Y88816I269J1478D01*
G01X1043783Y88806D01*
X1043550D01*
Y89189D01*
X1045950Y91589D01*
Y93289D01*
X1046811Y94150D01*
X1056054D01*
G02X1056395Y93541I0J-400D01*
G03X1058957I1281J-784D01*
G02X1059298Y94150I341J209D01*
G01X1062747D01*
G02X1063088Y93541I0J-400D01*
G03X1065650I1281J-784D01*
G02X1065991Y94150I341J209D01*
G01X1069440D01*
G02X1069781Y93541I0J-400D01*
G03X1072343I1281J-784D01*
G02X1072684Y94150I341J209D01*
G01X1094989D01*
X1095950Y93189D01*
Y91542D01*
G02X1095327Y91210I-400J0D01*
G03Y88718I-839J-1246D01*
G02X1095950Y88386I223J-332D01*
G01Y86292D01*
G02X1095327Y85960I-400J0D01*
G03X1093561Y83532I-840J-1245D01*
G01X1093638Y83472D01*
Y83174D01*
X1093386D01*
Y83150D01*
X1088896D01*
Y83174D01*
X1088645D01*
Y83472D01*
X1088722Y83532D01*
G03X1086868I-927J1182D01*
G01X1086945Y83472D01*
Y83174D01*
X1086694D01*
Y83150D01*
X1085550D01*
Y83174D01*
X1083346D01*
Y83150D01*
X1078856D01*
Y83174D01*
X1076654D01*
Y83150D01*
X1065472D01*
Y83174D01*
X1063268D01*
Y83150D01*
X1062399D01*
G02X1062093Y83808I0J400D01*
G03X1059953I-1070J906D01*
G02X1059647Y83150I-306J-258D01*
G01X1055432D01*
Y83575D01*
X1055479Y83631D01*
G03X1053181I-1149J968D01*
G01X1053228Y83575D01*
Y83150D01*
X1052086D01*
Y83174D01*
X1049882D01*
Y83150D01*
X1045392D01*
G37*
G36*
G01X1043911Y45450D02*
X1043150Y46211D01*
Y47840D01*
G02X1043706Y48208I400J0D01*
G03X1045254Y50743I583J1384D01*
G02X1045511Y51450I257J307D01*
G01X1053689D01*
X1056589Y48550D01*
X1058289D01*
X1058950Y47889D01*
Y46311D01*
X1058089Y45450D01*
X1055779D01*
G02X1055458Y46088I0J400D01*
G03X1053204I-1127J834D01*
G02X1052883Y45450I-321J-238D01*
G01X1052433D01*
G02X1052112Y46088I0J400D01*
G03X1049858I-1127J834D01*
G02X1049537Y45450I-321J-238D01*
G01X1043911D01*
G37*
G36*
G01X1045392Y508550D02*
Y508574D01*
X1044186D01*
X1043450Y509311D01*
Y510942D01*
G02X1043943Y511331I400J0D01*
G03X1044314Y514294I347J1461D01*
G02X1044038Y514977I6J400D01*
G01X1048643Y519582D01*
X1048738D01*
Y519650D01*
X1053228D01*
Y519582D01*
X1055432D01*
Y519650D01*
X1056576D01*
Y519182D01*
X1056528Y519126D01*
G03X1058825Y519124I1148J-969D01*
G01X1058778Y519180D01*
Y519650D01*
X1063268D01*
Y519182D01*
X1063221Y519126D01*
G03X1065518Y519124I1148J-969D01*
G01X1065472Y519180D01*
Y519650D01*
X1069962D01*
Y519182D01*
X1069914Y519126D01*
G03X1072211Y519124I1148J-969D01*
G01X1072164Y519180D01*
Y519650D01*
X1073308D01*
Y519582D01*
X1075510D01*
Y519650D01*
X1080000D01*
Y519582D01*
X1082204D01*
Y519650D01*
X1086694D01*
Y519582D01*
X1088896D01*
Y519650D01*
X1093386D01*
Y519582D01*
X1095058D01*
X1095950Y518689D01*
Y516942D01*
G02X1095327Y516610I-400J0D01*
G03X1094616Y513867I-839J-1246D01*
G02X1095050Y513469I34J-398D01*
G01Y512009D01*
G02X1094616Y511611I-400J0D01*
G03X1093561Y508932I-128J-1497D01*
G01X1093638Y508872D01*
Y508574D01*
X1093386D01*
Y508550D01*
X1088896D01*
Y508574D01*
X1088645D01*
Y508872D01*
X1088722Y508932D01*
G03X1086868I-927J1182D01*
G01X1086945Y508872D01*
Y508574D01*
X1086694D01*
Y508550D01*
X1085550D01*
Y508574D01*
X1083346D01*
Y508550D01*
X1078856D01*
Y508574D01*
X1076654D01*
Y508550D01*
X1065472D01*
Y508574D01*
X1063268D01*
Y508550D01*
X1062399D01*
G02X1062093Y509208I0J400D01*
G03X1059953I-1070J906D01*
G02X1059647Y508550I-306J-258D01*
G01X1055432D01*
Y508975D01*
X1055479Y509031D01*
G03X1053181I-1149J968D01*
G01X1053228Y508975D01*
Y508550D01*
X1052086D01*
Y508574D01*
X1049882D01*
Y508550D01*
X1045392D01*
G37*
G36*
G01Y584150D02*
Y584174D01*
X1043886D01*
X1043150Y584911D01*
Y586640D01*
G02X1043706Y587008I400J0D01*
G03X1045787Y588517I584J1384D01*
G02X1046185Y588950I399J33D01*
G01X1055089D01*
X1056689Y587350D01*
X1058389D01*
X1058650Y587089D01*
Y585211D01*
X1057589Y584150D01*
X1055432D01*
Y584174D01*
X1054997D01*
Y584484D01*
X1055089Y584543D01*
G03X1053573I-758J1179D01*
G01X1053665Y584484D01*
Y584174D01*
X1053228D01*
Y584150D01*
X1052086D01*
Y584174D01*
X1051651D01*
Y584484D01*
X1051743Y584543D01*
G03X1050227I-758J1179D01*
G01X1050319Y584484D01*
Y584174D01*
X1049882D01*
Y584150D01*
X1045392D01*
G37*
G36*
G01X1044311Y546550D02*
X1043350Y547511D01*
Y548768D01*
G02X1043864Y549152I400J0D01*
G03X1045787Y550717I426J1440D01*
G02X1046185Y551150I399J33D01*
G01X1054989D01*
X1056589Y549550D01*
X1058289D01*
X1058750Y549089D01*
Y547511D01*
X1057789Y546550D01*
X1055848D01*
G02X1055512Y547166I0J400D01*
G03X1053150I-1181J756D01*
G02X1052814Y546550I-336J-216D01*
G01X1052501D01*
G02X1052165Y547166I0J400D01*
G03X1049803I-1181J756D01*
G02X1049467Y546550I-336J-216D01*
G01X1044311D01*
G37*
G36*
G01X1339914Y85000D02*
X1339500Y85414D01*
Y87086D01*
X1339914Y87500D01*
X1340914D01*
X1342500Y89086D01*
Y91914D01*
X1341414Y93000D01*
X1332149D01*
X1329649Y91000D01*
X1329236D01*
Y91302D01*
X1329319Y91362D01*
G03X1327390Y91644I-819J1138D01*
G02X1327073Y91000I-317J-244D01*
G01X1325000D01*
Y98401D01*
G02X1325191Y98601I200J0D01*
G03X1326527Y100026I-66J1400D01*
G01X1326525Y100111D01*
X1329914Y103500D01*
X1339586D01*
X1341086Y102000D01*
X1359086D01*
X1362500Y98586D01*
Y93414D01*
X1362000Y92914D01*
Y86414D01*
X1361086Y85500D01*
X1360000D01*
Y87914D01*
X1358914Y89000D01*
X1351086D01*
X1348586Y86500D01*
X1343586D01*
X1342086Y85000D01*
X1339914D01*
G37*
G36*
G01X1395890Y233538D02*
Y236480D01*
G02X1396537Y236795I400J0D01*
G03X1398073Y236670I863J1105D01*
G02X1398664Y236309I191J-351D01*
G03X1399023Y235337I1402J-35D01*
G02X1399003Y234783I-298J-267D01*
G03X1398576Y233751I975J-1008D01*
G02X1398004Y233383I-400J-7D01*
G03X1396537Y233223I-604J-1265D01*
G02X1395890Y233538I-247J315D01*
G37*
G36*
G01X1443529Y267984D02*
G03X1442983Y268529I-1225J-682D01*
G02Y269228I195J349D01*
G03X1442985Y271679I-680J1226D01*
G02Y272378I195J350D01*
G03X1443529Y272922I-681J1225D01*
G02X1444229I350J-194D01*
G03X1446135Y274828I1225J681D01*
G02Y275528I194J350D01*
G03X1446679Y276071I-680J1226D01*
G02X1447378I349J-194D01*
G03X1449285Y277978I1225J682D01*
G02Y278677I194J350D01*
G03X1449828Y279221I-683J1224D01*
G02X1450528I350J-194D01*
G03X1452434Y281128I1225J681D01*
G02Y281827I194J349D01*
G03X1452978Y282370I-680J1226D01*
G02X1453677I349J-195D01*
G03X1455583Y284277I1225J682D01*
G02Y284977I194J350D01*
G03X1456127Y285521I-681J1225D01*
G02X1456827I350J-194D01*
G03X1459277I1225J681D01*
G02X1459977I350J-194D01*
G03X1460521Y284977I1225J681D01*
G02Y284277I-194J-350D01*
G03Y281827I681J-1225D01*
G02Y281127I-194J-350D01*
G03X1459977Y280583I681J-1225D01*
G02X1459277I-350J194D01*
G03X1457370Y278677I-1225J-681D01*
G02Y277978I-194J-350D01*
G03X1456827Y277434I683J-1224D01*
G02X1456127I-350J194D01*
G03X1454221Y275528I-1225J-681D01*
G02Y274828I-194J-350D01*
G03X1453677Y274285I680J-1226D01*
G02X1452978I-350J194D01*
G03X1451071Y272378I-1225J-682D01*
G02Y271679I-194J-350D01*
G03X1450528Y271135I683J-1224D01*
G02X1449828I-350J194D01*
G03X1447922Y269229I-1225J-681D01*
G02Y268529I-194J-350D01*
G03X1447378Y267986I680J-1226D01*
G02X1446679I-350J194D01*
G03X1444228Y267984I-1225J-682D01*
G02X1443529I-350J194D01*
G37*
G36*
G01X1409534Y303032D02*
G03X1407682Y303157I-997J-986D01*
G02X1407038Y303474I-244J317D01*
G01Y306202D01*
G02X1407682Y306519I400J0D01*
G03X1409534Y306644I855J1111D01*
G02X1410218Y306363I284J-281D01*
G01Y303313D01*
G02X1409534Y303032I-400J0D01*
G37*
G36*
G01X1459277Y305779D02*
G03X1458734Y306323I-1226J-680D01*
G02Y307022I194J350D01*
G03X1458733Y309472I-682J1225D01*
G02Y310172I194J350D01*
G03X1459277Y310716I-681J1225D01*
G02X1459977I350J-194D01*
G03X1462427Y310715I1225J681D01*
G02X1463126I349J-194D01*
G03X1463669Y310172I1225J682D01*
G02Y309473I-194J-350D01*
G03Y307022I681J-1226D01*
G02Y306323I-195J-350D01*
G03X1463126Y305780I682J-1225D01*
G02X1462427I-350J194D01*
G03X1459977Y305779I-1225J-682D01*
G02X1459277I-350J194D01*
G37*
G36*
G01X1611816Y113022D02*
G03X1611272Y113566I-1225J-681D01*
G02Y114266I194J350D01*
G03X1611273Y116716I-681J1225D01*
G02Y117415I194J349D01*
G03X1611816Y117959I-683J1224D01*
G02X1612516I350J-194D01*
G03X1614966I1225J681D01*
G02X1615665I350J-195D01*
G03X1616223Y117408I1225J682D01*
G02X1616214Y116699I-190J-352D01*
G03X1616155Y114230I634J-1250D01*
G02X1616164Y113540I-198J-348D01*
G03X1615665Y113023I726J-1200D01*
G02X1614966I-349J194D01*
G03X1612516Y113022I-1225J-682D01*
G02X1611816I-350J194D01*
G37*
G36*
G01X1655910Y122471D02*
G03X1655367Y123015I-1226J-680D01*
G02Y123714I194J350D01*
G03X1653460Y125621I-681J1226D01*
G02X1652761I-349J194D01*
G03X1652217Y126164I-1224J-683D01*
G02Y126864I194J350D01*
G03Y129314I-681J1225D01*
G02Y130014I194J350D01*
G03X1652761Y130557I-680J1226D01*
G02X1653460I350J-194D01*
G03X1655910Y130558I1225J682D01*
G02X1656610I350J-194D01*
G03X1659060I1225J681D01*
G02X1659760I350J-194D01*
G03X1660304Y130014I1225J681D01*
G02Y129314I-194J-350D01*
G03Y126864I681J-1225D01*
G02Y126164I-194J-350D01*
G03X1660303Y123714I681J-1225D01*
G02Y123015I-194J-350D01*
G03X1659760Y122471I683J-1224D01*
G02X1659060I-350J194D01*
G03X1656610I-1225J-681D01*
G02X1655910I-350J194D01*
G37*
%LPC*%
G75*
G36*
G01X58175Y255329D02*
G02X56785Y255306I-675J-1229D01*
G03X56753Y256011I-204J344D01*
G02X58183Y256034I692J1445D01*
G03X58175Y255329I184J-355D01*
G37*
G36*
G01X364129Y86483D02*
G03X363540I-295J-271D01*
G02Y88517I-1105J1017D01*
G03X364129I294J271D01*
G02Y86483I1105J-1017D01*
G37*
G36*
G01X362698Y516269D02*
G03X363249Y516258I281J284D01*
G02X363209Y514083I1016J-1107D01*
G03X362658Y514094I-281J-284D01*
G02X362698Y516269I-1016J1107D01*
G37*
G36*
G01X1013737Y86483D02*
G03X1013148I-295J-271D01*
G02Y88517I-1105J1017D01*
G03X1013737I295J271D01*
G02Y86483I1105J-1017D01*
G37*
G36*
G01X1012306Y516269D02*
G03X1012857Y516258I281J284D01*
G02X1012817Y514083I1016J-1107D01*
G03X1012266Y514094I-281J-284D01*
G02X1012306Y516269I-1016J1107D01*
G37*
G54D64*
X327754Y87392D03*
X324407Y89964D03*
X334447Y87392D03*
X331100Y89964D03*
X354415Y87392D03*
X351179Y89964D03*
X347833Y87392D03*
X344486Y89964D03*
X327754Y512792D03*
X324407Y515364D03*
X334447Y512792D03*
X331100Y515364D03*
X354307Y512792D03*
X351179Y515364D03*
X347833Y512792D03*
X344486Y515364D03*
X404722Y89964D03*
X401375Y87392D03*
X398029Y89964D03*
X414761Y87392D03*
X431494Y89964D03*
X428147Y87392D03*
X434840D03*
X424801Y89964D03*
X438187D03*
X404722Y515364D03*
X401375Y512792D03*
X398029Y515364D03*
X414761Y512792D03*
X431494Y515364D03*
X428147Y512792D03*
X434840D03*
X424801Y515364D03*
X438187D03*
X974015Y89964D03*
X977362Y87392D03*
X984055D03*
X980708Y89964D03*
X1004023Y87392D03*
X1000787Y89964D03*
X997441Y87392D03*
X994094Y89964D03*
X974015Y515364D03*
X977362Y512792D03*
X984055D03*
X980708Y515364D03*
X1003915Y512792D03*
X1000787Y515364D03*
X997441Y512792D03*
X994094Y515364D03*
X1054330Y89964D03*
X1050983Y87392D03*
X1081102Y89964D03*
X1047637D03*
X1077755Y87392D03*
X1064369D03*
X1084448D03*
X1074409Y89964D03*
X1087795D03*
X1054330Y515364D03*
X1050983Y512792D03*
X1081102Y515364D03*
X1047637D03*
X1077755Y512792D03*
X1064369D03*
X1084448D03*
X1074409Y515364D03*
X1087795D03*
G54D74*
X19800Y257900D03*
G54D49*
X19904Y254162D03*
X37000Y265350D03*
X33490Y267900D03*
X37000Y275000D03*
X689500Y37900D03*
X685000Y46650D03*
X685100Y43000D03*
X690500Y523300D03*
X675500Y521900D03*
X1345257Y100000D03*
X1353500Y96959D03*
X1348615Y96239D03*
%LPD*%
G75*
G54D10*
X-17936Y-49379D03*
Y-53779D03*
Y-44979D03*
Y-40579D03*
X-18079Y-35764D03*
Y-58764D03*
X-14186Y196989D03*
Y199989D03*
X-14839Y445588D03*
X-14753Y448601D03*
X-17179Y643156D03*
X-17194Y638753D03*
X-17179Y647556D03*
Y660756D03*
Y651956D03*
Y656356D03*
X-13636Y-40479D03*
Y-44879D03*
Y-53679D03*
X-9079Y-50164D03*
X-4679D03*
X-279D03*
X-9079Y-54264D03*
X-4679D03*
X-279D03*
X22964Y-40379D03*
Y-44779D03*
Y-53579D03*
Y-49179D03*
X18964Y-53579D03*
Y-49179D03*
X13964Y-53579D03*
Y-49179D03*
X8964Y-40379D03*
Y-44779D03*
Y-53579D03*
Y-49179D03*
X3964Y-40379D03*
Y-44779D03*
Y-53579D03*
Y-49179D03*
X25921Y-35764D03*
X30321D03*
X43521D03*
X39121D03*
X34721D03*
X8321D03*
X12721D03*
X21521D03*
X17121D03*
X-13679D03*
X-9279D03*
X3921D03*
X-4879D03*
X-479D03*
X17121Y-58764D03*
X21521D03*
X12721D03*
X8321D03*
X34721D03*
X39121D03*
X43521D03*
X30321D03*
X25921D03*
X-479D03*
X-13679D03*
X-4879D03*
X3921D03*
X-13636Y-49279D03*
X-9279Y-58764D03*
X875Y211336D03*
X6074Y211293D03*
X3474Y211263D03*
X875Y208352D03*
X36200Y208600D03*
X33200D03*
X20700D03*
X17700Y211600D03*
X20700D03*
X17700Y208600D03*
X23700Y211600D03*
Y208600D03*
X33200Y211600D03*
X30200D03*
Y208600D03*
X36200Y211600D03*
X6074Y208321D03*
X3474Y208263D03*
X5500Y218500D03*
X-5300Y200191D03*
X-7900D03*
X-2700Y200202D03*
X-11586Y196989D03*
Y199989D03*
X-2600Y232300D03*
X-5246Y232351D03*
X-7846D03*
X20500Y221000D03*
Y224000D03*
X17500Y221000D03*
Y224000D03*
X23500D03*
Y221000D03*
X33300Y224000D03*
Y221000D03*
X30300D03*
Y224000D03*
X36300D03*
Y221000D03*
X-14129Y235221D03*
X-11484Y235215D03*
Y232215D03*
X-14084D03*
X2678Y221018D03*
X5277Y221110D03*
X5173Y224042D03*
X2574Y223963D03*
X-26Y223982D03*
X-11652Y445530D03*
Y448530D03*
X22421Y647556D03*
X26821D03*
X31221D03*
X18021D03*
Y643156D03*
X31221D03*
X26821D03*
X22421D03*
X18006Y638753D03*
X9221Y647556D03*
X13621D03*
Y643156D03*
X9221D03*
X4821D03*
Y647556D03*
X22406Y638753D03*
X26806D03*
X31206D03*
X-12794D03*
X-12779Y647556D03*
Y643156D03*
X40006Y638753D03*
X44406D03*
X35606D03*
X35621Y647556D03*
Y643156D03*
X-9599Y610630D03*
X-3301Y619643D03*
Y601615D03*
X4549Y620682D03*
X4548Y600577D03*
X13801Y624130D03*
Y597130D03*
X23360Y620172D03*
X23352Y601079D03*
X27301Y610630D03*
X18021Y660756D03*
X35621Y656356D03*
X26821Y660756D03*
X18021Y651956D03*
X31221D03*
X22421Y660756D03*
X26821Y651956D03*
X22421D03*
X4821D03*
X13621D03*
X9221D03*
X-8379Y660756D03*
X4821Y656356D03*
X9221D03*
X13621D03*
X-3979D03*
X421D03*
X13621Y660756D03*
X-3979D03*
X421D03*
X4821D03*
X-12779Y651956D03*
X22421Y656356D03*
X26821D03*
X31221D03*
X18021D03*
X-8379D03*
X-12779D03*
X31221Y660756D03*
X35621Y651956D03*
Y660756D03*
X44421D03*
X40021D03*
X-12779D03*
X9221D03*
X107921Y-58764D03*
X102921D03*
X97921D03*
X92921D03*
X87921D03*
X82921D03*
X77921D03*
X72921D03*
X67921D03*
X62921D03*
X57921D03*
X52921D03*
X47921Y-35764D03*
Y-58764D03*
X107921Y-35764D03*
X102921D03*
X97921D03*
X92921D03*
X87921D03*
X82921D03*
X77921D03*
X72921D03*
X67921D03*
X62921D03*
X57921D03*
X52921D03*
X96249Y204722D03*
X64700Y210100D03*
Y212800D03*
X64778Y218062D03*
X58000Y206500D03*
X56900Y197800D03*
X93870Y199131D03*
X97730Y188584D03*
X58200Y230400D03*
Y233400D03*
X55600Y230400D03*
X53000Y230300D03*
Y233300D03*
X55600Y233400D03*
X58200Y227400D03*
X53000Y227300D03*
X55600Y227400D03*
X58200Y239400D03*
X53000Y239300D03*
X55600Y239400D03*
X58200Y236400D03*
X55600D03*
X53000Y236300D03*
X71500Y263300D03*
X68800D03*
X53004Y244632D03*
X55275Y245900D03*
X57875D03*
X57457Y248537D03*
Y251237D03*
X57600Y262800D03*
X57500Y260200D03*
X62800Y265500D03*
X71500Y266000D03*
X65500Y265500D03*
X68800Y266000D03*
X60000Y265500D03*
X76540Y397355D03*
X81900Y398300D03*
X79140Y397355D03*
X98149Y399769D03*
X102456Y393756D03*
X76052Y420935D03*
X78000Y423100D03*
X80100Y425000D03*
X81500Y427400D03*
X79700Y409700D03*
X77400Y407800D03*
X81500Y412100D03*
X84913Y434471D03*
X87013Y436371D03*
X107571Y406291D03*
X48806Y638753D03*
X75206D03*
X106006D03*
X70806D03*
X53206D03*
X66406D03*
X92806D03*
X97206D03*
X101606D03*
X57606D03*
X62006D03*
X79606D03*
X84006D03*
X88406D03*
X53221Y660756D03*
X101621D03*
X97221D03*
X92821D03*
X106021D03*
X48821D03*
X70821D03*
X66421D03*
X62021D03*
X57621D03*
X75221D03*
X88421D03*
X84021D03*
X79621D03*
X167921Y-58764D03*
X162921D03*
X157921D03*
X152921D03*
X147921D03*
X142921D03*
X137921D03*
X132921D03*
X127921D03*
X122921D03*
X117921D03*
X112921D03*
X162921Y-35764D03*
X157921D03*
X152921D03*
X147921D03*
X142921D03*
X137921D03*
X132921D03*
X127921D03*
X122921D03*
X117921D03*
X112921D03*
X167921D03*
X166000Y212900D03*
X168600D03*
X164300Y207870D03*
X160800Y212900D03*
X163400D03*
X157800Y207300D03*
X161216Y209533D03*
Y206933D03*
X154500Y205500D03*
X150600Y212900D03*
X151000Y205500D03*
X140889Y211972D03*
X137615Y212039D03*
X143900Y204600D03*
X147500Y205500D03*
X137300Y204500D03*
X140200Y204400D03*
X153200Y212900D03*
X122044Y162340D03*
X139815Y268974D03*
X137900Y272800D03*
X139800Y237000D03*
X165825Y239543D03*
X168425Y236943D03*
Y239543D03*
X165825Y236943D03*
X163225D03*
X152825D03*
X145025D03*
X147625D03*
X150225D03*
X142425D03*
X163225Y239543D03*
X158025Y236943D03*
X155425D03*
X160625D03*
X142371Y244384D03*
X142466Y268982D03*
X142700Y276200D03*
X136729Y276386D03*
X139683Y276174D03*
X163225Y242143D03*
X168425Y244743D03*
X165825D03*
X163225D03*
X168425Y242143D03*
X165825D03*
X150700Y276800D03*
X169150Y259470D03*
Y255470D03*
X157633Y268727D03*
X162833D03*
X160233D03*
X165433D03*
X168033Y271327D03*
X162833Y276527D03*
Y273927D03*
Y271327D03*
X165433Y276527D03*
Y273927D03*
Y271327D03*
X159983Y276507D03*
X168033Y276527D03*
Y273927D03*
Y268727D03*
X153300Y276800D03*
X139866Y333016D03*
X160233Y306257D03*
Y308857D03*
Y303657D03*
X157518Y335391D03*
X157745Y332800D03*
X139900Y302400D03*
X142433Y301057D03*
X147633D03*
X150233D03*
X145033D03*
X145200Y341300D03*
X148200D03*
X142465Y332940D03*
X152833Y301057D03*
X163233Y306257D03*
Y308857D03*
X168433Y306257D03*
Y308857D03*
Y301057D03*
X165833D03*
X163233D03*
X160633D03*
X158033D03*
X155433D03*
X169150Y287600D03*
Y291600D03*
X165833Y306257D03*
X163233Y303657D03*
X168433D03*
X165833D03*
Y308857D03*
X151000Y341300D03*
X169150Y323600D03*
Y319600D03*
X160501Y332965D03*
X160274Y335556D03*
X165701Y338165D03*
Y335565D03*
X163101Y332965D03*
X168301D03*
X165701D03*
X163101Y335565D03*
X168301Y340765D03*
Y338165D03*
Y335565D03*
X163101Y338165D03*
Y340765D03*
X165701D03*
X154200Y341100D03*
X139767Y364883D03*
X147833Y364457D03*
X142421Y364908D03*
X145033Y364457D03*
X142863Y402829D03*
X140219Y402894D03*
X137619Y402900D03*
X134992D03*
X142818Y400163D03*
X143073Y397194D03*
X140475Y397310D03*
X140218Y400163D03*
X137529Y400296D03*
X134929D03*
X114084Y399937D03*
X122840Y400827D03*
X150633Y364457D03*
X167433Y369657D03*
X169150Y355600D03*
Y351600D03*
X167700Y363900D03*
X161833Y364457D03*
X164633D03*
X159033D03*
X156233D03*
X153433D03*
X164633Y369657D03*
X161833D03*
X161933Y372357D03*
X164733D03*
X167533D03*
X166340Y374785D03*
X167670Y383993D03*
Y387993D03*
X130613Y429647D03*
X123648Y425041D03*
X125328Y427269D03*
X127932Y428571D03*
X110519Y410307D03*
X110199Y413852D03*
X110406Y638753D03*
X145606D03*
X141206D03*
X136806D03*
X132406D03*
X158806D03*
X119206D03*
X123606D03*
X114806D03*
X128006D03*
X163206D03*
X154406D03*
X167606D03*
X150006D03*
X132421Y660756D03*
X145621D03*
X141221D03*
X136821D03*
X123621D03*
X114821D03*
X128021D03*
X110421D03*
X119221D03*
X150021D03*
X167621D03*
X163221D03*
X158821D03*
X154421D03*
X182921Y-58764D03*
X177921D03*
X172921D03*
X227921Y-35764D03*
X222921D03*
X217921D03*
X212921D03*
X207921D03*
X202921D03*
X197921D03*
X192921D03*
X187921D03*
X182921D03*
X177921D03*
X227921Y-58764D03*
X222921D03*
X217921D03*
X212921D03*
X207921D03*
X202921D03*
X197921D03*
X192921D03*
X187921D03*
X172921Y-35764D03*
X211606Y638753D03*
X224806D03*
X220406D03*
X216006D03*
X189606D03*
X198406D03*
X202806D03*
X207206D03*
X176406D03*
X172006D03*
X185206D03*
X180806D03*
X194006D03*
X226500Y649900D03*
X229206Y638753D03*
X224821Y660756D03*
X220421D03*
X198421D03*
X211621D03*
X189621D03*
X202821D03*
X207221D03*
X194021D03*
X185221D03*
X172021D03*
X176421D03*
X180821D03*
X229221D03*
X216021D03*
X292921Y-35764D03*
X287921D03*
X282921D03*
X277921D03*
X272921D03*
X267921D03*
X262921D03*
X257921D03*
X252921D03*
X247921D03*
X242921D03*
X237921D03*
X232921D03*
X292921Y-58764D03*
X287921D03*
X282921D03*
X277921D03*
X272921D03*
X267921D03*
X262921D03*
X257921D03*
X252921D03*
X247921D03*
X242921D03*
X237921D03*
X232921D03*
X290806Y638753D03*
X268806D03*
X273206D03*
X277606D03*
X282006D03*
X260006D03*
X264406D03*
X255606D03*
X251206D03*
X286406D03*
X242406D03*
X246806D03*
X233606D03*
X238006D03*
X286421Y660756D03*
X268821D03*
X282021D03*
X273221D03*
X277621D03*
X264421D03*
X251221D03*
X255621D03*
X260021D03*
X246821D03*
X242421D03*
X238021D03*
X233621D03*
X290821D03*
X352921Y-58764D03*
Y-35764D03*
X347921Y-58764D03*
Y-35764D03*
X342921Y-58764D03*
Y-35764D03*
X337921Y-58764D03*
Y-35764D03*
X332921Y-58764D03*
Y-35764D03*
X327921Y-58764D03*
Y-35764D03*
X322921Y-58764D03*
Y-35764D03*
X317921Y-58764D03*
Y-35764D03*
X312921Y-58764D03*
X307921D03*
Y-35764D03*
X302921Y-58764D03*
Y-35764D03*
X297921D03*
Y-58764D03*
X312921Y-35764D03*
X330406Y638753D03*
X348006D03*
X326006D03*
X312806D03*
X317206D03*
X321606D03*
X352406D03*
X295206D03*
X299606D03*
X308406D03*
X304006D03*
X334806D03*
X339206D03*
X343606D03*
X312821Y660756D03*
X317221D03*
X308421D03*
X304021D03*
X352421D03*
X295221D03*
X326021D03*
X321621D03*
X339221D03*
X299621D03*
X334821D03*
X330421D03*
X343621D03*
X348021D03*
X392921Y-35764D03*
X387921Y-58764D03*
Y-35764D03*
X382921Y-58764D03*
Y-35764D03*
X377921Y-58764D03*
Y-35764D03*
X372921Y-58764D03*
Y-35764D03*
X367921Y-58764D03*
Y-35764D03*
X362921Y-58764D03*
Y-35764D03*
X357921Y-58764D03*
Y-35764D03*
X392921Y-58764D03*
X402921Y-35764D03*
X397921Y-58764D03*
Y-35764D03*
X412921Y-58764D03*
Y-35764D03*
X407921Y-58764D03*
Y-35764D03*
X402921Y-58764D03*
X380885Y273876D03*
Y270876D03*
X382494Y278904D03*
X371094D03*
X378294D03*
X375294D03*
X368094D03*
X389694D03*
X392694D03*
X385945Y278480D03*
X407094Y278910D03*
X414207D03*
X411288D03*
X404094D03*
X400842Y278914D03*
X368094Y295904D03*
X371094D03*
X385494D03*
X375294D03*
X378294D03*
X382494D03*
X389694D03*
X392694D03*
X365693Y311893D03*
X391144Y324173D03*
X388394D03*
X385494D03*
X411294Y295904D03*
X414294D03*
X407094D03*
X404094D03*
X399894D03*
X396894D03*
Y324173D03*
X408894D03*
X411894D03*
X405894D03*
X414894D03*
X393894D03*
X402894D03*
X399894D03*
X383206Y638753D03*
X387606D03*
X392006D03*
X396406D03*
X400806D03*
X405206D03*
X409606D03*
X414006D03*
X370006D03*
X365606D03*
X374406D03*
X378806D03*
X356806D03*
X361206D03*
X374421Y660756D03*
X387621D03*
X383221D03*
X400821D03*
X396421D03*
X392021D03*
X405221D03*
X409621D03*
X414021D03*
X361221D03*
X365621D03*
X356821D03*
X370021D03*
X378821D03*
X477921Y-58764D03*
Y-35764D03*
X472921Y-58764D03*
Y-35764D03*
X467921Y-58764D03*
Y-35764D03*
X462921Y-58764D03*
Y-35764D03*
X457921Y-58764D03*
Y-35764D03*
X452921Y-58764D03*
Y-35764D03*
X447921Y-58764D03*
Y-35764D03*
X442921Y-58764D03*
Y-35764D03*
X437921Y-58764D03*
Y-35764D03*
X432921Y-58764D03*
X422921Y-35764D03*
X417921Y-58764D03*
Y-35764D03*
X432921D03*
X427921Y-58764D03*
Y-35764D03*
X422921Y-58764D03*
X432643Y264508D03*
X418523Y278910D03*
X428694D03*
X432894D03*
X425694D03*
X435894Y278938D03*
X443094Y278904D03*
X440094D03*
X421523Y278944D03*
X451675Y291739D03*
X449148Y292841D03*
X446209Y292842D03*
X451816Y295904D03*
X435894D03*
X418494D03*
X443094D03*
X440094D03*
X446383Y295841D03*
X428694Y295904D03*
X432894D03*
X425694D03*
X421494D03*
X418494Y324173D03*
X451267Y324476D03*
X448694Y323949D03*
X421494Y324173D03*
X446094Y323904D03*
X425694Y324173D03*
X428694D03*
X432894D03*
X435894D03*
X455226Y291686D03*
X454922Y295841D03*
X466806Y638753D03*
X462406D03*
X475606D03*
X471206D03*
X418406D03*
X422806D03*
X427206D03*
X440406D03*
X436006D03*
X431606D03*
X449206D03*
X458006D03*
X453606D03*
X444806D03*
X458021Y660756D03*
X449221D03*
X462421D03*
X466821D03*
X471221D03*
X418421D03*
X475621D03*
X453621D03*
X422821D03*
X427221D03*
X440421D03*
X431621D03*
X436021D03*
X444821D03*
X537921Y-58764D03*
Y-35764D03*
X532921Y-58764D03*
Y-35764D03*
X527921Y-58764D03*
Y-35764D03*
X522921Y-58764D03*
Y-35764D03*
X517921Y-58764D03*
Y-35764D03*
X512921Y-58764D03*
Y-35764D03*
X507921Y-58764D03*
Y-35764D03*
X502921Y-58764D03*
Y-35764D03*
X497921Y-58764D03*
Y-35764D03*
X492921Y-58764D03*
Y-35764D03*
X487921Y-58764D03*
Y-35764D03*
X482921Y-58764D03*
Y-35764D03*
X480006Y638753D03*
X484406D03*
X488806D03*
X493206D03*
X497606D03*
X510806D03*
X537206D03*
X519606D03*
X524006D03*
X532806D03*
X528406D03*
X515206D03*
X502006D03*
X506406D03*
X524021Y660756D03*
X480021D03*
X484421D03*
X497621D03*
X493221D03*
X488821D03*
X519621D03*
X532821D03*
X537221D03*
X528421D03*
X515221D03*
X510821D03*
X506421D03*
X502021D03*
X597921Y-35764D03*
Y-58764D03*
X592921Y-35764D03*
Y-58764D03*
X587921Y-35764D03*
Y-58764D03*
X582921Y-35764D03*
Y-58764D03*
X577921Y-35764D03*
Y-58764D03*
X572921Y-35764D03*
Y-58764D03*
X567921Y-35764D03*
Y-58764D03*
X562921Y-35764D03*
Y-58764D03*
X557921Y-35764D03*
Y-58764D03*
X552921Y-35764D03*
Y-58764D03*
X547921D03*
Y-35764D03*
X542921Y-58764D03*
Y-35764D03*
X590006Y638753D03*
X572406D03*
X559206D03*
X568006D03*
X563606D03*
X550406D03*
X581206D03*
X585606D03*
X576806D03*
X598806D03*
X594406D03*
X601500Y649500D03*
X554806Y638753D03*
X541606D03*
X546006D03*
X559221Y660756D03*
X546021D03*
X554821D03*
X598821D03*
X572421D03*
X568021D03*
X563621D03*
X585621D03*
X541621D03*
X594421D03*
X576821D03*
X590021D03*
X581221D03*
X550421D03*
X637921Y-58764D03*
X632921Y-35764D03*
Y-58764D03*
X627921Y-35764D03*
Y-58764D03*
X622921Y-35764D03*
Y-58764D03*
X617921Y-35764D03*
Y-58764D03*
X612921Y-35764D03*
Y-58764D03*
X607921Y-35764D03*
Y-58764D03*
X602921Y-35764D03*
Y-58764D03*
X652921Y-35764D03*
Y-58764D03*
X647921Y-35764D03*
Y-58764D03*
X642921Y-35764D03*
Y-58764D03*
X637921Y-35764D03*
X662921D03*
Y-58764D03*
X657921Y-35764D03*
Y-58764D03*
X638406Y638753D03*
X634006D03*
X642806D03*
X629606D03*
X616406D03*
X612006D03*
X603206D03*
X625206D03*
X651606D03*
X647206D03*
X660406D03*
X620806D03*
X656006D03*
X607606D03*
X607621Y660756D03*
X638421D03*
X647221D03*
X616421D03*
X634021D03*
X612021D03*
X620821D03*
X625221D03*
X629621D03*
X642821D03*
X603221D03*
X656021D03*
X660421D03*
X651621D03*
X692921Y-58764D03*
X687921Y-35764D03*
Y-58764D03*
X682921Y-35764D03*
Y-58764D03*
X677921Y-35764D03*
Y-58764D03*
X672921Y-35764D03*
Y-58764D03*
X667921Y-35764D03*
Y-58764D03*
X697921Y-35764D03*
Y-58764D03*
X692921Y-35764D03*
X722921D03*
Y-58764D03*
X717921Y-35764D03*
Y-58764D03*
X712921Y-35764D03*
Y-58764D03*
X707921Y-35764D03*
Y-58764D03*
X702921Y-35764D03*
Y-58764D03*
X704466Y-7874D03*
X690966Y-21374D03*
X700525Y1668D03*
X700517Y-17425D03*
X681713Y-17927D03*
X690966Y5626D03*
X681714Y2178D03*
X673864Y-16889D03*
X667566Y-7874D03*
X673864Y1139D03*
X695606Y638753D03*
X673606D03*
X708806D03*
X704406D03*
X700006D03*
X722006D03*
X717606D03*
X713206D03*
X664806D03*
X669206D03*
X686806D03*
X682406D03*
X678006D03*
X691206D03*
X690966Y624130D03*
Y597130D03*
X700525Y620172D03*
X700517Y601079D03*
X704466Y610630D03*
X667566D03*
X673864Y619643D03*
Y601615D03*
X681714Y620682D03*
X681713Y600577D03*
X664821Y660756D03*
X695621D03*
X708821D03*
X700021D03*
X704421D03*
X669221D03*
X686821D03*
X691221D03*
X678021D03*
X673621D03*
X682421D03*
X722021D03*
X717621D03*
X713221D03*
X777921Y-58764D03*
X772921Y-35764D03*
Y-58764D03*
X767921Y-35764D03*
Y-58764D03*
X762921Y-35764D03*
Y-58764D03*
X757921Y-35764D03*
Y-58764D03*
X752921Y-35764D03*
Y-58764D03*
X787921Y-35764D03*
Y-58764D03*
X782921Y-35764D03*
Y-58764D03*
X777921Y-35764D03*
X747921D03*
Y-58764D03*
X742921Y-35764D03*
Y-58764D03*
X737921Y-35764D03*
Y-58764D03*
X732921Y-35764D03*
Y-58764D03*
X727921Y-35764D03*
Y-58764D03*
X786674Y211463D03*
X785920Y204763D03*
X786300Y207400D03*
X787200Y244200D03*
Y271900D03*
X787100Y241100D03*
X773419Y270414D03*
X787200Y276400D03*
X787100Y303900D03*
X753098Y338316D03*
X744698Y332816D03*
X787000Y308300D03*
X787400Y340400D03*
X741774Y376463D03*
X785400Y372400D03*
X757500Y374000D03*
X770406Y638753D03*
X779206D03*
X774806D03*
X730806D03*
X726406D03*
X739606D03*
X735206D03*
X748406D03*
X744006D03*
X766006D03*
X761606D03*
X757206D03*
X752806D03*
X783606D03*
X744021Y660756D03*
X735221D03*
X779221D03*
X770421D03*
X774821D03*
X726421D03*
X730821D03*
X739621D03*
X748421D03*
X783621D03*
X757221D03*
X761621D03*
X752821D03*
X766021D03*
X842921Y-35764D03*
X837921Y-58764D03*
Y-35764D03*
X832921Y-58764D03*
X847921D03*
Y-35764D03*
X842921Y-58764D03*
X832921Y-35764D03*
X827921Y-58764D03*
Y-35764D03*
X822921Y-58764D03*
Y-35764D03*
X817921Y-58764D03*
Y-35764D03*
X812921Y-58764D03*
Y-35764D03*
X807921Y-58764D03*
Y-35764D03*
X802921Y-58764D03*
Y-35764D03*
X797921D03*
Y-58764D03*
X792921Y-35764D03*
Y-58764D03*
X816900Y216300D03*
X816874Y212863D03*
X814274D03*
X811674D03*
X808818Y211179D03*
X808618Y208579D03*
X803200Y213100D03*
X800600D03*
X794474Y211463D03*
X791874D03*
X789274D03*
X788522Y204343D03*
X791122Y204339D03*
X789432Y236947D03*
X789400Y273700D03*
X811983Y244843D03*
Y242243D03*
X814583Y239643D03*
X815432Y237000D03*
X814583Y244843D03*
Y242243D03*
X812832Y237000D03*
X811983Y239643D03*
X802432Y237000D03*
X799832D03*
X792032D03*
X794632D03*
X810232D03*
X797232D03*
X805032D03*
X807632D03*
X791000Y244400D03*
X793600D03*
X816800Y234300D03*
X816900Y230900D03*
X817000Y252500D03*
X789800Y276400D03*
X792400D03*
X801991Y276557D03*
X804591D03*
X792191Y269101D03*
X789591D03*
X814891Y271657D03*
Y274257D03*
Y276857D03*
Y269057D03*
X812291D03*
Y274257D03*
Y276857D03*
Y271657D03*
X817000Y255100D03*
Y257700D03*
X817491Y276857D03*
Y274257D03*
Y271657D03*
Y269057D03*
X817183Y242243D03*
Y239643D03*
Y244843D03*
X818032Y237000D03*
X788600Y306100D03*
X789500Y301200D03*
X797300D03*
X799900D03*
X810300D03*
X802500D03*
X812900D03*
X807700D03*
X805100D03*
X815500D03*
X811991Y308957D03*
Y306357D03*
Y303757D03*
X814591Y306357D03*
Y308957D03*
Y303757D03*
X792900Y308400D03*
X789900D03*
X794700Y301200D03*
X792100D03*
X793000Y340400D03*
X790300Y340300D03*
X816991Y337357D03*
Y334757D03*
Y339957D03*
X814391D03*
Y337357D03*
Y334757D03*
X811791Y337357D03*
Y339957D03*
Y334757D03*
X791879Y332798D03*
X794600Y332600D03*
X816938Y319888D03*
Y323888D03*
X817100Y317000D03*
X818100Y301200D03*
X817191Y303757D03*
Y306357D03*
Y308957D03*
X789860Y364947D03*
X816591Y369857D03*
Y372457D03*
X811391Y369857D03*
X813991D03*
Y372457D03*
X811391D03*
X790900Y372300D03*
X788300Y372400D03*
X802759Y364575D03*
X816672Y358809D03*
X795310Y364721D03*
X816593Y356210D03*
X807959Y364575D03*
X805359D03*
X810559D03*
X815759D03*
X813159D03*
X816900Y361400D03*
X792610Y364821D03*
X816591Y375057D03*
X792238Y396753D03*
X789600Y396809D03*
X811515Y397289D03*
X808915D03*
X813648Y395557D03*
X815472Y390442D03*
X814877Y393138D03*
X792000Y399409D03*
X789400D03*
X849606Y638753D03*
X836406D03*
X832006D03*
X796806D03*
X801206D03*
X792406D03*
X827606D03*
X818806D03*
X823206D03*
X810006D03*
X788006D03*
X845206D03*
X814406D03*
X805606D03*
X840806D03*
X849621Y660756D03*
X832021D03*
X810021D03*
X818821D03*
X836421D03*
X788021D03*
X814421D03*
X801221D03*
X805621D03*
X823221D03*
X827621D03*
X840821D03*
X796821D03*
X792421D03*
X845221D03*
X907921Y-58764D03*
Y-35764D03*
X902921Y-58764D03*
Y-35764D03*
X897921Y-58764D03*
Y-35764D03*
X892921Y-58764D03*
Y-35764D03*
X887921Y-58764D03*
Y-35764D03*
X882921Y-58764D03*
Y-35764D03*
X877921Y-58764D03*
Y-35764D03*
X872921Y-58764D03*
Y-35764D03*
X867921Y-58764D03*
Y-35764D03*
X862921Y-58764D03*
Y-35764D03*
X857921Y-58764D03*
Y-35764D03*
X852921Y-58764D03*
Y-35764D03*
X858406Y638753D03*
X854006D03*
X884806D03*
X880406D03*
X876006D03*
X871606D03*
X867206D03*
X911206D03*
X906806D03*
X889206D03*
X898006D03*
X902406D03*
X893606D03*
X862806D03*
X854021Y660756D03*
X858421D03*
X862821D03*
X898021D03*
X902421D03*
X871621D03*
X884821D03*
X893621D03*
X867221D03*
X889221D03*
X911221D03*
X906821D03*
X880421D03*
X876021D03*
X937921Y-35764D03*
X932921Y-58764D03*
Y-35764D03*
X927921Y-58764D03*
Y-35764D03*
X922921Y-58764D03*
Y-35764D03*
X917921Y-58764D03*
Y-35764D03*
X912921Y-58764D03*
Y-35764D03*
X942921D03*
X967921D03*
X962921Y-58764D03*
Y-35764D03*
X957921Y-58764D03*
Y-35764D03*
X952921Y-58764D03*
Y-35764D03*
X947921Y-58764D03*
Y-35764D03*
X942921Y-58764D03*
X972921D03*
Y-35764D03*
X967921Y-58764D03*
X937921D03*
X924406Y638753D03*
X920006D03*
X915606D03*
X972806D03*
X968406D03*
X964006D03*
X917100Y649300D03*
X942006Y638753D03*
X937606D03*
X933206D03*
X928806D03*
X959606D03*
X955206D03*
X950806D03*
X946406D03*
X959621Y660756D03*
X964021D03*
X968421D03*
X972821D03*
X920021D03*
X915621D03*
X924421D03*
X946421D03*
X942021D03*
X937621D03*
X933221D03*
X928821D03*
X955221D03*
X950821D03*
X1002921Y-58764D03*
Y-35764D03*
X997921Y-58764D03*
Y-35764D03*
X992921Y-58764D03*
Y-35764D03*
X987921Y-58764D03*
Y-35764D03*
X982921Y-58764D03*
Y-35764D03*
X977921Y-58764D03*
Y-35764D03*
X1032921Y-58764D03*
Y-35764D03*
X1027921Y-58764D03*
Y-35764D03*
X1022921Y-58764D03*
Y-35764D03*
X1017921Y-58764D03*
Y-35764D03*
X1012921Y-58764D03*
Y-35764D03*
X1007921Y-58764D03*
Y-35764D03*
X1030489Y270889D03*
Y273889D03*
X1027902Y278904D03*
X1020702D03*
X1017702D03*
X1024902D03*
X1032102D03*
X1017567Y295859D03*
X1024767D03*
X1020567D03*
X1031967D03*
X1027767D03*
X1015293Y311955D03*
X1003606Y638753D03*
X1012406D03*
X977206D03*
X990406D03*
X986006D03*
X994806D03*
X1016806D03*
X1021206D03*
X981606D03*
X999206D03*
X1025606D03*
X1008006D03*
X1030006D03*
X1034406D03*
X999221Y660756D03*
X1034421D03*
X1030021D03*
X1008021D03*
X1012421D03*
X1003621D03*
X1016821D03*
X977221D03*
X981621D03*
X1021221D03*
X1025621D03*
X994821D03*
X986021D03*
X990421D03*
X1067921Y-58764D03*
Y-35764D03*
X1062921Y-58764D03*
Y-35764D03*
X1057921Y-58764D03*
Y-35764D03*
X1052921Y-58764D03*
Y-35764D03*
X1047921Y-58764D03*
Y-35764D03*
X1042921Y-58764D03*
Y-35764D03*
X1037921Y-58764D03*
Y-35764D03*
X1092921Y-58764D03*
Y-35764D03*
X1087921Y-58764D03*
Y-35764D03*
X1082921Y-58764D03*
Y-35764D03*
X1077921Y-58764D03*
Y-35764D03*
X1072921Y-58764D03*
Y-35764D03*
X1042302Y278904D03*
X1039302D03*
X1056602Y278910D03*
X1035814Y278775D03*
X1049867Y278999D03*
X1053459Y278910D03*
X1060958D03*
X1075302D03*
X1078302D03*
X1082330D03*
X1070926D03*
X1063652D03*
X1067783D03*
X1082432Y264620D03*
X1085518Y278910D03*
X1089702Y278904D03*
X1039167Y295859D03*
X1042167D03*
X1034967D03*
X1046367D03*
X1056567D03*
X1049367D03*
X1053567D03*
X1038720Y324174D03*
X1044220D03*
X1035820D03*
X1050220D03*
X1047220D03*
X1053220D03*
X1056220D03*
X1041470D03*
X1059220D03*
X1060767Y295859D03*
X1095756Y292841D03*
X1082367Y295859D03*
X1085367D03*
X1075167D03*
X1078167D03*
X1089567D03*
X1092567D03*
X1095567Y295841D03*
X1070967Y295859D03*
X1063767D03*
X1067967D03*
X1062220Y324174D03*
X1095402Y323904D03*
X1083220Y324174D03*
X1076020D03*
X1079020D03*
X1071820D03*
X1065220D03*
X1068820D03*
X1096006Y638753D03*
X1078406D03*
X1082806D03*
X1074006D03*
X1069606D03*
X1091606D03*
X1052006D03*
X1038806D03*
X1087206D03*
X1060806D03*
X1056406D03*
X1065206D03*
X1043206D03*
X1047606D03*
X1078421Y660756D03*
X1060821D03*
X1087221D03*
X1038821D03*
X1091621D03*
X1052021D03*
X1074021D03*
X1065221D03*
X1096021D03*
X1056421D03*
X1043221D03*
X1047621D03*
X1082821D03*
X1069621D03*
X1157921Y-58764D03*
Y-35764D03*
X1152921Y-58764D03*
Y-35764D03*
X1147921Y-58764D03*
Y-35764D03*
X1142921Y-58764D03*
Y-35764D03*
X1137921Y-58764D03*
Y-35764D03*
X1132921Y-58764D03*
Y-35764D03*
X1127921Y-58764D03*
Y-35764D03*
X1122921Y-58764D03*
Y-35764D03*
X1117921Y-58764D03*
Y-35764D03*
X1112921Y-58764D03*
Y-35764D03*
X1107921Y-58764D03*
Y-35764D03*
X1102921Y-58764D03*
Y-35764D03*
X1097921Y-58764D03*
Y-35764D03*
X1104256Y291841D03*
X1101615Y292447D03*
X1098756Y292841D03*
X1101567Y295859D03*
X1104221Y295696D03*
X1098567Y295841D03*
X1112490Y312723D03*
X1112515Y315369D03*
X1101200Y324013D03*
X1098402Y324017D03*
X1135606Y638753D03*
X1126806D03*
X1144406D03*
X1140006D03*
X1118006D03*
X1122406D03*
X1153206D03*
X1157606D03*
X1104806D03*
X1100406D03*
X1131206D03*
X1148806D03*
X1109206D03*
X1113606D03*
X1157621Y660756D03*
X1148821D03*
X1122421D03*
X1126821D03*
X1100421D03*
X1118021D03*
X1140021D03*
X1113621D03*
X1109221D03*
X1153221D03*
X1144421D03*
X1104821D03*
X1131221D03*
X1135621D03*
X1217921Y-58764D03*
Y-35764D03*
X1212921Y-58764D03*
Y-35764D03*
X1207921Y-58764D03*
Y-35764D03*
X1202921Y-58764D03*
Y-35764D03*
X1197921Y-58764D03*
Y-35764D03*
X1192921Y-58764D03*
Y-35764D03*
X1187921Y-58764D03*
Y-35764D03*
X1182921Y-58764D03*
Y-35764D03*
X1177921Y-58764D03*
Y-35764D03*
X1172921Y-58764D03*
Y-35764D03*
X1167921Y-58764D03*
Y-35764D03*
X1162921Y-58764D03*
Y-35764D03*
X1188406Y638753D03*
X1214806D03*
X1197206D03*
X1201606D03*
X1192806D03*
X1170806D03*
X1162006D03*
X1166406D03*
X1206006D03*
X1219206D03*
X1179606D03*
X1175206D03*
X1210406D03*
X1184006D03*
X1184021Y660756D03*
X1219221D03*
X1192821D03*
X1188421D03*
X1201621D03*
X1179621D03*
X1214821D03*
X1206021D03*
X1166421D03*
X1210421D03*
X1170821D03*
X1162021D03*
X1175221D03*
X1197221D03*
X1232921Y-58764D03*
Y-35764D03*
X1227921Y-58764D03*
Y-35764D03*
X1222921Y-58764D03*
Y-35764D03*
X1252921Y-58764D03*
Y-35764D03*
X1247921Y-58764D03*
Y-35764D03*
X1242921Y-58764D03*
Y-35764D03*
X1237921Y-58764D03*
Y-35764D03*
X1257921D03*
X1272921Y-58764D03*
Y-35764D03*
X1267921Y-58764D03*
Y-35764D03*
X1262921Y-58764D03*
Y-35764D03*
X1257921Y-58764D03*
X1277921D03*
Y-35764D03*
X1263206Y638753D03*
X1223606D03*
X1228006D03*
X1258806D03*
X1241206D03*
X1236806D03*
X1250006D03*
X1245606D03*
X1276406D03*
X1254406D03*
X1280806D03*
X1272006D03*
X1267606D03*
X1232406D03*
X1228021Y660756D03*
X1232421D03*
X1280821D03*
X1245621D03*
X1236821D03*
X1223621D03*
X1276421D03*
X1241221D03*
X1272021D03*
X1258821D03*
X1250021D03*
X1254421D03*
X1263221D03*
X1267621D03*
X1342921Y-35764D03*
Y-58764D03*
X1317921D03*
X1312921Y-35764D03*
Y-58764D03*
X1307921Y-35764D03*
Y-58764D03*
X1302921Y-35764D03*
Y-58764D03*
X1297921D03*
Y-35764D03*
X1292921Y-58764D03*
Y-35764D03*
X1287921Y-58764D03*
Y-35764D03*
X1282921Y-58764D03*
Y-35764D03*
X1322921D03*
Y-58764D03*
X1317921Y-35764D03*
X1337921D03*
Y-58764D03*
X1332921Y-35764D03*
Y-58764D03*
X1327921Y-35764D03*
Y-58764D03*
X1324806Y638753D03*
X1298406D03*
X1285206D03*
X1294006D03*
X1302806D03*
X1333606D03*
X1338006D03*
X1320406D03*
X1311606D03*
X1329206D03*
X1307206D03*
X1342406D03*
X1289606D03*
X1316006D03*
X1329221Y660756D03*
X1311621D03*
X1316021D03*
X1333621D03*
X1342421D03*
X1285221D03*
X1324821D03*
X1338021D03*
X1298421D03*
X1289621D03*
X1294021D03*
X1320421D03*
X1302821D03*
X1307221D03*
X1402921Y-58764D03*
X1397921D03*
X1402921Y-35764D03*
X1392921Y-58764D03*
X1397921Y-35764D03*
X1387921Y-58764D03*
X1392921Y-35764D03*
X1382921Y-58764D03*
X1387921Y-35764D03*
X1377921Y-58764D03*
X1382921Y-35764D03*
X1372921Y-58764D03*
X1377921Y-35764D03*
X1367921Y-58764D03*
X1362921Y-35764D03*
Y-58764D03*
X1357921Y-35764D03*
Y-58764D03*
X1352921Y-35764D03*
Y-58764D03*
X1347921Y-35764D03*
Y-58764D03*
X1395913Y-7874D03*
X1402211Y1139D03*
Y-16889D03*
X1351206Y638753D03*
X1360006D03*
X1404506Y638853D03*
X1355606Y638753D03*
X1386906Y638853D03*
X1364406Y638753D03*
X1391306Y638853D03*
X1346806Y638753D03*
X1400106Y638853D03*
X1382006Y638753D03*
X1377606D03*
X1373206D03*
X1395706Y638853D03*
X1368806Y638753D03*
X1402211Y601615D03*
Y619643D03*
X1395913Y610630D03*
X1368821Y660756D03*
X1346821D03*
X1355621D03*
X1360021D03*
X1364421D03*
X1351221D03*
X1404521Y660856D03*
X1400121D03*
X1395721D03*
X1386921D03*
X1377621Y660756D03*
X1382021D03*
X1373221D03*
X1391321Y660856D03*
X1407921Y-58764D03*
X1412921Y-35764D03*
X1407921D03*
X1442921Y-58764D03*
X1447921Y-35764D03*
X1437921Y-58764D03*
X1442921Y-35764D03*
X1432921Y-58764D03*
X1437921Y-35764D03*
X1427921Y-58764D03*
X1432921Y-35764D03*
X1422921Y-58764D03*
X1427921Y-35764D03*
X1417921Y-58764D03*
X1422921Y-35764D03*
X1412921Y-58764D03*
X1417921Y-35764D03*
X1462921Y-58764D03*
X1457921D03*
X1462921Y-35764D03*
X1452921Y-58764D03*
X1457921Y-35764D03*
X1447921Y-58764D03*
X1452921Y-35764D03*
X1410061Y2178D03*
X1410060Y-17927D03*
X1419313Y5626D03*
Y-21374D03*
X1428872Y1668D03*
X1428864Y-17425D03*
X1432813Y-7874D03*
X1422106Y638853D03*
X1466106D03*
X1448506D03*
X1457306D03*
X1417706D03*
X1413306D03*
X1461706D03*
X1452906D03*
X1408906D03*
X1444106D03*
X1435306D03*
X1426506D03*
X1430906D03*
X1439706D03*
X1432813Y610630D03*
X1428864Y601079D03*
X1428872Y620172D03*
X1419313Y597130D03*
Y624130D03*
X1410060Y600577D03*
X1410061Y620682D03*
X1457321Y660856D03*
X1417721D03*
X1413321D03*
X1408921D03*
X1422121D03*
X1426521D03*
X1435321D03*
X1444121D03*
X1439721D03*
X1430921D03*
X1448521D03*
X1452921D03*
X1466121D03*
X1461721D03*
X1502921Y-58764D03*
X1507921Y-35764D03*
X1497921Y-58764D03*
X1502921Y-35764D03*
X1492921Y-58764D03*
X1497921Y-35764D03*
X1487921Y-58764D03*
X1492921Y-35764D03*
X1482921Y-58764D03*
X1487921Y-35764D03*
X1477921Y-58764D03*
X1482921Y-35764D03*
X1472921Y-58764D03*
X1477921Y-35764D03*
X1467921Y-58764D03*
X1472921Y-35764D03*
X1467921D03*
X1527921Y-58764D03*
X1522921D03*
X1527921Y-35764D03*
X1517921Y-58764D03*
X1522921Y-35764D03*
X1512921Y-58764D03*
X1517921Y-35764D03*
X1507921Y-58764D03*
X1512921Y-35764D03*
X1496906Y638853D03*
X1492506D03*
X1501706Y638753D03*
X1506106D03*
X1514906D03*
X1483706Y638853D03*
X1523706Y638753D03*
X1510506D03*
X1488106Y638853D03*
X1474906D03*
X1519306Y638753D03*
X1479306Y638853D03*
X1528106Y638753D03*
X1470506Y638853D03*
X1496921Y660856D03*
X1483721D03*
X1488121D03*
X1492521D03*
X1479321D03*
X1510521Y660756D03*
X1528121D03*
X1523721D03*
X1501721D03*
X1506121D03*
X1514921D03*
X1519321D03*
X1474921Y660856D03*
X1470521D03*
X1587921Y-58764D03*
X1582921D03*
X1587921Y-35764D03*
X1532921D03*
X1542921D03*
X1532921Y-58764D03*
X1537921Y-35764D03*
X1577921Y-58764D03*
X1582921Y-35764D03*
X1572921Y-58764D03*
X1577921Y-35764D03*
X1567921Y-58764D03*
X1572921Y-35764D03*
X1562921Y-58764D03*
X1567921Y-35764D03*
X1557921Y-58764D03*
X1562921Y-35764D03*
X1552921Y-58764D03*
X1557921Y-35764D03*
X1547921Y-58764D03*
X1552921Y-35764D03*
X1542921Y-58764D03*
X1547921Y-35764D03*
X1537921Y-58764D03*
X1580121Y647556D03*
X1555106Y638753D03*
X1555121Y647556D03*
X1590121D03*
X1590106Y638753D03*
X1590121Y643156D03*
X1585121Y647556D03*
X1585106Y638753D03*
X1585121Y643156D03*
X1565121Y647556D03*
X1570121Y643156D03*
X1570106Y638753D03*
X1565106D03*
X1565121Y643156D03*
X1570121Y647556D03*
X1560121D03*
X1560106Y638753D03*
X1560121Y643156D03*
X1575121D03*
X1575106Y638753D03*
X1575121Y647556D03*
X1555121Y643156D03*
X1580106Y638753D03*
X1580121Y643156D03*
X1550121Y647556D03*
X1541306Y638753D03*
X1545706D03*
X1550106D03*
X1550121Y643156D03*
X1536906Y638753D03*
X1532506D03*
X1565121Y651956D03*
X1570121Y660756D03*
Y656356D03*
X1565121Y660756D03*
X1555121Y651956D03*
X1590121Y660756D03*
Y656356D03*
Y651956D03*
X1585121Y660756D03*
Y656356D03*
Y651956D03*
X1580121Y660756D03*
Y656356D03*
Y651956D03*
X1560121Y660756D03*
Y656356D03*
Y651956D03*
X1555121Y660756D03*
Y656356D03*
X1570121Y651956D03*
X1575121D03*
Y656356D03*
Y660756D03*
X1565121Y656356D03*
X1550121Y651956D03*
Y656356D03*
X1541321Y660756D03*
X1550121D03*
X1545721D03*
X1532521D03*
X1536921D03*
X1642921Y-35764D03*
Y-58764D03*
X1637921Y-35764D03*
Y-58764D03*
X1632921Y-35764D03*
Y-58764D03*
X1627921D03*
X1622921D03*
X1627921Y-35764D03*
X1617921Y-58764D03*
X1622921Y-35764D03*
X1612921Y-58764D03*
X1617921Y-35764D03*
X1607921Y-58764D03*
X1612921Y-35764D03*
X1602921Y-58764D03*
X1607921Y-35764D03*
X1597921Y-58764D03*
X1602921Y-35764D03*
X1592921Y-58764D03*
X1597921Y-35764D03*
X1592921D03*
X1647921D03*
Y-58764D03*
X1625106Y638753D03*
X1625121Y647556D03*
X1630121Y643156D03*
X1630106Y638753D03*
X1630121Y647556D03*
X1635121Y643156D03*
X1635106Y638753D03*
X1635121Y647556D03*
X1640121Y643156D03*
Y647556D03*
X1640106Y638753D03*
X1650121Y647556D03*
X1650106Y638753D03*
X1650121Y643156D03*
X1645121Y647556D03*
X1645106Y638753D03*
X1645121Y643156D03*
X1625121D03*
X1620121Y647556D03*
X1620106Y638753D03*
X1620121Y643156D03*
X1615121Y647556D03*
X1615106Y638753D03*
X1615121Y643156D03*
X1610121Y647556D03*
X1610106Y638753D03*
X1610121Y643156D03*
X1605121Y647556D03*
X1605106Y638753D03*
X1605121Y643156D03*
X1600121Y647556D03*
X1600106Y638753D03*
X1600121Y643156D03*
X1595121Y647556D03*
X1595106Y638753D03*
X1595121Y643156D03*
X1625121Y651956D03*
Y660756D03*
X1630121Y651956D03*
Y656356D03*
Y660756D03*
X1635121Y651956D03*
Y656356D03*
Y660756D03*
X1625121Y656356D03*
X1640121D03*
Y651956D03*
X1650121Y660756D03*
Y656356D03*
Y651956D03*
X1645121Y660756D03*
Y656356D03*
Y651956D03*
X1640121Y660756D03*
X1620121D03*
Y656356D03*
Y651956D03*
X1615121Y660756D03*
Y656356D03*
Y651956D03*
X1610121Y660756D03*
Y656356D03*
Y651956D03*
X1605121Y660756D03*
Y656356D03*
Y651956D03*
X1600121Y660756D03*
Y656356D03*
Y651956D03*
X1595121Y660756D03*
Y656356D03*
Y651956D03*
X1692921Y-40764D03*
X1702921Y-54764D03*
X1687921D03*
X1682921D03*
X1677921D03*
X1672921D03*
X1692921D03*
X1697921D03*
X1707921D03*
X1712921D03*
X1697921Y-40764D03*
X1692921Y-50764D03*
X1687921D03*
X1682921D03*
X1677921D03*
X1672921D03*
X1712921D03*
X1707921D03*
X1702921D03*
X1697921Y-45764D03*
X1707921D03*
X1702921D03*
X1712921D03*
X1697921Y-50764D03*
X1667921Y-35764D03*
X1712921D03*
Y-58764D03*
X1707921Y-35764D03*
Y-58764D03*
X1702921Y-35764D03*
Y-58764D03*
X1697921Y-35764D03*
Y-58764D03*
X1687921Y-40764D03*
X1672921Y-45764D03*
X1677921D03*
X1682921D03*
Y-40764D03*
X1687921Y-45764D03*
X1692921D03*
X1667921Y-58764D03*
X1662921Y-35764D03*
Y-58764D03*
X1657921Y-35764D03*
Y-58764D03*
X1652921Y-35764D03*
Y-58764D03*
X1712921Y-40764D03*
X1707921D03*
X1702921D03*
X1677921D03*
X1672921D03*
X1677921Y-35764D03*
Y-58764D03*
X1672921Y-35764D03*
Y-58764D03*
X1682921Y-35764D03*
Y-58764D03*
X1692921Y-35764D03*
Y-58764D03*
X1687921Y-35764D03*
Y-58764D03*
X1690121Y647556D03*
X1710121D03*
X1710106Y638753D03*
X1710121Y643156D03*
X1705121Y647556D03*
X1705106Y638753D03*
X1695121Y643156D03*
X1695106Y638753D03*
X1695121Y647556D03*
X1700121Y643156D03*
X1700106Y638753D03*
X1685121Y647556D03*
X1685106Y638753D03*
X1685121Y643156D03*
X1680121Y647556D03*
X1680106Y638753D03*
X1680121Y643156D03*
X1675121Y647556D03*
X1675106Y638753D03*
X1675121Y643156D03*
X1670121Y647556D03*
X1670106Y638753D03*
X1670121Y643156D03*
X1665121Y647556D03*
X1665106Y638753D03*
X1665121Y643156D03*
X1660121Y647556D03*
X1660106Y638753D03*
X1660121Y643156D03*
X1655121Y647556D03*
X1655106Y638753D03*
X1655121Y643156D03*
X1690121D03*
X1690106Y638753D03*
X1700121Y647556D03*
X1705121Y643156D03*
X1690121Y656356D03*
Y651956D03*
X1710121Y660756D03*
Y656356D03*
Y651956D03*
X1705121Y660756D03*
Y656356D03*
Y651956D03*
X1690121Y660756D03*
X1695121Y651956D03*
Y656356D03*
Y660756D03*
X1685121Y651956D03*
X1680121Y660756D03*
Y656356D03*
Y651956D03*
X1675121Y660756D03*
Y656356D03*
Y651956D03*
X1670121Y660756D03*
Y656356D03*
Y651956D03*
X1665121Y660756D03*
Y656356D03*
Y651956D03*
X1660121Y660756D03*
Y656356D03*
Y651956D03*
X1655121Y660756D03*
Y656356D03*
Y651956D03*
X1685121Y660756D03*
Y656356D03*
X1700121Y651956D03*
Y656356D03*
Y660756D03*
X1737921Y-50764D03*
X1722921Y-45764D03*
X1727921D03*
X1732921D03*
X1747921D03*
X1752921D03*
X1727921Y-54764D03*
X1757921D03*
X1717921D03*
X1722921D03*
X1767921Y-40764D03*
Y-50764D03*
X1762921D03*
X1757921D03*
X1762921Y-54764D03*
X1752921D03*
X1747921D03*
X1742921D03*
X1737921D03*
X1732921D03*
X1772921D03*
X1767921D03*
X1762921Y-40764D03*
X1772921D03*
X1722921Y-50764D03*
X1717921D03*
X1732921D03*
X1757921Y-40764D03*
X1717921Y-45764D03*
Y-58764D03*
X1742921Y-50764D03*
X1747921D03*
X1752921D03*
X1742921Y-58764D03*
X1737921Y-35764D03*
Y-58764D03*
X1732921Y-35764D03*
Y-58764D03*
X1727921Y-35764D03*
Y-58764D03*
X1722921Y-35764D03*
Y-58764D03*
X1717921Y-35764D03*
X1757921Y-45764D03*
X1762921D03*
X1742921D03*
X1752921Y-40764D03*
X1747921D03*
X1742921D03*
X1737921D03*
X1732921D03*
X1727921D03*
X1722921D03*
X1717921D03*
X1727921Y-50764D03*
X1767921Y-45764D03*
X1772921D03*
X1737921D03*
X1772921Y-35764D03*
Y-58764D03*
X1767921Y-35764D03*
Y-58764D03*
X1762921Y-35764D03*
Y-58764D03*
X1757921Y-35764D03*
Y-58764D03*
X1752921Y-35764D03*
Y-58764D03*
X1747921Y-35764D03*
Y-58764D03*
X1742921Y-35764D03*
X1772921Y-50764D03*
X1775121Y643156D03*
Y647556D03*
X1775106Y638753D03*
X1730121Y647556D03*
X1730106Y638753D03*
X1730121Y643156D03*
X1725121Y647556D03*
X1725106Y638753D03*
X1725121Y643156D03*
X1720121Y647556D03*
X1720106Y638753D03*
X1720121Y643156D03*
X1715121Y647556D03*
X1715106Y638753D03*
X1715121Y643156D03*
X1770121Y647556D03*
X1770106Y638753D03*
X1770121Y643156D03*
X1765121Y647556D03*
X1765106Y638753D03*
X1765121Y643156D03*
X1760121Y647556D03*
X1760106Y638753D03*
X1760121Y643156D03*
X1755121Y647556D03*
X1755106Y638753D03*
X1755121Y643156D03*
X1750121Y647556D03*
X1750106Y638753D03*
X1750121Y643156D03*
X1745121Y647556D03*
X1745106Y638753D03*
X1745121Y643156D03*
X1740121Y647556D03*
X1740106Y638753D03*
X1740121Y643156D03*
X1735121Y647556D03*
X1735106Y638753D03*
X1735121Y643156D03*
X1770121Y660756D03*
X1775121D03*
Y656356D03*
Y651956D03*
X1725121Y660756D03*
Y656356D03*
Y651956D03*
X1720121Y660756D03*
Y656356D03*
Y651956D03*
X1715121Y660756D03*
Y656356D03*
Y651956D03*
X1770121D03*
X1765121Y660756D03*
Y656356D03*
Y651956D03*
X1760121Y660756D03*
Y656356D03*
Y651956D03*
X1755121Y660756D03*
Y656356D03*
Y651956D03*
X1750121Y660756D03*
Y656356D03*
Y651956D03*
X1745121Y660756D03*
Y656356D03*
Y651956D03*
X1740121Y660756D03*
Y656356D03*
Y651956D03*
X1735121Y660756D03*
Y656356D03*
Y651956D03*
X1730121Y660756D03*
Y656356D03*
X1770121D03*
X1730121Y651956D03*
X1817921Y-40764D03*
X1832921Y-45764D03*
Y-54764D03*
X1827921D03*
X1822921D03*
X1817921D03*
X1812921D03*
X1807921D03*
X1802921D03*
X1797921D03*
X1792921D03*
X1787921D03*
X1782921D03*
X1777921D03*
X1832921Y-50764D03*
X1827921D03*
X1822921D03*
X1817921D03*
X1812921D03*
X1807921D03*
X1802921D03*
X1797921D03*
X1792921D03*
X1787921D03*
X1782921Y-40764D03*
X1792921D03*
X1802921D03*
X1807921D03*
X1822921D03*
X1827921D03*
X1832921D03*
X1812921D03*
X1797921D03*
X1777921Y-45764D03*
X1782921D03*
X1787921D03*
X1792921D03*
X1797921D03*
X1802921D03*
X1807921D03*
X1812921D03*
X1817921D03*
X1822921D03*
X1787921Y-40764D03*
X1832921Y-35764D03*
Y-58764D03*
X1827921Y-35764D03*
Y-58764D03*
X1822921Y-35764D03*
Y-58764D03*
X1817921Y-35764D03*
Y-58764D03*
X1812921Y-35764D03*
Y-58764D03*
X1807921Y-35764D03*
Y-58764D03*
X1802921Y-35764D03*
Y-58764D03*
X1797921Y-35764D03*
Y-58764D03*
X1792921Y-35764D03*
Y-58764D03*
X1787921Y-35764D03*
Y-58764D03*
X1782921Y-35764D03*
Y-58764D03*
X1777921Y-35764D03*
Y-58764D03*
X1782921Y-50764D03*
X1777921D03*
Y-40764D03*
X1827921Y-45764D03*
X1794992Y61342D03*
X1797664Y61334D03*
X1797645Y64153D03*
X1792382Y61363D03*
X1792363Y64182D03*
X1794973Y64161D03*
X1807891Y62180D03*
X1810563Y62172D03*
X1810693Y59493D03*
X1808021Y59501D03*
X1805411Y59522D03*
X1813393Y59493D03*
X1813363Y62172D03*
X1810578Y56866D03*
X1805282Y56880D03*
X1807916Y56895D03*
X1813278Y56866D03*
X1805281Y62201D03*
X1831148Y144592D03*
X1836200Y153424D03*
X1833000D03*
X1833600Y145900D03*
X1793205Y165531D03*
X1793268Y162774D03*
X1780121Y643156D03*
X1780106Y638753D03*
X1780121Y647556D03*
X1785121Y643156D03*
X1790121D03*
X1835121Y647556D03*
X1835106Y638753D03*
X1835121Y643156D03*
X1830121Y647556D03*
X1830106Y638753D03*
X1830121Y643156D03*
X1825121Y647556D03*
X1825106Y638753D03*
X1825121Y643156D03*
X1820121Y647556D03*
X1820106Y638753D03*
X1820121Y643156D03*
X1815121Y647556D03*
X1815106Y638753D03*
X1815121Y643156D03*
X1810121Y647556D03*
X1810106Y638753D03*
X1810121Y643156D03*
X1805121Y647556D03*
X1805106Y638753D03*
X1805121Y643156D03*
X1800121Y647556D03*
X1800106Y638753D03*
X1800121Y643156D03*
X1795121Y647556D03*
X1795106Y638753D03*
X1795121Y643156D03*
X1790121Y647556D03*
X1790106Y638753D03*
X1785121Y647556D03*
X1785106Y638753D03*
X1800121Y656356D03*
X1780121Y651956D03*
Y656356D03*
Y660756D03*
X1835121D03*
Y656356D03*
Y651956D03*
X1830121Y660756D03*
Y656356D03*
Y651956D03*
X1825121Y660756D03*
Y656356D03*
Y651956D03*
X1820121Y660756D03*
Y656356D03*
Y651956D03*
X1815121Y660756D03*
Y656356D03*
Y651956D03*
X1810121Y660756D03*
Y656356D03*
Y651956D03*
X1805121Y660756D03*
Y656356D03*
Y651956D03*
X1800121Y660756D03*
Y651956D03*
X1795121Y660756D03*
Y656356D03*
Y651956D03*
X1790121Y660756D03*
Y656356D03*
Y651956D03*
X1785121Y660756D03*
Y656356D03*
Y651956D03*
X1857921Y-45764D03*
X1837921D03*
X1897921D03*
X1892921D03*
X1887921D03*
X1882921D03*
X1877921D03*
X1872921D03*
X1867921D03*
X1862921D03*
X1842921Y-54764D03*
X1852921Y-45764D03*
X1847921D03*
X1842921D03*
X1897921Y-54764D03*
X1892921D03*
X1887921D03*
X1882921D03*
X1877921D03*
X1872921D03*
X1867921D03*
X1862921D03*
X1857921D03*
X1852921D03*
X1847921D03*
X1837921D03*
X1897921Y-50764D03*
X1892921D03*
X1887921D03*
X1882921D03*
X1877921D03*
X1872921D03*
X1867921D03*
X1862921D03*
X1857921D03*
X1852921D03*
X1847921D03*
X1842921D03*
X1837921D03*
X1892921Y-40764D03*
X1897921D03*
X1877921D03*
X1882921D03*
X1887921D03*
X1857921D03*
X1862921D03*
X1867921D03*
X1872921D03*
X1837921D03*
X1842921D03*
X1847921D03*
X1852921D03*
Y-35764D03*
Y-58764D03*
X1847921Y-35764D03*
Y-58764D03*
X1842921Y-35764D03*
Y-58764D03*
X1837921Y-35764D03*
Y-58764D03*
X1862921D03*
X1857921Y-35764D03*
Y-58764D03*
X1882921D03*
X1877921Y-35764D03*
Y-58764D03*
X1872921Y-35764D03*
Y-58764D03*
X1867921Y-35764D03*
Y-58764D03*
X1862921Y-35764D03*
X1897921D03*
Y-58764D03*
X1892921Y-35764D03*
Y-58764D03*
X1887921Y-35764D03*
Y-58764D03*
X1882921Y-35764D03*
X1847797Y26331D03*
X1847564Y21636D03*
X1844732Y-7874D03*
X1851030Y1139D03*
Y-16889D03*
X1858880Y2178D03*
X1858879Y-17927D03*
X1868132Y5626D03*
Y-21374D03*
X1877691Y1668D03*
X1877683Y-17425D03*
X1881632Y-7874D03*
X1895121Y647556D03*
X1895106Y638753D03*
X1895121Y643156D03*
X1890121Y647556D03*
X1890106Y638753D03*
X1890121Y643156D03*
X1885121Y647556D03*
X1885106Y638753D03*
X1885121Y643156D03*
X1880121Y647556D03*
X1880106Y638753D03*
X1880121Y643156D03*
X1875121Y647556D03*
X1875106Y638753D03*
X1875121Y643156D03*
X1870121Y647556D03*
X1870106Y638753D03*
X1870121Y643156D03*
X1865121Y647556D03*
X1865106Y638753D03*
X1865121Y643156D03*
X1860121Y647556D03*
X1860106Y638753D03*
X1860121Y643156D03*
X1855121Y647556D03*
X1855106Y638753D03*
X1855121Y643156D03*
X1850121Y647556D03*
X1850106Y638753D03*
X1850121Y643156D03*
X1845121Y647556D03*
X1845106Y638753D03*
X1845121Y643156D03*
X1840121Y647556D03*
X1840106Y638753D03*
X1840121Y643156D03*
X1844732Y610630D03*
X1851030Y619643D03*
Y601615D03*
X1858880Y620682D03*
X1858879Y600577D03*
X1868132Y624130D03*
Y597130D03*
X1877691Y620172D03*
X1877683Y601079D03*
X1881632Y610630D03*
X1895121Y660756D03*
Y656356D03*
Y651956D03*
X1890121Y660756D03*
Y656356D03*
Y651956D03*
X1885121Y660756D03*
Y656356D03*
Y651956D03*
X1880121Y660756D03*
Y656356D03*
Y651956D03*
X1875121Y660756D03*
Y656356D03*
Y651956D03*
X1870121Y660756D03*
Y656356D03*
Y651956D03*
X1865121Y660756D03*
Y656356D03*
Y651956D03*
X1860121Y660756D03*
Y656356D03*
Y651956D03*
X1855121Y660756D03*
Y656356D03*
Y651956D03*
X1850121Y660756D03*
Y656356D03*
Y651956D03*
X1845121Y660756D03*
Y656356D03*
Y651956D03*
X1840121Y660756D03*
Y656356D03*
Y651956D03*
X1927921Y-40764D03*
X1947921Y-45764D03*
X1942921D03*
X1937921D03*
X1932921D03*
X1927921D03*
X1922921D03*
X1917921D03*
X1912921D03*
X1907921D03*
X1902921D03*
X1927921Y-50764D03*
X1932921D03*
Y-40764D03*
X1937921D03*
X1942921D03*
X1947921D03*
X1907921Y-50764D03*
X1902921D03*
X1922921Y-40764D03*
X1917921D03*
X1912921D03*
X1907921D03*
X1902921D03*
X1922921Y-54764D03*
X1917921D03*
X1912921D03*
X1907921D03*
X1902921D03*
X1927921D03*
X1932921D03*
X1937921D03*
X1942921D03*
X1947921D03*
X1952921D03*
X1957921D03*
Y-50764D03*
X1952921D03*
X1947921D03*
X1942921D03*
X1937921D03*
X1922921D03*
X1917921D03*
X1912921D03*
X1957921Y-35764D03*
Y-58764D03*
X1952921Y-35764D03*
Y-58764D03*
X1947921Y-35764D03*
Y-58764D03*
X1942921Y-35764D03*
Y-58764D03*
X1937921Y-35764D03*
Y-58764D03*
X1932921Y-35764D03*
Y-58764D03*
X1927921Y-35764D03*
Y-58764D03*
X1922921Y-35764D03*
Y-58764D03*
X1917921Y-35764D03*
Y-58764D03*
X1912921Y-35764D03*
Y-58764D03*
X1907921Y-35764D03*
Y-58764D03*
X1902921Y-35764D03*
Y-58764D03*
X1960106Y638753D03*
X1955106D03*
X1950106D03*
X1945121Y647556D03*
Y643156D03*
X1945106Y638753D03*
X1940121Y647556D03*
Y643156D03*
X1940106Y638753D03*
X1935121Y647556D03*
Y643156D03*
X1935106Y638753D03*
X1930106D03*
X1925106D03*
X1920121Y647556D03*
X1910121Y643156D03*
X1910106Y638753D03*
X1905121Y647556D03*
Y643156D03*
X1905106Y638753D03*
X1900121Y647556D03*
X1900106Y638753D03*
X1900121Y643156D03*
X1920106Y638753D03*
X1915121Y647556D03*
X1920121Y643156D03*
X1910121Y647556D03*
X1915106Y638753D03*
X1915121Y643156D03*
X1960121Y656356D03*
Y660756D03*
X1955121Y656356D03*
Y660756D03*
X1950121Y651956D03*
Y656356D03*
Y660756D03*
X1945121Y651956D03*
Y656356D03*
Y660756D03*
X1940121Y651956D03*
Y656356D03*
Y660756D03*
X1935121Y651956D03*
Y656356D03*
Y660756D03*
X1930121Y651956D03*
Y656356D03*
Y660756D03*
X1925121Y651956D03*
Y656356D03*
Y660756D03*
X1920121Y651956D03*
Y656356D03*
X1905121Y651956D03*
Y656356D03*
Y660756D03*
X1900121D03*
Y656356D03*
Y651956D03*
X1915121D03*
Y656356D03*
Y660756D03*
X1920121D03*
X1910121D03*
Y656356D03*
Y651956D03*
X1967921Y-45764D03*
X1962921D03*
Y-40764D03*
X1967921D03*
Y-54764D03*
X1962921D03*
X1967921Y-50764D03*
X1962921D03*
X1967921Y-35764D03*
Y-58764D03*
X1962921Y-35764D03*
Y-58764D03*
X1970121Y647556D03*
Y643156D03*
X1970106Y638753D03*
X1965121Y647556D03*
Y643156D03*
X1965106Y638753D03*
X1970121Y651956D03*
Y656356D03*
Y660756D03*
X1965121Y651956D03*
Y656356D03*
Y660756D03*
G54D11*
X0Y0D03*
G54D20*
X72074Y243282D03*
X65180Y243368D03*
X61800Y243400D03*
X68498Y243368D03*
X49560Y649770D03*
Y644670D03*
X54360D03*
X49560Y649570D03*
Y644670D03*
X54360D03*
X49560Y654670D03*
X54360D03*
X49560D03*
X54360D03*
X214820Y649570D03*
Y644670D03*
X210020D03*
X214820Y649770D03*
Y644670D03*
X210020D03*
X214820Y654670D03*
X210020D03*
X214820D03*
X210020D03*
X238282Y649670D03*
Y644770D03*
X243082D03*
X238282Y649870D03*
Y644770D03*
X243082D03*
X238282Y654770D03*
X243082D03*
X238282D03*
X243082D03*
X402404Y649650D03*
Y644550D03*
X397604D03*
X402404Y649450D03*
Y644550D03*
X397604D03*
X402404Y654550D03*
X397604D03*
X402404D03*
X397604D03*
X425750Y649400D03*
Y644500D03*
X430550D03*
X425750Y649600D03*
Y644500D03*
X430550D03*
X425750Y654500D03*
X430550D03*
X425750D03*
X430550D03*
X589871Y649379D03*
Y644279D03*
X585071D03*
X589872Y649180D03*
Y644280D03*
X585072D03*
X589871Y654279D03*
X585071D03*
X589872Y654280D03*
X585072D03*
X613298Y649331D03*
Y644231D03*
X618098D03*
X613298Y649131D03*
Y644231D03*
X618098D03*
X613298Y654231D03*
X618098D03*
X613298D03*
X618098D03*
X905515Y649159D03*
Y644259D03*
X900715D03*
X905515Y649359D03*
Y644259D03*
X900715D03*
X905515Y654259D03*
X900715D03*
X905515D03*
X900715D03*
X928952Y649120D03*
Y644220D03*
X933752D03*
X928952Y649320D03*
Y644220D03*
X933752D03*
X928952Y654220D03*
X933752D03*
X928952D03*
X933752D03*
X1219041Y649348D03*
Y644248D03*
X1214241D03*
X1219041Y649148D03*
Y644248D03*
X1214241D03*
X1219041Y654248D03*
X1214241D03*
X1219041D03*
X1214241D03*
X1242450Y649150D03*
Y644250D03*
X1247250D03*
X1242450Y649350D03*
Y644250D03*
X1247250D03*
X1242450Y654250D03*
X1247250D03*
X1242450D03*
X1247250D03*
X1527739Y644278D03*
D03*
Y654278D03*
D03*
X1532539Y649378D03*
Y644278D03*
Y649178D03*
Y644278D03*
Y654278D03*
D03*
G54D30*
X1753465Y536791D03*
X1749528D03*
G54D21*
X60512Y467244D03*
X1894100Y493000D03*
X1891086Y602105D03*
G54D12*
G01X38645Y172740D02*
X44291Y178386D01*
G01D02*
X49937Y184032D01*
G01X38645D02*
X44291Y178386D01*
G01D02*
X49937Y172740D01*
G01X-7615D02*
X-1969Y178386D01*
G01D02*
X3677Y184032D01*
G01X-7615D02*
X-1969Y178386D01*
G01D02*
X3677Y172740D01*
G01X12582D02*
X18228Y178386D01*
G01D02*
X23874Y184032D01*
G01X12582D02*
X18228Y178386D01*
G01D02*
X23874Y172740D01*
G01X12129Y430711D02*
X15512Y434094D01*
G01D02*
X18895Y437477D01*
G01X12129D02*
X15512Y434094D01*
G01D02*
X18895Y430711D01*
G01X116597Y142148D02*
X119980Y145531D01*
G01D02*
X123363Y148914D01*
G01X116597D02*
X119980Y145531D01*
G01D02*
X123363Y142148D01*
G01X430749Y-124922D02*
G02I-12000J0D01*
G01X425599D02*
G02I-6850J0D01*
G01X434749D02*
X402749D01*
G01X434749Y-140922D02*
Y-220922D01*
G01D02*
X1729349D01*
G01X434749Y-176422D02*
X1729349D01*
G01X418749Y-140922D02*
Y-108922D01*
G01X434749Y-140922D02*
X1729349D01*
G01X941849D02*
Y-220922D01*
G01X1079349Y-140922D02*
Y-220922D01*
G01X1194349Y-140922D02*
Y-220922D01*
G01X1361849Y-140922D02*
Y-220922D01*
G01X1389729Y21441D02*
X1392264Y23976D01*
G01D02*
X1394799Y26511D01*
G01X1389729D02*
X1392264Y23976D01*
G01D02*
X1394799Y21441D01*
G01X1511383D02*
X1513918Y23976D01*
G01D02*
X1516453Y26511D01*
G01X1511383D02*
X1513918Y23976D01*
G01D02*
X1516453Y21441D01*
G01X1531849Y-140922D02*
Y-220922D01*
G01X1644721Y-2921D02*
X1647327Y-315D01*
G01D02*
X1649933Y2291D01*
G01X1644721D02*
X1647327Y-315D01*
G01D02*
X1649933Y-2921D01*
G01X1729349Y-140922D02*
Y-220922D01*
G01X1757349Y-124922D02*
G02I-12000J0D01*
G01X1752199D02*
G02I-6850J0D01*
G01X1745349Y-140922D02*
Y-108922D01*
G01X1761349Y-124922D02*
X1729349D01*
G01X1947447Y214597D02*
X1950000Y207893D01*
G01X1947447Y203241D02*
X1950000Y207893D01*
G01X1959921Y209074D02*
X1961890Y211043D01*
G01X1950000Y220787D02*
X1953630Y217612D01*
G01X1946370D02*
X1950000Y220787D01*
G01X1947447Y234851D02*
X1950000Y241555D01*
G01Y234851D02*
Y241555D01*
G01X1959921Y240374D02*
X1961890Y238405D01*
G01X1946370Y231836D02*
X1950000Y228661D01*
G01D02*
X1953630Y225486D01*
G01X1950000Y228661D02*
X1953630Y231836D01*
G01X1946370Y223962D02*
X1950000Y220787D01*
G01D02*
X1953630Y223962D01*
G01X1929453Y529639D02*
Y532541D01*
G01D02*
Y535443D01*
G01X1925351Y532541D02*
X1929453D01*
G01D02*
X1933555D01*
G01X1967468Y212037D02*
X1970670Y207007D01*
G01X1967468Y201977D02*
X1970670Y207007D01*
G01X1961890Y211043D02*
X1963859Y213012D01*
G01X1961890Y211043D02*
X1963859Y209074D01*
G01X1967468Y237411D02*
X1970670Y242441D01*
G01Y237411D02*
Y242441D01*
G01X1961890Y238405D02*
X1963859Y240374D01*
G01X1961890Y238405D02*
X1963859Y236436D01*
X-20700Y31400D03*
Y25200D03*
Y22300D03*
Y28100D03*
X-20600Y41200D03*
X-20526Y44263D03*
X-20500Y60300D03*
Y57300D03*
X-20700Y48800D03*
X-20726Y37463D03*
X-20800Y34400D03*
X-20500Y54300D03*
Y51300D03*
X-18000Y247400D03*
X-15000D03*
X-18000Y262700D03*
X-15000D03*
X-14690Y471140D03*
X-16726Y503651D03*
X-17084Y467626D03*
X-17300Y530800D03*
X-17397Y564242D03*
X30600Y-12000D03*
X25838Y-20458D03*
X10600Y25100D03*
X1068Y24831D03*
X27102Y25383D03*
X39530Y5205D03*
X45670Y5185D03*
X33370D03*
X45429Y-4669D03*
X33628Y131D03*
X40994Y-7148D03*
X45700Y40D03*
X11539Y31427D03*
X27200Y30600D03*
X27239Y28027D03*
X25600Y32500D03*
X11600Y33944D03*
X26760Y49595D03*
X27800Y86900D03*
X22100Y56400D03*
X27800Y89900D03*
Y83900D03*
X30400Y89800D03*
Y86800D03*
Y83800D03*
X10925Y56167D03*
X27904Y56294D03*
X30686Y79943D03*
X23530Y94840D03*
X11030D03*
X13530D03*
X16030D03*
X18530D03*
X22380Y92670D03*
X21030Y94840D03*
X2380Y92670D03*
X4880D03*
X7380D03*
X9880D03*
X12380D03*
X14880D03*
X17380D03*
X19880D03*
X3530Y94840D03*
X6030D03*
X8530D03*
X-1000Y81500D03*
X24880Y92670D03*
X25870Y80880D03*
X28294Y80889D03*
X32500Y81791D03*
X25100Y56300D03*
X-1190Y53240D03*
X25886Y71467D03*
X25925Y75867D03*
X26185Y67017D03*
X27488Y64671D03*
X11925Y65311D03*
X27625Y73967D03*
X27525Y69367D03*
X11925Y67811D03*
X11864Y62794D03*
X24064Y61894D03*
X15111Y62553D03*
X27564Y61894D03*
X11600Y36444D03*
X25900Y40300D03*
X27564Y59394D03*
X24064D03*
X25700Y36200D03*
X27300Y34300D03*
Y38300D03*
X27208Y42313D03*
X27239Y47027D03*
X25700Y44400D03*
X27525Y77867D03*
X44200Y139400D03*
X44300Y144800D03*
X44200Y130700D03*
Y116800D03*
X44100Y97800D03*
X44200Y111500D03*
X44300Y102700D03*
Y125600D03*
X44600Y154100D03*
X7995Y285385D03*
X32450Y454050D03*
X35100Y453900D03*
X35900Y423500D03*
X43550Y431300D03*
X20075Y424850D03*
X12025Y427900D03*
X7025D03*
X2025D03*
X21397Y439354D03*
Y444354D03*
X18836Y441785D03*
X7736D03*
X-6104Y461190D03*
X5000Y469000D03*
X10443Y490649D03*
X40132Y499800D03*
X24400Y519500D03*
X280Y524350D03*
X40185Y482918D03*
X37568Y482836D03*
X26780Y488910D03*
X21000Y495800D03*
X13300Y509600D03*
X13600Y504300D03*
X4000Y509500D03*
X2485Y498185D03*
X13700Y498500D03*
X24591Y479139D03*
X35896Y557668D03*
X33396D03*
X38696D03*
X-10200Y558200D03*
X21700Y532300D03*
X19100D03*
X27000D03*
X1040Y531218D03*
X21948Y566700D03*
X19448D03*
X27114Y557563D03*
X24748Y566700D03*
X0Y566800D03*
X29400Y532300D03*
X46400Y536290D03*
Y539790D03*
X43505Y538714D03*
X43241Y535965D03*
X41500Y533800D03*
X29914Y557563D03*
X45880Y554710D03*
Y557820D03*
X46560Y581000D03*
Y577500D03*
X1500Y540600D03*
X15787Y551700D03*
X17100Y545400D03*
X13639Y534683D03*
Y537183D03*
X15800Y543300D03*
X15600Y539100D03*
X17139Y534683D03*
Y537183D03*
X17100Y541200D03*
X17035Y549558D03*
X15800Y547500D03*
X17139Y553683D03*
X1500Y543100D03*
X1439Y538083D03*
X15800Y579500D03*
Y575300D03*
X17108Y585513D03*
X17156Y581481D03*
X17100Y577400D03*
X17139Y573183D03*
X1500Y576600D03*
X17139Y570683D03*
X1500Y579100D03*
X1439Y574083D03*
X15770Y587700D03*
X15800Y583500D03*
X27495Y591409D03*
X-12450Y590965D03*
X30212Y591417D03*
X35085Y591621D03*
X32609Y591538D03*
X46500Y595190D03*
X43190Y598410D03*
X43210Y595180D03*
X43190Y601910D03*
X17139Y589683D03*
X65800Y14200D03*
X59061Y476D03*
X61152Y-12752D03*
X59281Y-20641D03*
X99102Y-12010D03*
X105892Y8700D03*
X62076Y5575D03*
X76247Y1189D03*
X84202Y-11395D03*
X81702D03*
X79202D03*
X73611Y1158D03*
X71111D03*
X68611D03*
X73574Y-1437D03*
X71074D03*
X68574D03*
X79500Y-16600D03*
X55713Y-5095D03*
X76165Y-1415D03*
X106200Y26500D03*
X102100Y73800D03*
X105892Y45290D03*
X52500Y67200D03*
Y63700D03*
Y60700D03*
Y37700D03*
Y34700D03*
Y43700D03*
Y40700D03*
Y57700D03*
X71050Y89600D03*
X48700Y90700D03*
Y95500D03*
X61300Y89800D03*
X81861Y93392D03*
X108385Y84291D03*
X63737Y130602D03*
X48900Y132600D03*
X68592D03*
X85250Y127680D03*
X77730Y126860D03*
X63858Y97620D03*
X66600Y102360D03*
X62422Y109413D03*
X68000Y111000D03*
X48900Y123500D03*
X62524Y123395D03*
X68584Y123900D03*
X68654Y118680D03*
X48800Y118900D03*
X48700Y109600D03*
X48600Y104900D03*
X63582Y116409D03*
X62502Y105100D03*
X52500Y152000D03*
X60300Y151500D03*
X70800Y151400D03*
X48800Y137600D03*
X63878Y144800D03*
X68632Y137800D03*
X63888Y140064D03*
X107254Y128041D03*
X106698Y215610D03*
X100500Y188600D03*
X97500Y185700D03*
X104800D03*
X102400D03*
X99900D03*
X77650Y178150D03*
X73500Y191500D03*
X107750Y238730D03*
X83300Y267400D03*
X108000Y249330D03*
X53400Y277582D03*
Y274500D03*
X48800Y282600D03*
Y285100D03*
X53500Y307300D03*
X85300Y335750D03*
X69500Y322000D03*
X103500Y302100D03*
X99770Y325249D03*
X67400Y391690D03*
X67230Y397380D03*
X67710Y402040D03*
X55616Y368998D03*
X52000Y354500D03*
X61000Y383000D03*
X57500Y388100D03*
X77300Y390600D03*
X107224Y393848D03*
X76500Y368300D03*
X76300Y358400D03*
X82037Y358542D03*
X70600Y368400D03*
X82100Y368300D03*
X70900Y358300D03*
X51500Y406000D03*
X57471Y410749D03*
X64007Y408276D03*
X63630Y424280D03*
X63600Y429000D03*
X51890Y424470D03*
Y418970D03*
X103100Y411800D03*
X72603Y474072D03*
X60300Y508650D03*
X51607Y511747D03*
X74480Y504480D03*
X79630Y504580D03*
X60000Y526500D03*
X79400Y502150D03*
X74600Y502064D03*
X77000Y502133D03*
X49800Y524300D03*
X76996Y504587D03*
X60700Y521900D03*
X57936Y516012D03*
X60202Y495342D03*
X57302Y495442D03*
X105958Y518550D03*
X106392Y537000D03*
X105392Y574800D03*
X105412Y556580D03*
X105000Y614533D03*
X82459Y618932D03*
X105352Y594770D03*
X101898Y611483D03*
X150391Y14814D03*
X163427Y14714D03*
X157084Y14814D03*
X160431Y-1801D03*
X153738Y9114D03*
X150391Y-7851D03*
X163391D03*
X157084D03*
X153738Y-1751D03*
X160431Y9114D03*
X126616Y14714D03*
X136756Y16900D03*
X120273Y16839D03*
X132959Y14814D03*
X141880Y17114D03*
X147045Y9114D03*
X130163D03*
X141856Y9100D03*
X136780Y9098D03*
X123620Y9114D03*
X126580Y-7851D03*
X132959Y-7700D03*
X120273Y-9901D03*
X141893Y-9864D03*
X136806Y-9650D03*
X136780Y-1801D03*
X123620D03*
X130313Y-1751D03*
X141906Y-2050D03*
X147045Y-1751D03*
X169770Y14814D03*
X167124Y-1751D03*
X169770Y-7700D03*
X166974Y9114D03*
X169770Y30100D03*
X120273Y27899D03*
X141893Y27936D03*
X136806Y28150D03*
X126580Y29949D03*
X132959Y30100D03*
X157084Y29949D03*
X163391D03*
X150391D03*
X169770Y90364D03*
X166974Y84714D03*
Y73849D03*
Y46914D03*
X169770Y52614D03*
X167124Y36049D03*
X169770Y67900D03*
X157084Y67749D03*
X163391D03*
X130313Y73849D03*
X123620Y73799D03*
X141906Y73550D03*
X136780Y73799D03*
X126580Y67749D03*
X132959Y67900D03*
X141880Y54914D03*
X123620Y35983D03*
X141856Y46900D03*
X141906Y35750D03*
X136806Y65950D03*
X141893Y65736D03*
X136756Y54700D03*
X136780Y35999D03*
X130313Y35983D03*
X123620Y46914D03*
X132959Y52614D03*
X126616Y52514D03*
X147045Y46914D03*
Y36049D03*
X120273Y54839D03*
Y92500D03*
X126616Y90314D03*
X132959Y90414D03*
X141880Y92714D03*
X163427Y90314D03*
X157084Y90414D03*
X150391D03*
X160431Y84714D03*
X153738D03*
X136756Y92500D03*
X141856Y84700D03*
X136780Y84698D03*
X123620Y84714D03*
X147045D03*
X130163D03*
Y46914D03*
X136780Y46898D03*
X120273Y66000D03*
X147045Y73849D03*
X153738Y36049D03*
Y73849D03*
X160431Y73799D03*
X157084Y52614D03*
X160431Y35999D03*
X150391Y67749D03*
Y52614D03*
X163427Y52514D03*
X160431Y46914D03*
X153738D03*
X156954Y192872D03*
X154454Y193021D03*
X151810Y192670D03*
X124895Y212033D03*
X153788Y187309D03*
X156928Y190053D03*
X148900Y180400D03*
X148800Y185300D03*
Y182900D03*
X148900Y190100D03*
X148800Y187700D03*
X113800Y180500D03*
X116900D03*
X151359Y187700D03*
X156294Y187625D03*
X151300Y190200D03*
X141263Y215216D03*
X125563Y218616D03*
X137763Y217716D03*
X128500Y218700D03*
X141263Y217716D03*
X137763Y215216D03*
X154130Y190186D03*
X169150Y223600D03*
Y227600D03*
X112904Y237218D03*
X122820Y244133D03*
X123074Y275948D03*
X113100Y269163D03*
X125624Y223633D03*
Y221133D03*
X141263Y234216D03*
X141200Y229600D03*
X141211Y225615D03*
X141300Y221700D03*
X139763Y231700D03*
Y227600D03*
Y223700D03*
X139582Y219800D03*
X128200Y250700D03*
X125563Y250616D03*
X141263Y249716D03*
Y247216D03*
X137763D03*
Y249716D03*
X125624Y255633D03*
X141300Y253700D03*
X139631Y251900D03*
X125624Y253133D03*
X137763Y279216D03*
X141263Y266216D03*
X139763Y255700D03*
Y259600D03*
X139800Y263700D03*
X141313Y257533D03*
X141263Y279216D03*
X141200Y261600D03*
X137300Y337200D03*
X118800Y298400D03*
X123301Y308044D03*
X110180Y280920D03*
X109960Y313190D03*
X119050Y341625D03*
X113000Y304000D03*
X113100Y333106D03*
X125624Y287633D03*
X128200Y282600D03*
X141263Y311216D03*
X137763D03*
X141263Y281716D03*
X139730Y284200D03*
X139763Y288200D03*
Y292000D03*
Y296000D03*
X125624Y285133D03*
X141200Y286100D03*
X141261Y290076D03*
X141300Y294000D03*
X141263Y298216D03*
X137763Y281716D03*
X125563Y282616D03*
X141211Y325515D03*
X128200Y314800D03*
X141263Y330216D03*
X139763Y327800D03*
X141300Y317500D03*
Y321500D03*
X139582Y315800D03*
X139763Y319400D03*
X125563Y314616D03*
X141263Y313716D03*
X137763D03*
X139763Y323600D03*
X125624Y317133D03*
Y319633D03*
X109640Y376070D03*
X113500Y369000D03*
X110670Y344500D03*
X112600Y366300D03*
X122300Y372100D03*
X119300Y400900D03*
X110397Y402603D03*
X109924Y393848D03*
X141289Y349488D03*
X128100Y346700D03*
X141300Y353300D03*
X141200Y357200D03*
X137763Y345716D03*
X141263D03*
Y343216D03*
X125624Y349133D03*
X137763Y343216D03*
X141263Y362216D03*
X139582Y347800D03*
X139763Y351400D03*
Y355200D03*
Y359500D03*
X125624Y351633D03*
X125563Y346616D03*
X141300Y381800D03*
X139763Y384000D03*
X125624Y381133D03*
X141263Y394216D03*
Y390416D03*
X141261Y385876D03*
X139736Y392300D03*
X125563Y378616D03*
X137763Y375216D03*
X141263D03*
Y377716D03*
X137763D03*
X139631Y379900D03*
X128500Y378700D03*
X139900Y388000D03*
X125624Y383633D03*
X117363Y417416D03*
X130163Y510114D03*
X147045D03*
X132959Y515814D03*
X126616Y515714D03*
X120273Y517900D03*
X136780Y510098D03*
X136756Y517900D03*
X141856Y510100D03*
X141880Y518114D03*
X123620Y510114D03*
X150391Y515814D03*
X169770Y515764D03*
X163427Y515714D03*
X166974Y510114D03*
X160431D03*
X157084Y515814D03*
X153738Y510114D03*
X141893Y528936D03*
X136806Y529150D03*
X141906Y536750D03*
X132959Y553614D03*
X126616Y553514D03*
X130163Y547914D03*
X123620D03*
X136780Y547898D03*
X141856Y547900D03*
X147045Y537049D03*
Y547914D03*
X120210Y529200D03*
X130313Y537049D03*
X132959Y531100D03*
X126580Y530949D03*
X123620Y536999D03*
X136780D03*
X123620Y574799D03*
X130313Y574849D03*
X132959Y568900D03*
X126580Y568749D03*
X141856Y585700D03*
X141906Y574550D03*
X136780Y574799D03*
Y585698D03*
X120092Y566900D03*
X136806Y566950D03*
X147045Y585714D03*
Y574849D03*
X141880Y555914D03*
X120273Y555700D03*
X136756D03*
X141893Y566736D03*
X130163Y585714D03*
X123620D03*
X150391Y530949D03*
Y553614D03*
X166974Y537049D03*
X163391Y530949D03*
X160431Y536999D03*
X169770Y553564D03*
X163427Y553514D03*
X166974Y547914D03*
X160431D03*
X157084Y530949D03*
X153738Y537049D03*
X157084Y553614D03*
X153738Y547914D03*
X169770Y531100D03*
X150391Y568749D03*
X163391D03*
X160431Y585714D03*
X166974D03*
Y574849D03*
X160431Y574799D03*
X169770Y568900D03*
X157084Y568749D03*
X153738Y585714D03*
Y574849D03*
X147045Y612649D03*
X123620Y612599D03*
X136780D03*
X130313Y612649D03*
X160431Y612599D03*
X166974Y612649D03*
X153738D03*
X126616Y591314D03*
X116992Y590700D03*
X132959Y591414D03*
X136756Y593500D03*
X141880Y593714D03*
X132959Y606700D03*
X126580Y606549D03*
X120092Y604900D03*
X141906Y612350D03*
X136806Y604750D03*
X141893Y604536D03*
X150391Y591414D03*
Y606549D03*
X163427Y591314D03*
X163391Y606549D03*
X169770Y606700D03*
Y591364D03*
X157084Y591414D03*
Y606549D03*
X173591Y-1801D03*
X178691Y17114D03*
X173567Y16900D03*
X178717Y-2050D03*
X183856Y-1751D03*
X173617Y-9650D03*
X178704Y-9864D03*
X178667Y9100D03*
X173591Y9098D03*
X183856Y9114D03*
X178704Y27936D03*
X173617Y28150D03*
X190549Y9114D03*
X197242D03*
X210402Y9098D03*
X210428Y-9650D03*
X193895Y-7851D03*
X187202D03*
X200202D03*
X210402Y-1801D03*
X190549Y-1751D03*
X197242Y-1801D03*
X203935Y-1751D03*
X206581Y-7700D03*
X203785Y9114D03*
X210378Y16900D03*
X210428Y28150D03*
X200202Y29949D03*
X187202D03*
X193895Y14814D03*
Y29949D03*
X200238Y14714D03*
X187202Y14814D03*
X206581D03*
Y30100D03*
X220667Y-1751D03*
X215528Y-2050D03*
X215515Y-9864D03*
X227360Y-1751D03*
X230706Y-7851D03*
X224013D03*
X215478Y9100D03*
X220667Y9114D03*
X227360D03*
X224013Y29949D03*
X230706D03*
Y14814D03*
X224013D03*
X215502Y17114D03*
X215515Y27936D03*
X178691Y92714D03*
X173591Y84698D03*
X178667Y84700D03*
X183856Y84714D03*
X173567Y92500D03*
X183856Y36049D03*
X173591Y46898D03*
X183856Y73849D03*
X178717Y73550D03*
X173591Y73799D03*
X178691Y54914D03*
X173591Y35999D03*
X183856Y46914D03*
X178717Y35750D03*
X178667Y46900D03*
X173567Y54700D03*
X173617Y65950D03*
X178704Y65736D03*
X206581Y52614D03*
X210378Y54700D03*
X210402Y46898D03*
X193895Y67749D03*
X200202D03*
X187202D03*
X203785Y46914D03*
X190549D03*
X197242D03*
X200238Y52514D03*
X193895Y52614D03*
X187202D03*
X190549Y36049D03*
X203935D03*
X197242Y35999D03*
X206581Y67900D03*
X210428Y65950D03*
X210402Y35999D03*
X197242Y73799D03*
X203935Y73849D03*
X210402Y73799D03*
Y84698D03*
X210378Y92500D03*
X190549Y73849D03*
Y84714D03*
X197242D03*
X203785D03*
X193895Y90414D03*
X206581D03*
X200238Y90314D03*
X187202Y90414D03*
X215478Y46900D03*
X215502Y54914D03*
X215515Y65736D03*
X224013Y52614D03*
X220667Y46914D03*
X230706Y52614D03*
X224013Y67749D03*
X230706D03*
X227360Y46914D03*
Y36049D03*
X220667D03*
X215528Y35750D03*
X215502Y92714D03*
X220667Y73849D03*
Y84714D03*
X227360D03*
X230706Y90414D03*
X215478Y84700D03*
X215528Y73550D03*
X227360Y73849D03*
X224013Y90414D03*
X197617Y243089D03*
X191537Y242989D03*
Y240489D03*
X197617Y240589D03*
X191537Y237989D03*
X197617Y238089D03*
X192037Y270750D03*
X194537D03*
X197037D03*
X194537Y299750D03*
X197037D03*
X192037D03*
X194537Y332480D03*
X197037D03*
X192037D03*
X194500Y360200D03*
X197137Y360350D03*
X191900Y360173D03*
X195200Y377800D03*
Y380300D03*
X172697Y407196D03*
X197242Y510114D03*
X200238Y515714D03*
X203785Y510114D03*
X190549D03*
X187202Y515814D03*
X193895D03*
X183856Y510114D03*
X173591Y510098D03*
X173567Y517900D03*
X178691Y518114D03*
X206581Y515814D03*
X210402Y510098D03*
X210378Y517900D03*
X215502Y518114D03*
X215478Y510100D03*
X224013Y515814D03*
X220667Y510114D03*
X227360D03*
X230706Y515814D03*
X193895Y553614D03*
X200238Y553514D03*
X183856Y547914D03*
X190549D03*
X203785D03*
X197242D03*
X190549Y537049D03*
X183856D03*
X187202Y530949D03*
X193895D03*
X197242Y536999D03*
X203935Y537049D03*
X200202Y530949D03*
X206581Y553614D03*
X210402Y547898D03*
X178717Y536750D03*
X173617Y529150D03*
X173591Y536999D03*
X178704Y528936D03*
X178667Y547900D03*
X173591Y547898D03*
X206581Y531100D03*
X210402Y536999D03*
X210428Y529150D03*
X187202Y553614D03*
X178691Y555914D03*
X173567Y555700D03*
X210378D03*
X203935Y574849D03*
X200202Y568749D03*
X197242Y574799D03*
X190549Y585714D03*
X183856D03*
X187202Y568749D03*
X193895D03*
X190549Y574849D03*
X183856D03*
X210402Y585698D03*
X206581Y568900D03*
X210428Y566950D03*
X210402Y574799D03*
X178667Y585700D03*
X178717Y574550D03*
X173591Y574799D03*
Y585698D03*
X173617Y566950D03*
X178704Y566736D03*
X197242Y585714D03*
X203785D03*
X215515Y528936D03*
X215528Y536750D03*
X215478Y547900D03*
X224013Y530949D03*
X220667Y537049D03*
X230706Y530949D03*
X227360Y537049D03*
X230706Y553614D03*
X220667Y547914D03*
X227360D03*
X224013Y553614D03*
X215502Y555914D03*
X220667Y585714D03*
X215528Y574550D03*
X215478Y585700D03*
X215515Y566736D03*
X224013Y568749D03*
X220667Y574849D03*
X230706Y568749D03*
X227360Y574849D03*
Y585714D03*
Y612649D03*
X220667D03*
X203935D03*
X197242Y612599D03*
X190549Y612649D03*
X183856D03*
X210402Y612599D03*
X173591D03*
X187202Y591414D03*
X193895D03*
X187202Y606549D03*
X193895D03*
X200202D03*
X210428Y604750D03*
X206581Y606700D03*
X210378Y593500D03*
X206581Y591414D03*
X178717Y612350D03*
X173617Y604750D03*
X178704Y604536D03*
X173567Y593500D03*
X178691Y593714D03*
X200238Y591314D03*
X224013Y606549D03*
X230706D03*
Y591414D03*
X215515Y604536D03*
X215528Y612350D03*
X215502Y593714D03*
X224013Y591414D03*
X270864Y-1801D03*
X247213D03*
X240746Y-1751D03*
X264171D03*
X252339Y-2050D03*
X234053Y-1801D03*
X257478Y-1751D03*
X243392Y-7700D03*
X260824Y-7851D03*
X252326Y-9864D03*
X237013Y-7851D03*
X247239Y-9650D03*
X267517Y-7851D03*
X252289Y9100D03*
X264171Y9114D03*
X240596D03*
X247213Y9098D03*
X270864Y9114D03*
X234053D03*
X257478D03*
X267517Y14814D03*
Y29949D03*
X247189Y16900D03*
X252326Y27936D03*
X243392Y30100D03*
X247239Y28150D03*
X260824Y29949D03*
X237013D03*
X252313Y17114D03*
X243392Y14814D03*
X260824D03*
X237049Y14714D03*
X284050Y-9650D03*
X289137Y-9864D03*
X273824Y-7851D03*
X280203Y-7700D03*
X289100Y9100D03*
X284024Y9098D03*
X277407Y9114D03*
X277557Y-1751D03*
X289150Y-2050D03*
X284024Y-1801D03*
X273824Y29949D03*
X273860Y14714D03*
X284000Y16900D03*
X280203Y14814D03*
Y30100D03*
X289124Y17114D03*
X284050Y28150D03*
X289137Y27936D03*
X247213Y46898D03*
X257478Y46914D03*
X240596D03*
X243392Y67900D03*
X267517Y67749D03*
Y52614D03*
X270864Y46914D03*
X252326Y65736D03*
X237013Y67749D03*
X260824D03*
X247239Y65950D03*
X243392Y52614D03*
X264171Y46914D03*
X247213Y35999D03*
X257478Y36049D03*
X252339Y35750D03*
X234053Y35999D03*
X240746Y36049D03*
X264171D03*
X237049Y52514D03*
X252289Y46900D03*
X247189Y54700D03*
X252313Y54914D03*
X260824Y52614D03*
X270864Y35999D03*
X234053Y46914D03*
X247213Y73799D03*
Y84698D03*
X264171Y84714D03*
X252339Y73550D03*
X257478Y84714D03*
X240746Y73849D03*
X257478D03*
X234053Y73799D03*
X264171Y73849D03*
X243392Y90414D03*
X252313Y92714D03*
X237049Y90314D03*
X270864Y84714D03*
X247189Y92500D03*
X240596Y84714D03*
X234053D03*
X252289Y84700D03*
X260824Y90414D03*
X267517D03*
X270864Y73799D03*
X273824Y67749D03*
X280203Y67900D03*
X284024Y35999D03*
X277557Y36049D03*
X277407Y46914D03*
X289137Y65736D03*
X284050Y65950D03*
X284024Y46898D03*
X284000Y54700D03*
X289100Y46900D03*
X289150Y35750D03*
X289124Y54914D03*
X280203Y52614D03*
X273860Y90314D03*
X277407Y84714D03*
X289100Y84700D03*
X284024Y84698D03*
X284000Y92500D03*
X289150Y73550D03*
X284024Y73799D03*
X289124Y92714D03*
X280203Y90414D03*
X277407Y73849D03*
X264171Y104284D03*
X267517Y109984D03*
X270864Y104284D03*
X257478D03*
X260824Y109984D03*
X243392Y109534D03*
X252339Y112865D03*
X247213Y113114D03*
X237049Y109884D03*
X240596Y104284D03*
X247239Y105265D03*
X252326Y105051D03*
X234053Y104284D03*
X273860Y109884D03*
X284050Y105265D03*
X289137Y105051D03*
X289150Y112865D03*
X284024Y113114D03*
X280203Y109534D03*
X277407Y104284D03*
X271239Y211060D03*
X284759Y207159D03*
X291519D03*
X274619Y213009D03*
Y216909D03*
X277999Y211060D03*
Y214960D03*
Y203260D03*
Y207159D03*
X281379Y213009D03*
X288139Y216909D03*
X284759Y214960D03*
X291519D03*
Y218860D03*
X281379Y201309D03*
X284759Y199360D03*
X291519D03*
X267859Y244209D03*
Y240309D03*
X271239Y238360D03*
X264179D03*
Y250060D03*
X264092Y222710D03*
X264179Y226660D03*
X271239Y269560D03*
Y273460D03*
Y265660D03*
X267859Y263709D03*
Y259809D03*
X264179Y265660D03*
X267859Y252009D03*
X264179Y253960D03*
X291519Y238360D03*
X284759Y234460D03*
X288139Y232509D03*
X281379D03*
X277999Y234460D03*
X274619Y232509D03*
Y220809D03*
Y224709D03*
Y228610D03*
X277999Y230559D03*
X274619Y244209D03*
X277999Y250060D03*
X274619Y240309D03*
Y248109D03*
Y236409D03*
X291519Y246160D03*
Y250060D03*
X284759Y246160D03*
X291519Y242260D03*
X281379Y220809D03*
X284759Y226660D03*
X288139Y236409D03*
X291519Y234460D03*
Y222760D03*
Y230559D03*
Y226660D03*
X281379Y240309D03*
Y252009D03*
X274619D03*
X277999Y253960D03*
X284759D03*
X291519D03*
X284759Y265660D03*
X291519D03*
Y277360D03*
X281379Y275409D03*
Y271509D03*
X284759Y277360D03*
Y273460D03*
X288139Y275409D03*
Y271509D03*
X277999Y277360D03*
X274619Y255909D03*
Y259809D03*
X277999Y269560D03*
X274619Y275409D03*
Y267609D03*
Y263709D03*
X288139Y255909D03*
X291519Y269560D03*
Y257860D03*
Y261760D03*
X281379Y259809D03*
X288139Y252009D03*
X271239Y328060D03*
X267859Y333909D03*
Y341709D03*
Y330009D03*
X264179Y328060D03*
Y339760D03*
X291519Y285160D03*
Y292959D03*
X284759Y285160D03*
X277999Y308560D03*
Y300760D03*
Y292959D03*
Y285160D03*
X291519Y308560D03*
X284759D03*
Y300760D03*
X291519D03*
X284759Y292959D03*
X291519Y316360D03*
X281379Y318309D03*
X291519Y328060D03*
X288139Y341709D03*
X274619Y330009D03*
Y326110D03*
Y322209D03*
X277999Y328060D03*
X274619Y341709D03*
X277999Y320260D03*
Y316360D03*
X274619Y333909D03*
Y337809D03*
X284759Y324160D03*
X288139Y318309D03*
X284759Y316360D03*
X281379Y337809D03*
X291519Y339760D03*
Y335860D03*
X284759Y331960D03*
X291519D03*
X281379Y326110D03*
X288139D03*
X267559Y369010D03*
X271239Y355360D03*
X267859Y349509D03*
Y353409D03*
X267559Y361209D03*
X264179Y343660D03*
Y355360D03*
X267492Y380709D03*
X271239Y390460D03*
X267859Y388509D03*
X271239Y382660D03*
X284759Y351460D03*
X281379Y345609D03*
X291519Y359260D03*
Y355360D03*
Y351460D03*
X284759Y343660D03*
X274619Y365109D03*
X277999Y363160D03*
Y367060D03*
X274619Y369010D03*
Y361209D03*
Y345609D03*
X277999Y347560D03*
X274619Y353409D03*
Y357309D03*
Y349509D03*
X277999Y343660D03*
X291519Y347560D03*
Y343660D03*
X288139Y365109D03*
X281379D03*
X284759Y363160D03*
X291519D03*
X284759Y370959D03*
X291519Y367060D03*
Y370959D03*
X288139Y361209D03*
X281379Y357309D03*
X288139Y345609D03*
Y380709D03*
Y400209D03*
X274619Y380709D03*
X277999Y394359D03*
X274619Y392410D03*
X277999Y390460D03*
Y386560D03*
X274619Y376809D03*
Y372909D03*
X291519Y374860D03*
X277999Y382660D03*
X284759Y398260D03*
X281379Y396309D03*
X291519Y398260D03*
X284759Y390460D03*
X291519D03*
X281379Y376809D03*
Y384609D03*
X284759Y382660D03*
X291519D03*
Y378760D03*
X264171Y510114D03*
X257478D03*
X260824Y515814D03*
Y491044D03*
X247177Y490514D03*
X252313D03*
X236892Y493400D03*
X243392Y493094D03*
X267584Y491219D03*
X271092Y495944D03*
X257392Y495800D03*
X264192D03*
X233292Y495900D03*
X239492Y498500D03*
X247177Y498514D03*
X252313D03*
X252289Y510100D03*
X267517Y515814D03*
X270864Y510114D03*
X247189Y517900D03*
X252313Y518114D03*
X247213Y510098D03*
X240596Y510114D03*
X243392Y515814D03*
X234053Y510114D03*
X237049Y515714D03*
X284024Y490644D03*
X289124D03*
X273860Y515714D03*
X277557Y495944D03*
X277407Y510114D03*
X289100Y510100D03*
X289124Y518114D03*
X284024Y510098D03*
X280203Y515814D03*
X273992Y491144D03*
X280203Y490644D03*
X284024Y498644D03*
X289124D03*
X284000Y517900D03*
X257478Y537049D03*
X237013Y530949D03*
X252339Y536750D03*
X243392Y531100D03*
X247213Y536999D03*
X252326Y528936D03*
X240746Y537049D03*
X234053Y536999D03*
X267517Y553614D03*
X270864Y547914D03*
X267517Y530949D03*
X270864Y536999D03*
X260824Y553614D03*
X237049Y553514D03*
X243392Y553614D03*
X264171Y547914D03*
X257478D03*
X252289Y547900D03*
X240596Y547914D03*
X247213Y547898D03*
X234053Y547914D03*
X264171Y537049D03*
X260824Y530949D03*
X247189Y555700D03*
X252313Y555914D03*
X270864Y574799D03*
Y585714D03*
X267517Y568749D03*
X247239Y566950D03*
X252326Y566736D03*
X234053Y574799D03*
X240746Y574849D03*
X247213Y574799D03*
X234053Y585714D03*
X237013Y568749D03*
X264171Y585714D03*
X257478D03*
X264171Y574849D03*
X257478D03*
X260824Y568749D03*
X252339Y574550D03*
X252289Y585700D03*
X240596Y585714D03*
X247213Y585698D03*
X243392Y568900D03*
X277407Y537049D03*
X273824Y530949D03*
X273860Y553514D03*
X284024Y547898D03*
X289100Y547900D03*
X280203Y553614D03*
Y531100D03*
X284024Y536999D03*
X289137Y528936D03*
X284050Y529150D03*
X289150Y536750D03*
X277407Y547914D03*
X273824Y568749D03*
X284000Y555700D03*
X289124Y555914D03*
X280203Y568900D03*
X277407Y574849D03*
Y585714D03*
X289100Y585700D03*
X289150Y574550D03*
X284024Y574799D03*
Y585698D03*
X284050Y566950D03*
X289137Y566736D03*
X284024Y612599D03*
X240746Y612649D03*
X247213Y612599D03*
X234053D03*
X257478Y612649D03*
X247239Y604750D03*
X252326Y604536D03*
X260824Y606549D03*
X237013D03*
X243392Y606700D03*
X264171Y612449D03*
X252339Y612350D03*
X267517Y591414D03*
X260824D03*
X237049Y591314D03*
X247189Y593500D03*
X252313Y593714D03*
X243392Y591414D03*
X267517Y606549D03*
X270864Y612399D03*
X273824Y606549D03*
X273860Y591314D03*
X284050Y604750D03*
X289150Y612350D03*
X280203Y606700D03*
Y591414D03*
X277407Y612449D03*
X289124Y593714D03*
X284000Y593500D03*
X289137Y604536D03*
X297635Y-7851D03*
X304328D03*
X300982Y-1751D03*
X294289D03*
Y9114D03*
X300982D03*
X307675Y-1843D03*
Y9300D03*
X304328Y29949D03*
X307992Y13200D03*
X297635Y14814D03*
X321192Y13200D03*
X321334Y32100D03*
X308092D03*
X297635Y29949D03*
X304328Y14814D03*
X334292Y13200D03*
Y32100D03*
X307950Y50729D03*
X300982Y36049D03*
X294289Y46914D03*
X304328Y52614D03*
X321192Y51000D03*
X307675Y35957D03*
X304328Y67749D03*
X297635D03*
X294289Y36049D03*
X300982Y46914D03*
X297635Y52614D03*
X327754Y92757D03*
X331100Y84714D03*
X314368Y87392D03*
X311021Y89964D03*
X317714D03*
X321061Y87392D03*
X307992Y70400D03*
X321334Y69900D03*
X304278Y90414D03*
X307592Y73800D03*
X300982Y84714D03*
X294289D03*
X300982Y73849D03*
X294289D03*
X308166Y87394D03*
X297635Y90414D03*
X334292Y51000D03*
X347833Y92757D03*
X351179Y84599D03*
X337793Y89964D03*
X341140Y87392D03*
X334292Y69900D03*
X300992Y112300D03*
X297642Y107700D03*
X304192Y105000D03*
X324492Y103500D03*
X294899Y213009D03*
X308418Y201309D03*
X317428Y193507D03*
X301648Y194841D03*
X332078Y218860D03*
X329818Y214958D03*
X298279Y218860D03*
X311798Y211060D03*
Y218860D03*
Y214960D03*
X308418Y213009D03*
X305039Y211060D03*
Y218860D03*
X324200Y201308D03*
X298279Y199360D03*
X294899Y201309D03*
X312918Y205210D03*
X315178Y209109D03*
X298279Y207159D03*
Y203260D03*
Y211060D03*
X318558Y218860D03*
X315178Y216909D03*
Y213009D03*
X301659Y209109D03*
X325318Y211060D03*
X334328Y199108D03*
X348978Y209109D03*
X352357Y211060D03*
X338838Y211058D03*
X335458Y216909D03*
X355737Y209109D03*
X294899Y224709D03*
X332078Y242260D03*
Y250060D03*
X328698Y232509D03*
Y220809D03*
X332078Y234460D03*
X298279Y246160D03*
X325318Y250060D03*
X321938Y248109D03*
X305039Y246160D03*
X308418Y244209D03*
X294899D03*
Y248109D03*
X325318Y242260D03*
Y226660D03*
X298279Y234460D03*
X308418Y228610D03*
Y224709D03*
X305039Y230559D03*
X311798Y222760D03*
X308418Y232509D03*
X294899Y228610D03*
X325318Y234460D03*
Y230559D03*
Y222760D03*
X305039Y250060D03*
X318558Y246160D03*
X301659Y248109D03*
X308418Y240309D03*
X315178D03*
X301659D03*
X318558Y242260D03*
X298279Y226660D03*
X318558D03*
X315178Y220809D03*
X321938D03*
X315178Y232509D03*
X301659Y228610D03*
X308418Y236409D03*
X321938D03*
X311798Y238360D03*
X318558D03*
X305039Y226660D03*
X308418Y252009D03*
X298279Y253960D03*
X325318D03*
X308418Y275409D03*
X301659D03*
X308418Y255909D03*
X321938Y275409D03*
X315178Y279310D03*
X318558Y277360D03*
X311798Y261760D03*
X321938Y259809D03*
X301659D03*
X308418Y263709D03*
X325318Y269560D03*
X305039D03*
X318558D03*
X328698Y267609D03*
Y259809D03*
X332078Y269560D03*
X321938Y255909D03*
X308418Y259809D03*
X325318Y273460D03*
Y265660D03*
X301659Y267609D03*
X321938Y263709D03*
X294899Y275409D03*
Y263709D03*
X298279Y265660D03*
X305039Y273460D03*
Y277360D03*
X311798D03*
Y269560D03*
X305039Y265660D03*
X298279Y277360D03*
X328698Y252009D03*
X348978Y220809D03*
X352357Y238360D03*
X345598D03*
X342218Y220809D03*
X338838Y246160D03*
X335458Y248109D03*
X338838Y242260D03*
Y234460D03*
X335458Y236409D03*
X338838Y238360D03*
X335458Y224709D03*
X355737Y248109D03*
X348978D03*
X355737Y220809D03*
X338838Y253960D03*
X335458Y252009D03*
X338838Y265660D03*
X335458Y259809D03*
Y267609D03*
X345598Y265660D03*
X348978Y263709D03*
X355737Y259809D03*
X352357Y261760D03*
X345598Y273460D03*
Y269560D03*
X342218Y263709D03*
Y271509D03*
Y259809D03*
Y255909D03*
Y267609D03*
Y279310D03*
Y275409D03*
X311798Y292959D03*
X305039D03*
X321938Y283209D03*
X315178D03*
X318558Y281260D03*
Y292959D03*
X311798Y285160D03*
X328698Y310509D03*
X332078Y300760D03*
X328698Y283209D03*
X332078Y292959D03*
Y281260D03*
X298279Y308560D03*
X321938Y310509D03*
X315178D03*
X305039Y308560D03*
X311798D03*
X305039Y300760D03*
X325318D03*
X311798D03*
X298279D03*
X318558D03*
X325318Y292959D03*
Y281260D03*
X305039Y285160D03*
X298279D03*
Y292959D03*
X318558Y312460D03*
X325318D03*
X308418Y333909D03*
Y341709D03*
X325318Y339760D03*
Y335860D03*
X301659Y337809D03*
X315178Y330009D03*
X301659D03*
X308418Y337809D03*
X305039Y331960D03*
X298279Y328060D03*
Y331960D03*
X311798Y324160D03*
X308418Y330009D03*
X315178Y322209D03*
X321938D03*
X294899Y333909D03*
X305039Y328060D03*
X321938Y330009D03*
Y337809D03*
X328698Y330009D03*
Y326110D03*
Y333909D03*
X325318Y324160D03*
X318558Y320260D03*
X301659Y318309D03*
X308418D03*
X305039Y316360D03*
X332078Y331960D03*
Y339760D03*
X298279Y316360D03*
X294899Y322209D03*
Y318309D03*
X311798Y316360D03*
X308418Y326110D03*
X315178Y314409D03*
X332078Y312460D03*
X335458Y310509D03*
X338838Y300760D03*
Y292959D03*
Y281260D03*
X335458Y283209D03*
X342218Y310509D03*
Y283209D03*
X345598Y335860D03*
Y331960D03*
X342218Y314409D03*
X338838Y312460D03*
Y316360D03*
X335458Y330009D03*
X338838Y331960D03*
Y339760D03*
X345598Y328060D03*
Y339760D03*
X352357Y335860D03*
X348978Y333909D03*
X342218Y322209D03*
Y318309D03*
Y330009D03*
Y326110D03*
Y333909D03*
X355737Y337809D03*
X345598Y320260D03*
Y324160D03*
X308418Y357309D03*
X311798Y359260D03*
X298279Y351460D03*
X294899Y349509D03*
Y353409D03*
X321938Y349509D03*
X318558Y359260D03*
X321938Y361209D03*
X298279Y343660D03*
X315178Y357309D03*
X301659D03*
Y349509D03*
X308418Y361209D03*
Y353409D03*
Y345609D03*
X305039Y347560D03*
X325318Y343660D03*
Y347560D03*
X328698Y365109D03*
X332078Y363160D03*
X328698Y345609D03*
X325318Y355360D03*
X332078Y347560D03*
Y355360D03*
X294899Y369010D03*
X325318Y367060D03*
Y370959D03*
X318558D03*
X308418Y365109D03*
X315178D03*
X325318Y363160D03*
X298279D03*
X305039Y370959D03*
X308418Y369010D03*
X305039Y367060D03*
X301659Y369010D03*
X298279Y370959D03*
X318558Y351460D03*
Y355360D03*
X305039Y351460D03*
X301659Y388509D03*
X308418D03*
X318558Y394359D03*
X324458Y399911D03*
X332078Y378760D03*
X318558Y386560D03*
X325318D03*
X311798Y374860D03*
X325318D03*
X294899Y372909D03*
X308418D03*
X321938Y376809D03*
X318558Y382660D03*
Y378760D03*
X298279D03*
X305039D03*
X308418Y384609D03*
X311798Y382660D03*
Y378760D03*
X315178Y376809D03*
X328698D03*
X294899Y384609D03*
X318558Y390460D03*
X320808Y401941D03*
X298279Y386560D03*
Y390460D03*
X315178Y392410D03*
Y388509D03*
X311798Y386560D03*
X298279Y398260D03*
Y394359D03*
X294899Y396309D03*
X325318Y378760D03*
X321938Y380709D03*
X305039Y394359D03*
X302608Y402421D03*
X352357Y359260D03*
X338838Y347560D03*
X335458Y361209D03*
X338838Y359260D03*
Y355360D03*
Y351460D03*
X335458Y349509D03*
X345598Y359260D03*
X348978Y349509D03*
X345598Y343660D03*
X342218Y345609D03*
X355737Y349509D03*
Y376809D03*
Y388509D03*
X348978Y376809D03*
X342218Y388509D03*
Y376809D03*
X335458Y372909D03*
Y384609D03*
Y380709D03*
X345598Y390460D03*
X352357Y386560D03*
X294289Y490444D03*
X301092Y490700D03*
X317714Y515364D03*
X321061Y512792D03*
X331100Y510114D03*
X327754Y518157D03*
X314368Y512792D03*
X311021Y515364D03*
X297835Y497644D03*
X308166Y512794D03*
X300982Y510114D03*
X304278Y515814D03*
X297635D03*
X294289Y510114D03*
X304392Y497300D03*
X324187Y499793D03*
X337793Y515364D03*
X350882Y509999D03*
X347833Y518157D03*
X341140Y512792D03*
X307675Y548200D03*
X304278Y553614D03*
X297635D03*
X300982Y547914D03*
X294289D03*
X307675Y536957D03*
X304328Y530949D03*
X300982Y537049D03*
X297635Y530949D03*
X294289Y537049D03*
X307992Y533100D03*
X321334D03*
X321123Y552000D03*
X308100D03*
X307992Y570900D03*
X321334D03*
X294289Y574849D03*
Y585714D03*
X304328Y568749D03*
X307675Y574757D03*
X300982Y574849D03*
X307848Y588334D03*
X300982Y585714D03*
X297635Y568749D03*
X334292Y533100D03*
Y552000D03*
Y570900D03*
X304328Y606549D03*
X297635D03*
X294289Y612249D03*
X300982D03*
X307675Y611600D03*
X307892Y591000D03*
X321192Y589800D03*
X304278Y591414D03*
X297635D03*
X334292Y589800D03*
X375792Y6500D03*
X377592Y-10880D03*
X380232Y-10900D03*
X380200Y-1200D03*
X378792Y6500D03*
X358592Y30736D03*
X380792Y27812D03*
X357492Y14314D03*
X380792Y24933D03*
X357492Y11714D03*
X358619Y33342D03*
X398029Y9107D03*
X408069D03*
X394192Y-9700D03*
X409522Y-20794D03*
X408184Y32100D03*
Y13200D03*
X357762Y49659D03*
X357772Y68335D03*
X371042Y46900D03*
X380792Y56500D03*
X357762Y52333D03*
X357965Y92500D03*
X367911Y87500D03*
X368311Y92500D03*
X357872Y87500D03*
X357772Y70935D03*
X374292Y77200D03*
Y74100D03*
X408069Y46907D03*
X408184Y51000D03*
X398029Y46907D03*
X401375Y92757D03*
X398029Y84800D03*
X408068Y87392D03*
X411415Y89964D03*
X408184Y69900D03*
X386292Y98800D03*
X362497Y209109D03*
X382777D03*
X376017D03*
X389537D03*
X415634Y204496D03*
Y212296D03*
X396296Y209109D03*
X415634Y208397D03*
X407706Y209109D03*
X379397Y238360D03*
X362497Y220809D03*
X379397Y250060D03*
X369257Y220809D03*
X382777D03*
X376017D03*
X386157Y238360D03*
X372637Y250060D03*
X389537Y248109D03*
Y220809D03*
X376017Y248109D03*
X382777D03*
X386157Y250060D03*
X359117Y238360D03*
X365877D03*
X372637D03*
X365877Y253960D03*
X362497Y255909D03*
X359117Y257860D03*
X369257Y252009D03*
X392916Y250060D03*
Y238360D03*
X396296Y248109D03*
Y220809D03*
X399676Y250060D03*
X407706Y248109D03*
X415634Y247396D03*
Y235696D03*
Y223996D03*
X407706Y220809D03*
X370650Y312441D03*
X378156D03*
X375674D03*
X373162Y312400D03*
X368165Y312504D03*
X359117Y339760D03*
X362497Y341709D03*
X379397Y359260D03*
X382777Y349509D03*
X379397Y347560D03*
X369257Y345609D03*
X376017D03*
X386157Y351460D03*
Y359260D03*
X372637Y347560D03*
X389537Y353409D03*
X372637Y359260D03*
X365877D03*
X359117D03*
X365877Y343660D03*
X376017Y376809D03*
X369257D03*
X382777Y388509D03*
X369257D03*
X362497D03*
X376017D03*
X389537D03*
Y376809D03*
X382777D03*
X362497D03*
X396296Y353409D03*
X411086Y351460D03*
X405306Y347109D03*
X399676Y351460D03*
X392916D03*
Y359260D03*
X396296Y388509D03*
Y376809D03*
X411086Y374860D03*
X403056Y376809D03*
Y388509D03*
X385244Y504027D03*
X359042Y515200D03*
X358918Y510114D03*
X366865D03*
Y515152D03*
X401375Y518157D03*
X398029Y509999D03*
X411415Y515364D03*
X408068Y512792D03*
X357539Y550511D03*
X357661Y534000D03*
X376829Y546303D03*
X357661Y531546D03*
X357539Y553111D03*
X376785Y538305D03*
X363760Y529293D03*
X357724Y569474D03*
X376892Y577500D03*
X356798Y588366D03*
X357724Y571973D03*
X408069Y547907D03*
X408184Y533100D03*
Y552000D03*
X398029Y547907D03*
X408184Y570900D03*
X398029Y585707D03*
X408069D03*
X413324Y623559D03*
X399824D03*
X356798Y590939D03*
X373400Y593800D03*
X376204Y593650D03*
X374039Y611186D03*
X408184Y589800D03*
X447744Y-7180D03*
X451573Y-1801D03*
Y9114D03*
X436392Y-20760D03*
X422892Y-20789D03*
X448226Y28100D03*
X433508Y32100D03*
X448292Y31900D03*
X421368Y32100D03*
X433508Y13200D03*
X448292Y13700D03*
X421368Y13200D03*
X448892Y17000D03*
X458266Y-1751D03*
X460912Y-7700D03*
X454533Y-7851D03*
X458116Y9114D03*
X469832Y-2051D03*
X464732Y-1801D03*
X474998Y-1751D03*
X469845Y-9864D03*
X478344Y-7851D03*
X464758Y-9652D03*
X474998Y9114D03*
X464732Y9098D03*
X478344Y29949D03*
X460912Y30100D03*
Y14814D03*
X469832Y17114D03*
X454569Y14714D03*
X454533Y29949D03*
X469792Y9300D03*
X478344Y14814D03*
X469845Y27936D03*
X464792Y28100D03*
X464692Y16900D03*
X448414Y35761D03*
X448973Y54883D03*
X451573Y35999D03*
X448627Y68090D03*
X448517Y46975D03*
X448492Y51000D03*
X421368D03*
X433508D03*
X451573Y46900D03*
X428147Y92500D03*
X424801Y84800D03*
X431400D03*
X441533Y87392D03*
Y92500D03*
X418108Y89964D03*
Y84599D03*
X434840Y92500D03*
X448651Y70896D03*
X433508Y69900D03*
X421368D03*
X451573Y84714D03*
Y73799D03*
X448610Y85296D03*
X448599Y73589D03*
X448692Y89900D03*
X474998Y36049D03*
X464732Y46898D03*
X460912Y52614D03*
X458266Y36049D03*
X458116Y46914D03*
X464758Y65950D03*
X474998Y46914D03*
X454533Y67749D03*
X454569Y52514D03*
X469832Y54914D03*
X469792Y47100D03*
Y35800D03*
X464692Y54700D03*
X464732Y35999D03*
X478344Y52614D03*
X460912Y67900D03*
X478344Y67749D03*
X469845Y65736D03*
X458116Y84714D03*
X464708Y92500D03*
X464732Y84698D03*
X469808Y84700D03*
X474998Y73849D03*
X469858Y73550D03*
X474998Y84714D03*
X478344Y90414D03*
X469832Y92714D03*
X460912Y90314D03*
X464732Y73799D03*
X458266Y73849D03*
X454569Y90314D03*
X441743Y199841D03*
X421464Y199583D03*
X446253Y206446D03*
X425974D03*
X453013Y218147D03*
X449633Y212296D03*
Y216196D03*
X422594D03*
X419214Y214247D03*
X436113Y212296D03*
X432733Y214247D03*
X429354Y216196D03*
X432733Y218147D03*
X425974D03*
X429353Y212296D03*
X446253Y218147D03*
X442873Y216196D03*
X439493Y214247D03*
X436113Y216196D03*
X453013Y214247D03*
X439493Y210346D03*
X434983Y198931D03*
X455263Y198050D03*
X473292Y218147D03*
X469913Y216196D03*
X469912Y212296D03*
X475692Y199900D03*
X466533Y218147D03*
X473292Y214247D03*
X476672Y212296D03*
Y216196D03*
X459773Y214247D03*
X466533Y206446D03*
X456393Y216196D03*
X462023Y198327D03*
X456393Y212296D03*
X463153Y216196D03*
X429354Y251296D03*
X453013Y245447D03*
Y229847D03*
Y237647D03*
X449633Y251296D03*
Y247396D03*
Y227896D03*
Y223996D03*
X436113Y243496D03*
X442873D03*
X422594D03*
X425974Y245447D03*
Y249347D03*
X432733D03*
X436113Y251296D03*
X429354Y247396D03*
X422594Y251296D03*
X446253Y245447D03*
X419214Y249347D03*
X432733Y245447D03*
X439493Y237647D03*
X446253D03*
X422594Y223996D03*
Y231797D03*
X419214Y233746D03*
Y237647D03*
X436113Y231797D03*
X439493Y241547D03*
X419214D03*
X436113Y223996D03*
X429354D03*
Y220096D03*
Y227896D03*
X446253Y229847D03*
X432733D03*
X425974D03*
X439493Y233746D03*
X442873Y231797D03*
Y223996D03*
X425974Y237647D03*
X432733D03*
X449633Y220096D03*
X439493Y253247D03*
X449633Y255196D03*
Y259096D03*
X446253Y257147D03*
X442873Y255196D03*
X453013Y257147D03*
Y261047D03*
X448900Y269600D03*
X469913Y251296D03*
X466533Y245447D03*
X473292D03*
X476672Y223996D03*
Y243496D03*
Y251296D03*
X469913Y247396D03*
Y223996D03*
X473292Y229847D03*
X469913Y227896D03*
X466533Y229847D03*
X473292Y237647D03*
X466533D03*
X469913Y220096D03*
X456393Y243496D03*
Y251296D03*
X459773Y233746D03*
Y241547D03*
Y237647D03*
X456393Y223996D03*
Y231797D03*
X476672D03*
X463153Y243496D03*
Y251296D03*
Y231797D03*
Y223996D03*
X476672Y259096D03*
X463153D03*
X458408Y278940D03*
X477792Y272747D03*
X462023Y271097D03*
X458643Y269146D03*
X456393Y262996D03*
Y259096D03*
X459773Y261047D03*
X469913Y255196D03*
X473292Y257147D03*
X466533D03*
X468783Y274997D03*
X469913Y270796D03*
X466533Y264947D03*
X469913Y305896D03*
X477792Y307851D03*
X469913Y286396D03*
X477792Y303947D03*
Y288347D03*
Y315647D03*
Y319547D03*
X458643Y338746D03*
X477792Y327347D03*
X462948Y315251D03*
X455263Y340697D03*
X462848Y312741D03*
X467653Y340996D03*
X474413D03*
Y337096D03*
X469913Y321496D03*
X443993Y358547D03*
X441743Y348497D03*
X440613Y352696D03*
X437233Y358547D03*
X450753Y366347D03*
Y350747D03*
Y358547D03*
X437233Y362447D03*
X423714D03*
X433854Y368296D03*
X427094D03*
X440613Y364396D03*
X427094Y372197D03*
X447373D03*
Y368296D03*
X440613Y372197D03*
Y368296D03*
X443993Y366347D03*
X427094Y356596D03*
X433854Y352696D03*
X437233Y354647D03*
X423714D03*
X430474D03*
X427094Y360496D03*
X433854D03*
X445123Y346546D03*
X427094Y352696D03*
X430474Y385847D03*
X450753Y397547D03*
X440613Y395595D03*
X429354Y399496D03*
X433854Y379996D03*
X423714Y374146D03*
X437233D03*
X430474Y378047D03*
X433854Y376096D03*
X443993Y397546D03*
Y401447D03*
Y393647D03*
X440613Y391696D03*
X443993Y385847D03*
X427094Y376096D03*
X437233Y381947D03*
X447373Y376096D03*
X440613Y379996D03*
X443993Y378047D03*
X423715Y397548D03*
X430474Y393647D03*
X433854Y391696D03*
X423715Y401449D03*
X450753Y385847D03*
Y393647D03*
Y378047D03*
X437233Y389747D03*
Y385847D03*
X423714D03*
X477792Y342947D03*
Y362447D03*
Y354647D03*
Y358547D03*
X457513Y362447D03*
X454133Y372197D03*
Y364396D03*
Y348796D03*
Y352696D03*
X464273Y366347D03*
X474413Y372197D03*
X471033Y366347D03*
X467653Y372197D03*
X474413Y364396D03*
X464273Y350747D03*
X474413Y348796D03*
X471033Y350747D03*
X474413Y352696D03*
X471033Y358547D03*
X464273D03*
X467653Y368296D03*
Y348796D03*
X460893Y372197D03*
Y364396D03*
Y352696D03*
X457513Y354647D03*
Y358547D03*
Y346847D03*
X477792Y389747D03*
X457513D03*
X471033Y393647D03*
X460893Y395595D03*
X464273Y401447D03*
X471033D03*
X460893Y391696D03*
X457513Y385847D03*
Y381947D03*
X460893Y379996D03*
X477792Y381947D03*
X474413Y391696D03*
X464273Y385847D03*
X454133Y391696D03*
Y379996D03*
X471033Y385847D03*
X464273Y393647D03*
X474413Y379996D03*
X471033Y378047D03*
X467653Y376096D03*
X464273Y378047D03*
Y397546D03*
X477792Y385847D03*
X447091Y407782D03*
X428224Y407800D03*
X443993Y405347D03*
X467653Y407296D03*
X464273Y405347D03*
X441533Y512792D03*
Y518057D03*
X434840Y518157D03*
X431494Y509999D03*
X424801Y510114D03*
X418108Y515364D03*
Y509999D03*
X428147Y518157D03*
X451573Y510114D03*
X448692Y515300D03*
X447735Y512794D03*
X474998Y510114D03*
X464732Y510098D03*
X460912Y515714D03*
X458116Y510114D03*
X454569Y515714D03*
X478344Y515814D03*
X464708Y517900D03*
X469832Y518114D03*
X451573Y547914D03*
Y536999D03*
X448510Y549843D03*
X448410Y531156D03*
X448432Y536723D03*
X448692Y553100D03*
X448557Y534061D03*
X421368Y533100D03*
X434395Y532904D03*
X433508Y552000D03*
X421368D03*
X433508Y570900D03*
X421368D03*
X451573Y585714D03*
Y574799D03*
X448226Y569200D03*
X448291Y574773D03*
X464732Y536999D03*
X460912Y553514D03*
X458116Y547914D03*
X454569Y553514D03*
X454533Y530949D03*
X460912Y531100D03*
X458266Y537049D03*
X469845Y528936D03*
X474998Y537049D03*
X464758Y529150D03*
X469858Y536750D03*
X478344Y553614D03*
X464732Y547898D03*
X474998Y547914D03*
X469808Y547900D03*
X478344Y530949D03*
Y568749D03*
X464732Y574799D03*
X469808Y585700D03*
X469858Y574550D03*
X474998Y574849D03*
Y585714D03*
X464732Y585698D03*
X464758Y566950D03*
X469845Y566736D03*
X458266Y574849D03*
X460912Y568900D03*
X458116Y585714D03*
X454533Y568749D03*
X464708Y555700D03*
X469832Y555914D03*
X474998Y612649D03*
X464732Y612599D03*
X458266Y612649D03*
X427324Y623541D03*
X451573Y612599D03*
X447744Y607220D03*
X448692Y590900D03*
X420634Y589800D03*
X433500D03*
X478344Y591414D03*
X464708Y593500D03*
X469832Y593714D03*
X464758Y604750D03*
X469845Y604536D03*
X478344Y606549D03*
X469858Y612350D03*
X460912Y591314D03*
Y606700D03*
X454533Y606549D03*
X454569Y591314D03*
X511809Y-1751D03*
Y9114D03*
X495077Y-1751D03*
X501544Y-1801D03*
X506692Y-2000D03*
X488384Y-1801D03*
X481691Y-1751D03*
X485037Y-7851D03*
X491344D03*
X506657Y-9864D03*
X497723Y-7700D03*
X501592Y-9700D03*
X481691Y9114D03*
X494927D03*
X488384D03*
X501544Y9098D03*
X497723Y14814D03*
X506644Y17114D03*
X506657Y27936D03*
X497723Y30100D03*
X491380Y14714D03*
X506604Y9300D03*
X485037Y14814D03*
X501504Y16900D03*
X485037Y29949D03*
X491344D03*
X501603Y28100D03*
X515155Y-7851D03*
X538355Y9098D03*
X518502Y-1751D03*
X521848Y-7851D03*
X538355Y-1801D03*
X531888Y-1751D03*
X525195Y-1801D03*
X538403Y-9700D03*
X528155Y-7851D03*
X534534Y-7700D03*
X518502Y9114D03*
X531738D03*
X525195D03*
X521848Y14814D03*
Y29949D03*
X528191Y14714D03*
X538315Y16900D03*
X534534Y30100D03*
X515155Y29949D03*
Y14814D03*
X534534D03*
X528155Y29949D03*
X538415Y28100D03*
X488384Y35999D03*
X501492Y54700D03*
X497723Y52614D03*
Y67900D03*
X501544Y46898D03*
X511809Y46914D03*
X491344Y67749D03*
X506657Y65736D03*
X501570Y65950D03*
X481691Y36049D03*
X495077D03*
X506644Y54914D03*
X494927Y46914D03*
X485037Y52614D03*
X481691Y46914D03*
X511809Y36049D03*
X485037Y67749D03*
X488384Y46914D03*
X506603Y35800D03*
X506592Y47000D03*
X501544Y35999D03*
X511809Y84714D03*
X501544Y84698D03*
X494927Y84714D03*
X506670Y73550D03*
X481691Y84714D03*
X488384D03*
X501520Y92500D03*
X506620Y84700D03*
X511809Y73849D03*
X488384Y73799D03*
X481691Y73849D03*
X506644Y92714D03*
X491380Y90314D03*
X497723Y90414D03*
X485037D03*
X495077Y73849D03*
X501544Y73799D03*
X518502Y36049D03*
Y46914D03*
X521848Y67749D03*
X531888Y36049D03*
X538355Y35999D03*
X534534Y52614D03*
X531738Y46914D03*
X525195Y35999D03*
X515155Y67749D03*
Y52614D03*
X521848D03*
X534534Y67900D03*
X538381Y65950D03*
X528155Y67749D03*
X538355Y46898D03*
X538304Y54700D03*
X525195Y46914D03*
X515155Y90414D03*
X534534D03*
X528191Y90314D03*
X521848Y90414D03*
X518502Y73849D03*
Y84714D03*
X531738D03*
X525195D03*
X538355Y84698D03*
X538331Y92500D03*
X531888Y73849D03*
X525195Y73799D03*
X538355D03*
X512024Y104314D03*
X497723Y109564D03*
X501544Y113114D03*
X506670Y112865D03*
X501570Y105265D03*
X491430Y109564D03*
X506657Y105051D03*
X488634Y104314D03*
X495077D03*
X514820Y109564D03*
X521113D03*
X528191Y109914D03*
X534534Y109564D03*
X538355Y113114D03*
X531738Y104314D03*
X525134D03*
X538381Y105265D03*
X518467Y104314D03*
X511592Y206447D03*
Y210346D03*
Y218147D03*
X486812Y214247D03*
Y218147D03*
X498350Y209900D03*
X501452Y212296D03*
X480052Y214247D03*
Y206447D03*
X486812Y210346D03*
X508212Y212296D03*
X518352Y218147D03*
Y206445D03*
X538631Y210346D03*
Y214247D03*
Y206447D03*
X528491Y208397D03*
X525111Y218147D03*
X528491Y216196D03*
X535251Y204496D03*
X525111Y206447D03*
X531871D03*
X521731Y208397D03*
X511592Y241547D03*
Y249347D03*
X486812Y245447D03*
X494692Y247396D03*
X483432Y251296D03*
X501452Y247396D03*
X480052Y237647D03*
X508212Y239596D03*
X498072Y233746D03*
X486812D03*
Y229847D03*
X494692Y235696D03*
X504832Y229847D03*
X486812Y225947D03*
X498072Y222047D03*
Y225947D03*
X486812Y222047D03*
Y237647D03*
X480052Y233746D03*
X504832Y241547D03*
X480052D03*
X486812D03*
X494692Y243496D03*
X483432D03*
X504832Y245447D03*
X501452Y223996D03*
X508212Y231797D03*
Y220096D03*
Y223996D03*
X483432Y235696D03*
Y223996D03*
X494692Y251296D03*
X501452Y274696D03*
X508212Y278596D03*
X484552Y268847D03*
X494692Y255196D03*
X486812Y257147D03*
X504832Y253247D03*
X487932Y278596D03*
Y274696D03*
X494692Y278596D03*
X501452Y266896D03*
Y259096D03*
X483432D03*
X481172Y274696D03*
Y278596D03*
X508212Y270796D03*
X494692D03*
X480052Y261047D03*
X518352Y229847D03*
X521731Y231797D03*
Y235696D03*
Y247396D03*
Y220096D03*
X538631Y225947D03*
Y222047D03*
Y237647D03*
X528491Y247396D03*
Y243496D03*
X538631Y249347D03*
X535251Y235696D03*
X528491Y227896D03*
Y235696D03*
Y220096D03*
X535251Y247396D03*
Y251296D03*
Y239596D03*
X531871Y222047D03*
X525111Y237647D03*
X514972Y247396D03*
Y227896D03*
Y235696D03*
Y239596D03*
Y223996D03*
X535251Y259096D03*
X531871Y261047D03*
X514972Y270796D03*
Y278596D03*
X525111Y253247D03*
X518352D03*
X528491Y274696D03*
X531871Y268847D03*
Y276646D03*
X535251Y266896D03*
X525111Y280547D03*
X521731Y266896D03*
Y259096D03*
Y274696D03*
X538631Y257147D03*
X504832Y307847D03*
X525111Y315647D03*
X494692Y294196D03*
X501452Y290296D03*
Y282496D03*
X491312Y292245D03*
Y300047D03*
X508212Y290296D03*
Y294196D03*
X511592Y307847D03*
Y284447D03*
X481172Y309797D03*
X494692D03*
X481172Y301996D03*
X487932Y309797D03*
X498072Y303947D03*
X487932Y282496D03*
X484552Y300047D03*
Y292245D03*
X494692Y286396D03*
X501452Y298096D03*
X481172Y290296D03*
X508212Y329296D03*
X487932Y317596D03*
X504832Y319547D03*
X484552Y323446D03*
X508212Y317596D03*
Y325396D03*
X491312Y339047D03*
X494692Y337096D03*
X511592Y327347D03*
Y339047D03*
Y331247D03*
Y335147D03*
Y315647D03*
Y323446D03*
X508212Y313696D03*
X481172D03*
X494692Y340996D03*
X504832Y331247D03*
X508212Y337096D03*
Y333196D03*
X504832Y335147D03*
X501452Y333196D03*
X504832Y339047D03*
X501452Y340996D03*
X504832Y315647D03*
X498072Y319547D03*
X504832Y323446D03*
X498072Y327347D03*
X491312Y331247D03*
X511592Y319547D03*
X538631Y311747D03*
X535251Y290296D03*
X514972Y301996D03*
Y290296D03*
Y286396D03*
Y294196D03*
X525111Y284447D03*
X531871Y288347D03*
Y292245D03*
X528491Y294196D03*
X525111Y300047D03*
X531871D03*
X521731Y301996D03*
X528491Y286396D03*
Y298096D03*
X535251Y294196D03*
X538631Y292245D03*
Y288347D03*
Y284447D03*
X531871Y303947D03*
X535251Y301996D03*
X531871Y311747D03*
Y307847D03*
X535251Y309797D03*
X514972Y333196D03*
Y321496D03*
Y317596D03*
Y329296D03*
Y325396D03*
Y337096D03*
X518352Y319547D03*
Y323446D03*
Y315647D03*
X521731Y317596D03*
Y325396D03*
X518352Y327347D03*
Y339047D03*
X531871Y335147D03*
X525111D03*
X528491Y337096D03*
X531871Y327347D03*
X535251Y329296D03*
X538631Y335147D03*
Y339047D03*
X528491Y317596D03*
X531871Y319547D03*
X535251Y321496D03*
X538631Y319547D03*
X504832Y342947D03*
X491312Y370247D03*
X498072Y366347D03*
X494692Y372197D03*
X504832Y366347D03*
X501452Y368296D03*
X487932D03*
X484552Y362447D03*
X498072D03*
X491312D03*
X494692Y360496D03*
X487932D03*
X501452Y344896D03*
X504832Y354647D03*
X494692Y344896D03*
Y348796D03*
X491312Y350747D03*
Y366347D03*
X487932Y372197D03*
X484552Y370247D03*
X481172Y372197D03*
X484552Y366347D03*
X487932Y364396D03*
X494692D03*
X501452D03*
X491312Y358547D03*
X498072Y350747D03*
Y346847D03*
X501452Y360496D03*
X498072Y342947D03*
X491312Y346847D03*
X494692Y356596D03*
X498072Y358547D03*
Y354647D03*
X481172Y344896D03*
Y360496D03*
X484552Y346847D03*
X508212Y352696D03*
Y360496D03*
X504832Y346847D03*
Y358547D03*
X501452Y356596D03*
Y348796D03*
Y352696D03*
X511592Y370247D03*
X481172Y352696D03*
X484552Y393647D03*
X481172Y391696D03*
X484552Y385847D03*
X498072Y393647D03*
X494692Y391696D03*
X491312Y385847D03*
X498072D03*
X508212Y387796D03*
X501452Y391696D03*
Y395597D03*
X491312Y389747D03*
X504832Y381947D03*
Y378047D03*
X501452Y379996D03*
X481172Y395596D03*
X511592Y378047D03*
Y397546D03*
X491312Y378047D03*
X484552D03*
X481172Y379996D03*
X487932Y376096D03*
X491312Y381947D03*
Y374146D03*
X498072Y397546D03*
X487932Y403396D03*
Y399496D03*
X491312Y397546D03*
X487932Y395597D03*
X514972Y372197D03*
Y356596D03*
X521731Y360496D03*
Y356596D03*
Y348796D03*
X518352Y342947D03*
Y362447D03*
X521731Y372197D03*
X518352Y370247D03*
X525111Y354647D03*
X531871Y346847D03*
X535251Y356596D03*
X538631Y366347D03*
X528491Y364396D03*
X525111Y342947D03*
X514972Y403396D03*
Y379996D03*
X531871Y374146D03*
X521731Y399496D03*
X518352Y397546D03*
Y389747D03*
X535251Y383896D03*
X525111Y381947D03*
X538631Y393647D03*
Y378047D03*
X528491Y403396D03*
X531871Y401447D03*
Y389747D03*
X525111Y393647D03*
X484552Y405347D03*
X538750Y406200D03*
X511712Y495800D03*
X488384Y495887D03*
X494777D03*
X491380Y493744D03*
X506644Y490867D03*
X501560D03*
X497723Y493494D03*
X506620Y510100D03*
X506644Y518114D03*
X501544Y510098D03*
X485037Y515814D03*
X481691Y510114D03*
X491380Y515714D03*
X511809Y510114D03*
X497723Y515814D03*
X494927Y510114D03*
X488384D03*
X501520Y517900D03*
X506644Y498867D03*
X501560D03*
X514755Y491044D03*
X521048Y491144D03*
X538370Y490609D03*
X528241Y490944D03*
X534534Y490794D03*
X515155Y515814D03*
X530792Y495787D03*
X524595D03*
X517892Y495800D03*
X534534Y515814D03*
X528191Y515714D03*
X531738Y510114D03*
X525195D03*
X538355Y510098D03*
X538331Y517900D03*
X521848Y515814D03*
X518502Y510114D03*
X538370Y498609D03*
X506670Y536750D03*
X501570Y529150D03*
X506657Y528936D03*
X501544Y536999D03*
X511809Y547914D03*
Y537049D03*
X491380Y553514D03*
X497723Y553614D03*
X485037D03*
X506620Y547900D03*
X501544Y547898D03*
X481691Y547914D03*
X494927D03*
X488384D03*
X481691Y537049D03*
X491344Y530949D03*
X488384Y536999D03*
X495077Y537049D03*
X497723Y531100D03*
X485037Y530949D03*
Y568749D03*
X481691Y574849D03*
Y585714D03*
X501544Y585698D03*
Y574799D03*
X506657Y566736D03*
X501570Y566950D03*
X506670Y574550D03*
X506620Y585700D03*
X488384Y585714D03*
X511809D03*
Y574849D03*
X494927Y585714D03*
X491344Y568749D03*
X501520Y555700D03*
X506644Y555914D03*
X497723Y568900D03*
X488384Y574799D03*
X495077Y574849D03*
X515155Y553614D03*
Y530949D03*
X534534Y531100D03*
X531888Y537049D03*
X528155Y530949D03*
X525195Y536999D03*
X538355D03*
X538381Y529150D03*
X525195Y547914D03*
X531738D03*
X538355Y547898D03*
X534534Y553614D03*
X528191Y553514D03*
X518502Y547914D03*
X521848Y553614D03*
X518502Y537049D03*
X521848Y530949D03*
X515155Y568749D03*
X538331Y555700D03*
X518502Y585714D03*
Y574849D03*
X521848Y568749D03*
X538355Y585698D03*
Y574799D03*
X538381Y566950D03*
X531738Y585714D03*
X525195D03*
X534534Y568900D03*
X525195Y574799D03*
X528155Y568749D03*
X531888Y574849D03*
X525195Y612599D03*
X518502Y612649D03*
X538355Y612599D03*
X531888Y612649D03*
X501544Y612599D03*
X495077Y612649D03*
X488384Y612599D03*
X511809Y612649D03*
X497723Y591414D03*
X486250Y591020D03*
X491380Y591314D03*
X501520Y593500D03*
X506644Y593714D03*
X501570Y604750D03*
X506657Y604536D03*
X491344Y606549D03*
X497723Y606700D03*
X485037Y607230D03*
X506670Y612350D03*
X480950Y612430D03*
X515155Y606549D03*
Y591414D03*
X521848D03*
Y606549D03*
X534534Y591414D03*
X528191Y591314D03*
X538331Y593500D03*
X538381Y604750D03*
X534534Y606700D03*
X528155Y606549D03*
X562006Y9114D03*
X568549D03*
X555313D03*
X548620D03*
X571345Y-7700D03*
X551966Y-7851D03*
X564966D03*
X558659D03*
X562006Y-1801D03*
X555313Y-1751D03*
X568699D03*
X548620D03*
X543503Y-2000D03*
X543468Y-9864D03*
X543455Y17114D03*
X564992Y14714D03*
X543415Y9300D03*
X558659Y14814D03*
Y29949D03*
X551966Y14814D03*
Y29949D03*
X564966D03*
X571345Y14814D03*
Y30100D03*
X543468Y27936D03*
X575166Y9098D03*
X602163Y16999D03*
X575214Y-9700D03*
X575166Y-1801D03*
X580279Y-9864D03*
X580314Y-2000D03*
X588777Y-7851D03*
X598817Y-9901D03*
X595470Y-7851D03*
X592124Y-1751D03*
X598817D03*
X585431D03*
X602163Y-9901D03*
X598817Y9157D03*
X592124Y9114D03*
X585431D03*
X575182Y16900D03*
X575192Y28100D03*
X580192Y9300D03*
X588777Y29949D03*
X580279Y27936D03*
X595470Y29949D03*
Y14814D03*
X598817Y27899D03*
X588777Y14814D03*
X580266Y17114D03*
X562006Y46914D03*
X551966Y52614D03*
X565352Y52864D03*
X548620Y46914D03*
Y36049D03*
X558659Y52614D03*
X568699Y36049D03*
X555313D03*
X562006Y35999D03*
X551966Y67749D03*
X564966D03*
X571345Y52614D03*
Y67900D03*
X558659Y67749D03*
X568549Y46914D03*
X555313D03*
X543468Y65736D03*
X543404Y47000D03*
X543415Y35800D03*
X543455Y54914D03*
Y92714D03*
X548620Y84714D03*
X568549D03*
X555313D03*
X562006D03*
X543481Y73550D03*
X543431Y84700D03*
X548620Y73849D03*
X568699D03*
X562006Y73799D03*
X555313Y73849D03*
X558659Y90414D03*
X551966D03*
X571345D03*
X575166Y46898D03*
Y35999D03*
X575192Y65950D03*
X585431Y46914D03*
X595470Y52614D03*
X588777D03*
X585431Y36049D03*
X592124D03*
X598817D03*
Y46957D03*
X592124Y46914D03*
X598817Y65699D03*
X595470Y67749D03*
X588777D03*
X580266Y54914D03*
X580192Y35750D03*
X580279Y65736D03*
X602163Y65699D03*
X592124Y84714D03*
X585431D03*
X598817Y84757D03*
X580242Y84700D03*
X580266Y92714D03*
X588777Y90414D03*
X602163Y92599D03*
X575166Y73799D03*
X575142Y92500D03*
X575166Y84698D03*
X595470Y90414D03*
X585431Y73849D03*
X592124D03*
X598817D03*
X580292Y73550D03*
X548620Y104314D03*
X555313D03*
X558659Y110014D03*
X551966D03*
X543481Y112865D03*
X543468Y105051D03*
X602100Y109600D03*
X555531Y216196D03*
X557000Y206800D03*
X548771Y212296D03*
X552151Y214247D03*
X547800Y201400D03*
X545391Y210346D03*
X552151Y218147D03*
Y225947D03*
X558911Y222047D03*
X552151Y233746D03*
X548771Y235696D03*
X558911Y229847D03*
X552151D03*
X562591Y220096D03*
X564084Y235685D03*
X545391Y225947D03*
Y222047D03*
Y233746D03*
X542011Y239596D03*
Y247396D03*
X552151Y241547D03*
X548771Y239596D03*
X552151Y249347D03*
X555531Y247396D03*
X562591Y251296D03*
X548771Y243496D03*
X562591D03*
X572930Y232750D03*
Y228130D03*
X552151Y257147D03*
X562591Y255196D03*
X548771D03*
X573200Y262600D03*
X573100Y258600D03*
X548771Y266896D03*
X558911Y264947D03*
X563800Y275900D03*
X559211Y280547D03*
X548771Y278596D03*
X558911Y272747D03*
X555531Y274696D03*
X564500Y264800D03*
Y268800D03*
X552151Y261047D03*
X545391Y272747D03*
Y280547D03*
Y264947D03*
Y268847D03*
X542011Y274696D03*
X580360Y234590D03*
Y230060D03*
X545391Y307847D03*
X555831Y309797D03*
Y305896D03*
X548771Y309797D03*
X555831Y298096D03*
X552151Y284447D03*
X548771Y286396D03*
X552151Y288347D03*
Y296147D03*
X558145Y286727D03*
X545391Y296147D03*
Y288347D03*
Y292245D03*
Y300047D03*
X542011Y294196D03*
Y298096D03*
X545391Y303947D03*
X548771Y313696D03*
X561971Y317320D03*
X548771Y325396D03*
X558911Y335147D03*
X555531Y333196D03*
X562591D03*
X548771Y340996D03*
X561966Y325502D03*
X559211Y319547D03*
X552151Y323446D03*
X545391Y319547D03*
X542011Y321496D03*
X545391Y335147D03*
Y331247D03*
Y315647D03*
X552151Y350747D03*
X558911Y342947D03*
X559212Y370247D03*
X548771Y368296D03*
X562591Y352696D03*
Y344896D03*
X563200Y356596D03*
X545391Y354647D03*
Y346847D03*
X542011Y368296D03*
X545391Y366347D03*
Y358547D03*
X542011Y360496D03*
Y348796D03*
X559212Y374146D03*
X555531Y387797D03*
X559212Y381947D03*
Y393647D03*
X552151Y378047D03*
X545391Y397546D03*
Y385847D03*
X542011Y376096D03*
X573867Y459903D03*
X575614Y461694D03*
X584076Y443828D03*
X588285Y448306D03*
X586136Y446335D03*
X558659Y493444D03*
X551366Y490744D03*
X543455Y490909D03*
X555313Y510114D03*
X548492Y495800D03*
X554792Y495887D03*
X543431Y510100D03*
X543455Y518114D03*
X551966Y515814D03*
X548620Y510114D03*
X543455Y498909D03*
X568549Y510114D03*
X562006D03*
X571345Y515814D03*
X558659D03*
X582912Y468948D03*
X581032Y467202D03*
X575166Y510098D03*
X575142Y517900D03*
X580266Y518114D03*
X580242Y510100D03*
X598817Y510157D03*
X595470Y515814D03*
X588777D03*
X602163Y517999D03*
X592124Y510114D03*
X585431D03*
X543468Y528936D03*
X543481Y536750D03*
X543431Y547900D03*
X548620Y547914D03*
X551966Y553614D03*
X548620Y537049D03*
X551966Y530949D03*
X558659D03*
X555313Y537049D03*
X562006Y536999D03*
X564966Y530949D03*
X568699Y537049D03*
X571345Y553614D03*
Y531100D03*
X558659Y553614D03*
X555313Y547914D03*
X568549D03*
X562006D03*
X543455Y555914D03*
X571345Y568900D03*
X564966Y568749D03*
X562006Y574799D03*
X555313Y585714D03*
Y574849D03*
X558659Y568749D03*
X568549Y585714D03*
X562006D03*
X568699Y574849D03*
X551966Y568749D03*
X548620Y574849D03*
Y585714D03*
X543481Y574550D03*
X543431Y585700D03*
X543468Y566736D03*
X575166Y547898D03*
X575192Y529150D03*
X575166Y536999D03*
X598817Y547957D03*
X592124Y547914D03*
X595470Y530949D03*
X580242Y547900D03*
X580279Y528936D03*
X580292Y536750D03*
X592124Y537049D03*
X588777Y530949D03*
X598817Y528899D03*
Y537049D03*
X602163Y528899D03*
X585431Y547914D03*
Y537049D03*
X588777Y553614D03*
X595470D03*
X580279Y566736D03*
X585431Y574849D03*
Y585714D03*
X598817Y585757D03*
Y574849D03*
Y566699D03*
X592124Y585714D03*
X595470Y568749D03*
X588777D03*
X592124Y574849D03*
X575142Y555700D03*
X575192Y566950D03*
X575166Y585698D03*
Y574799D03*
X580266Y555914D03*
X580292Y574550D03*
X580242Y585700D03*
X575166Y612599D03*
X585431Y612649D03*
X592124D03*
X598817D03*
X555313D03*
X562006Y612599D03*
X568699Y612649D03*
X548620D03*
X571345Y591414D03*
X558659D03*
X571345Y606700D03*
X558659Y606549D03*
X564966D03*
X551966D03*
Y591414D03*
X543455Y593714D03*
X543468Y604536D03*
X543481Y612350D03*
X580292D03*
X580266Y593714D03*
X595470Y591414D03*
X588777D03*
X598817Y604499D03*
X595470Y606549D03*
X588777D03*
X575192Y604750D03*
X575142Y593500D03*
X602163Y593599D03*
Y604499D03*
X580279Y604536D03*
X620092Y13078D03*
X620192Y31978D03*
Y-5822D03*
X647317Y-1310D03*
X660676Y-2600D03*
X651300Y20000D03*
X659200Y31500D03*
X651300Y17500D03*
X620070Y50878D03*
X620192Y69778D03*
X620092Y88678D03*
X663500Y48000D03*
X663700Y65600D03*
X663476Y45296D03*
X616115Y108339D03*
X622200Y112200D03*
X616167Y118627D03*
X605300Y124600D03*
X630000Y126572D03*
X624500Y129400D03*
X626900Y128300D03*
X633580Y125560D03*
X661700Y142300D03*
X636481Y124951D03*
X635951Y127419D03*
X661053Y115971D03*
X658490Y115432D03*
X650307Y115518D03*
X647809Y116121D03*
X645311Y116724D03*
X650120Y122700D03*
X660900Y123650D03*
Y126650D03*
X647120Y122700D03*
X657900Y126650D03*
Y123650D03*
X651920Y125750D03*
X656111Y121550D03*
X653111D03*
X654558Y115101D03*
X640043Y117728D03*
X639100Y124200D03*
X638800Y126700D03*
X648690Y125590D03*
X643674Y123573D03*
X644950Y125750D03*
X641950D03*
X642899Y117112D03*
X632500Y238500D03*
Y235000D03*
X632692Y248172D03*
X632532Y241717D03*
X630200Y248100D03*
X633308Y263808D03*
X662800Y248600D03*
X643500Y272262D03*
X659900Y256900D03*
Y269200D03*
X652000Y284500D03*
X663200Y298600D03*
X644800Y292150D03*
X654500Y298600D03*
X652100Y288300D03*
X639045Y299555D03*
X639100Y309500D03*
X649000Y339400D03*
X638790Y329500D03*
X639350Y339980D03*
X639100Y319500D03*
X655900Y307700D03*
X656300Y312300D03*
X660700Y307700D03*
X655900Y316500D03*
X656000Y329800D03*
X655900Y320500D03*
X656000Y325100D03*
X660900Y329800D03*
X664100Y348000D03*
X648800D03*
X658900D03*
X662936Y367171D03*
X659936Y364171D03*
X662936D03*
X654000Y348000D03*
X634200Y436800D03*
X637300Y437200D03*
X625430Y490100D03*
X607012Y465997D03*
X623660Y466746D03*
X632113Y496892D03*
X619392Y514700D03*
X656900Y482290D03*
X649600Y492400D03*
X660500Y492000D03*
X652000Y513900D03*
X655000D03*
X661500D03*
X658500D03*
X620192Y532978D03*
X618892Y555800D03*
X618292Y574300D03*
X651750Y584150D03*
X653100Y587000D03*
X618192Y593600D03*
X620033Y608878D03*
X660230Y598170D03*
X674300Y9847D03*
X671800D03*
X669300D03*
X673900Y23100D03*
X671400D03*
X668900D03*
X690000Y15300D03*
X683800Y24856D03*
X670430Y29253D03*
X684126Y28137D03*
X681426D03*
X716858Y-14448D03*
X717720Y23279D03*
X715114Y26395D03*
X704500Y26300D03*
X700500Y26600D03*
X714337Y7852D03*
Y5352D03*
Y2852D03*
X718555Y-16147D03*
X666500Y48000D03*
X665100Y68600D03*
X668100D03*
X666700Y65600D03*
X684904Y39943D03*
X678020Y69870D03*
X678300Y92630D03*
Y95130D03*
X675630Y94988D03*
X681300Y95130D03*
Y92630D03*
X684300D03*
X687400Y93900D03*
X673830Y83050D03*
X676430D03*
X676500Y80500D03*
X673900D03*
X674010Y77970D03*
X676610D03*
X692200Y83800D03*
X695000Y67000D03*
X699880Y66840D03*
X724200Y64730D03*
X722460Y69550D03*
X713680Y60910D03*
X700360Y72160D03*
X694910Y72220D03*
X713050Y63650D03*
X710440Y63710D03*
X704880Y66750D03*
X697747Y72184D03*
X723700Y67400D03*
X713620Y58270D03*
X715800Y59490D03*
Y57000D03*
X713590Y53260D03*
X713610Y55730D03*
X700640Y69500D03*
X703120Y69380D03*
X702380Y66840D03*
X697440Y66900D03*
X700904Y38439D03*
X699800Y89100D03*
X713830Y82730D03*
X692000Y45000D03*
Y48500D03*
X697500D03*
Y45000D03*
X701525Y35610D03*
X664700Y142800D03*
X675600Y144900D03*
Y150000D03*
X679900Y128200D03*
X682400Y127085D03*
X684900D03*
X673566Y116724D03*
X676494Y116940D03*
X668665Y118185D03*
X671249Y118744D03*
X677896Y119093D03*
X674896D03*
X715505Y155076D03*
X720700Y154750D03*
X725650Y155000D03*
X691583Y200124D03*
X689033D03*
X686533D03*
Y196624D03*
X689033D03*
X691583D03*
X715550Y158880D03*
X705550D03*
X710550D03*
X709200Y198700D03*
X720369Y205199D03*
X716557Y198557D03*
X692513Y213800D03*
X692673Y206200D03*
X692500Y210100D03*
X690861Y211917D03*
Y215717D03*
X692400Y218100D03*
X690861Y204317D03*
Y208117D03*
X706500Y217400D03*
Y214900D03*
X719315Y239104D03*
X669900Y224000D03*
X672500Y224100D03*
X678454Y278000D03*
X675380Y246340D03*
X678000Y246400D03*
X668100Y232200D03*
X667240Y246600D03*
X672530Y246300D03*
X677400Y232300D03*
X674300Y232200D03*
X675200Y224100D03*
X667600Y250200D03*
X688643Y225980D03*
X688388Y231280D03*
X678400Y224100D03*
X690380Y252240D03*
X690939Y266630D03*
X693530Y261240D03*
X690660Y264000D03*
X690704Y271324D03*
X671100Y232200D03*
X701800Y246480D03*
X669750Y246350D03*
X710572Y244773D03*
X719360Y241504D03*
X710627Y242061D03*
X702000Y243900D03*
X722050Y221150D03*
X707653Y226347D03*
X718300Y227400D03*
X700900Y264100D03*
X694361Y223317D03*
Y220817D03*
X690861D03*
Y223317D03*
X672300Y269200D03*
X672200Y256800D03*
X706561Y219917D03*
X719900Y269300D03*
X725500Y279300D03*
X725300Y269400D03*
X719600Y279400D03*
X704175Y287275D03*
X704214Y290775D03*
X680000Y281900D03*
X672150Y288350D03*
X695300Y338100D03*
X695400Y328000D03*
X684100Y338200D03*
X695400Y318000D03*
X695800Y308000D03*
X696088Y297069D03*
X704500Y293800D03*
X707130Y310150D03*
X718200Y295000D03*
X706300Y318400D03*
X678200Y307800D03*
X672700Y307700D03*
X667100D03*
X678100Y324800D03*
X672200Y329800D03*
X678100Y329600D03*
X666900Y329700D03*
X678200Y313700D03*
Y319300D03*
X679000Y348000D03*
X688600Y365100D03*
X671936Y367171D03*
X665936Y370171D03*
X684900Y348000D03*
X674600D03*
X671936Y370171D03*
X665936Y367171D03*
X668936Y370171D03*
Y367171D03*
X665936Y364171D03*
X668936D03*
X669093Y348120D03*
X671936Y373171D03*
X668936D03*
X670300Y375600D03*
X713900Y347800D03*
X698560Y374430D03*
X713900Y342800D03*
Y352800D03*
Y350300D03*
Y345300D03*
X690040Y412030D03*
X685600Y432500D03*
X690600D03*
Y437500D03*
X703876Y414949D03*
X705850Y417093D03*
X710600Y420267D03*
X710423Y417423D03*
X708346Y415859D03*
X708011Y419078D03*
X712980Y417900D03*
X713493Y420449D03*
X723748Y499091D03*
X701255Y521538D03*
X676900Y489400D03*
X666500Y487600D03*
Y484600D03*
X669500D03*
Y481600D03*
X664610Y512810D03*
X685050Y503970D03*
X704500Y512850D03*
X716267Y522020D03*
X703028Y495600D03*
X709028D03*
X706028D03*
X703028Y492600D03*
X706028D03*
X700500Y512850D03*
X701200Y524250D03*
X686200Y511700D03*
X680000Y511800D03*
X686375Y527778D03*
X674200Y588900D03*
X690100Y575860D03*
X689193Y573493D03*
X693126Y581380D03*
X671599Y573493D03*
X671791Y588920D03*
X674099Y573493D03*
X669099D03*
X668891Y588900D03*
X713650Y540750D03*
X715650Y542250D03*
Y545250D03*
X713650Y546750D03*
X708000Y553250D03*
X720200Y551750D03*
X715650Y551250D03*
X696000Y553250D03*
X715650Y548250D03*
X713650Y549750D03*
X723200Y551750D03*
X699000Y553250D03*
X702000D03*
X705000D03*
X713650Y543750D03*
X723200Y554750D03*
X706500Y555750D03*
X703500D03*
X700500D03*
X720200Y554750D03*
X709500Y555750D03*
X712600Y571900D03*
X716300Y569400D03*
X707500Y587800D03*
X691900Y531350D03*
Y534850D03*
X697500Y534750D03*
Y531250D03*
X725173Y598171D03*
X724106Y609550D03*
X721106D03*
X708900Y589850D03*
X706100D03*
X732600Y3600D03*
X755500Y8700D03*
X753600Y-4300D03*
X736715Y33487D03*
X734201Y33510D03*
X726250Y23550D03*
X731457Y8471D03*
X732335Y6000D03*
X786414Y-9650D03*
X779771Y9114D03*
X773228D03*
Y-1801D03*
X779921Y-1751D03*
X776188Y-7851D03*
X769881Y-9901D03*
X782567Y-7700D03*
X786388Y9098D03*
Y-1801D03*
X786414Y28150D03*
X769881Y27899D03*
X782567Y14814D03*
Y30100D03*
X769881Y16839D03*
X776224Y14714D03*
X776188Y29949D03*
X786364Y16900D03*
X736631Y36122D03*
X736655Y38531D03*
X731887Y40916D03*
X734155Y38531D03*
X734131Y36122D03*
X731843Y43571D03*
X756100Y36200D03*
X755500Y46700D03*
X737800Y55800D03*
X751708Y73800D03*
X755500Y84361D03*
X786388Y35999D03*
X786364Y54700D03*
X786388Y46898D03*
X773228Y46914D03*
X779771D03*
X776188Y67749D03*
X769881Y66000D03*
X782567Y67900D03*
Y52614D03*
X769881Y54839D03*
X779921Y35983D03*
X773228D03*
X776224Y52514D03*
X769881Y92500D03*
X773228Y84714D03*
X779771D03*
X776224Y90314D03*
X782567Y90414D03*
X779921Y73849D03*
X773228Y73799D03*
X786414Y65950D03*
X786388Y73799D03*
X786364Y92500D03*
X786388Y84698D03*
X730600Y154984D03*
X746000Y150500D03*
X740718Y150957D03*
X769100Y102900D03*
X758400Y156200D03*
X747600Y161450D03*
X740650Y164800D03*
X735600Y164900D03*
X740650Y158800D03*
X754726Y205037D03*
X752226D03*
X749726D03*
X754726Y207537D03*
X752226D03*
X749726D03*
X742937Y218574D03*
X758400Y159200D03*
X774582Y212033D03*
X770200Y208600D03*
X775171Y218616D03*
X787371Y215216D03*
Y217716D03*
X777700Y218600D03*
X727969Y236770D03*
X736612Y237908D03*
X727997Y239195D03*
X736625Y240308D03*
X742897Y229573D03*
X746303Y243122D03*
X746321Y240569D03*
X760304Y235827D03*
X768560Y244055D03*
X769019Y276400D03*
X762616Y270113D03*
X761480Y242720D03*
X731100Y269300D03*
Y279300D03*
X787371Y247216D03*
Y249716D03*
X775232Y221133D03*
X777700Y250600D03*
X775232Y223633D03*
X775171Y250616D03*
X775232Y253133D03*
Y255633D03*
X787371Y279216D03*
X774347Y339983D03*
X762760Y339500D03*
X727300Y302910D03*
X727474Y338363D03*
Y335363D03*
X732474D03*
Y338363D03*
X756114Y316209D03*
X729974Y338363D03*
Y335363D03*
X771278Y307918D03*
X762842Y302434D03*
X765730Y335064D03*
X777700Y282600D03*
X775232Y287633D03*
Y285133D03*
X775171Y282616D03*
X787371Y281716D03*
Y311216D03*
X777800Y314700D03*
X775171Y314616D03*
X787371Y313716D03*
X775232Y317133D03*
Y319633D03*
X727474Y344663D03*
Y367463D03*
X732474D03*
X729974D03*
X727474Y364863D03*
X732474D03*
X729974D03*
Y347663D03*
X727474D03*
X732474D03*
Y344663D03*
X727574Y373463D03*
X732574D03*
X730074D03*
X732574Y376063D03*
X730074D03*
X729974Y344663D03*
X731100Y362300D03*
X772443Y371976D03*
X760140Y362819D03*
X758952Y384100D03*
X763333Y400212D03*
X772300Y403520D03*
X775171Y346616D03*
X787371Y343216D03*
Y345716D03*
X775232Y349133D03*
X777600Y346600D03*
X775232Y351633D03*
X787321Y374916D03*
Y377316D03*
X775182Y383633D03*
Y381133D03*
X778000Y378700D03*
X775121Y378616D03*
X749640Y431797D03*
X728940Y457806D03*
X775417Y435799D03*
X777979Y436516D03*
X752496Y515974D03*
X732522Y526808D03*
Y524308D03*
X750518Y522108D03*
X734922Y526808D03*
X776224Y515714D03*
X779771Y510114D03*
X773228D03*
X769881Y517900D03*
X782567Y515814D03*
X786388Y510098D03*
X786364Y517900D03*
X732442Y529300D03*
X734842D03*
X736300Y541500D03*
X756000Y537000D03*
X737400Y529400D03*
X734900Y531800D03*
X732400D03*
X726200Y551750D03*
X754910Y556400D03*
X726200Y554750D03*
X727400Y571300D03*
X755000Y574800D03*
X752500Y585150D03*
X727106Y586550D03*
X773228Y536999D03*
X763677Y547783D03*
X776188Y530949D03*
X782567Y531100D03*
X769818Y529200D03*
X779921Y537049D03*
X782567Y553614D03*
X773228Y547914D03*
X779771D03*
X776224Y553514D03*
X786388Y536999D03*
X786414Y529150D03*
X786388Y547898D03*
X786364Y555700D03*
X769881D03*
X773228Y574799D03*
X782567Y568900D03*
X769700Y566900D03*
X776188Y568749D03*
X779921Y574849D03*
X773228Y585714D03*
X779771D03*
X786388Y574799D03*
Y585698D03*
X786414Y566950D03*
X779921Y612649D03*
X773228Y612599D03*
X786388D03*
X755000Y614500D03*
X727000Y606600D03*
X766600Y590700D03*
X769700Y604900D03*
X776188Y606549D03*
X782567Y606700D03*
Y591414D03*
X776224Y591314D03*
X786414Y604750D03*
X786364Y593500D03*
X803346Y-1751D03*
X810039Y-1801D03*
X791514Y-2050D03*
X791501Y-9864D03*
X812999Y-7851D03*
X806692D03*
X799999D03*
X816582Y9114D03*
X796653D03*
X791464Y9100D03*
X810039Y9114D03*
X803346D03*
X816732Y-1751D03*
X796653D03*
X799999Y29949D03*
X806692D03*
X812999D03*
X791501Y27936D03*
X791488Y17114D03*
X799999Y14814D03*
X813035Y14714D03*
X806692Y14814D03*
X828275Y9100D03*
X833464Y9114D03*
X840157D03*
X819378Y-7700D03*
X823199Y9098D03*
Y-1801D03*
X823225Y-9650D03*
X828312Y-9864D03*
X843503Y-7851D03*
X836810D03*
X846850Y-1801D03*
X828325Y-2050D03*
X833464Y-1751D03*
X840157D03*
X846850Y9114D03*
X819378Y14814D03*
Y30100D03*
X843503Y14814D03*
X823175Y16900D03*
X823225Y28150D03*
X828312Y27936D03*
X836810Y29949D03*
X828299Y17114D03*
X836810Y14814D03*
X843503Y29949D03*
X791488Y54914D03*
X799999Y52614D03*
X796653Y46914D03*
X791464Y46900D03*
X810039Y35999D03*
X803346Y36049D03*
X799999Y90414D03*
X791488Y92714D03*
X806692Y90414D03*
X816582Y46914D03*
X816732Y36049D03*
X799999Y67749D03*
X812999D03*
X806692D03*
X791501Y65736D03*
X803346Y46914D03*
X806692Y52614D03*
X813035Y52514D03*
X810039Y46914D03*
X791514Y35750D03*
X796653Y36049D03*
X816582Y73849D03*
X791514Y73550D03*
X796653Y73849D03*
X810039Y73799D03*
X803346Y73849D03*
X816582Y84714D03*
X813035Y90314D03*
X803346Y84714D03*
X810039D03*
X796653D03*
X791464Y84700D03*
X819378Y67900D03*
Y52614D03*
X846850Y35999D03*
X833464Y36049D03*
X840157D03*
X823225Y65950D03*
X823175Y54700D03*
X823199Y46898D03*
Y35999D03*
X828299Y54914D03*
X828275Y46900D03*
X828325Y35750D03*
X833464Y46914D03*
X836810Y52614D03*
X840157Y46914D03*
X828312Y65736D03*
X836810Y67749D03*
X843503D03*
X846850Y46914D03*
X843503Y52614D03*
X823175Y92500D03*
X823199Y84698D03*
X846850Y73799D03*
X843503Y90414D03*
X846850Y84714D03*
X828325Y73550D03*
X840157Y73849D03*
X833464D03*
X828299Y92714D03*
X836810Y90414D03*
X840157Y84714D03*
X833464D03*
X828275Y84700D03*
X819378Y90364D03*
X823199Y73799D03*
X790871Y215216D03*
Y217716D03*
X845100Y268200D03*
X847600D03*
X842600D03*
X847600Y243400D03*
X841400Y243300D03*
X847600Y238400D03*
X841400Y238300D03*
X847600Y240900D03*
X841400Y240800D03*
X789500Y231800D03*
X790900Y234000D03*
Y229700D03*
X790846Y225774D03*
X790882Y221723D03*
X790871Y247216D03*
Y249716D03*
X789471Y227742D03*
X789576Y223737D03*
X789554Y219723D03*
X790900Y253900D03*
X789432Y252000D03*
X790871Y266216D03*
X789432Y255800D03*
X790867Y257724D03*
X789432Y259800D03*
X789500Y263900D03*
X790885Y261711D03*
X790871Y279216D03*
X842600Y299900D03*
X845100D03*
X847600D03*
X845100Y331500D03*
X842600D03*
X847600D03*
X790871Y311216D03*
X789432Y284200D03*
Y288300D03*
Y292400D03*
X789400Y296200D03*
X790871Y298216D03*
X790937Y294270D03*
X790900Y290300D03*
Y286200D03*
X790871Y281716D03*
Y313716D03*
X789432Y319900D03*
Y323900D03*
X790900Y322000D03*
Y326000D03*
X790871Y330216D03*
X789500Y328000D03*
X789478Y315671D03*
X790800Y317700D03*
X847600Y363000D03*
X845100D03*
X842600D03*
X847577Y381842D03*
X789432Y348100D03*
Y352100D03*
X789597Y356105D03*
X789500Y360200D03*
X790900Y358200D03*
X790835Y354048D03*
X790867Y350024D03*
X790871Y345716D03*
Y343216D03*
Y362216D03*
X790821Y374916D03*
X790900Y389300D03*
X789500Y391300D03*
X790900Y393400D03*
Y381100D03*
X789582Y383200D03*
X790900Y385300D03*
X789500Y387300D03*
X790821Y377316D03*
X789282Y379200D03*
X816582Y510114D03*
X806692Y515814D03*
X813035Y515714D03*
X810039Y510114D03*
X791488Y518114D03*
X791464Y510100D03*
X799999Y515814D03*
X796653Y510114D03*
X803346D03*
X819378Y515764D03*
X843503Y515814D03*
X846850Y510114D03*
X823175Y517900D03*
X823199Y510098D03*
X828299Y518114D03*
X840157Y510114D03*
X833464D03*
X836810Y515814D03*
X816582Y537049D03*
Y547914D03*
X810039Y536999D03*
X806692Y530949D03*
X812999D03*
X803346Y537049D03*
X796653D03*
X799999Y530949D03*
X791501Y528936D03*
X791514Y536750D03*
X799999Y553614D03*
X810039Y547914D03*
X796653D03*
X803346D03*
X791464Y547900D03*
X806692Y553614D03*
X813035Y553514D03*
X791488Y555914D03*
X810039Y585714D03*
X806692Y568749D03*
X810039Y574799D03*
X812999Y568749D03*
X803346Y585714D03*
X796653D03*
X791514Y574550D03*
X791464Y585700D03*
X799999Y568749D03*
X796653Y574849D03*
X803346D03*
X791501Y566736D03*
X816582Y585714D03*
Y574849D03*
X819378Y553564D03*
Y531100D03*
X836810Y530949D03*
X833464Y537049D03*
X846850Y547914D03*
X833464D03*
X840157D03*
X828275Y547900D03*
X843503Y553614D03*
X836810D03*
X846850Y536999D03*
X843503Y530949D03*
X823199Y547898D03*
Y536999D03*
X823225Y529150D03*
X828325Y536750D03*
X840157Y537049D03*
X828312Y528936D03*
X819378Y568900D03*
X823175Y555700D03*
X828299Y555914D03*
X828275Y585700D03*
X823225Y566950D03*
X823199Y585698D03*
Y574799D03*
X828312Y566736D03*
X840157Y585714D03*
X833464D03*
X828325Y574550D03*
X840157Y574849D03*
X833464D03*
X836810Y568749D03*
X846850Y585714D03*
Y574799D03*
X843503Y568749D03*
X846850Y612599D03*
X840157Y612649D03*
X833464D03*
X823199Y612599D03*
X810039D03*
X803346Y612649D03*
X796653D03*
X816582D03*
X791514Y612350D03*
X806692Y606549D03*
X812999D03*
X799999D03*
X791501Y604536D03*
X806692Y591414D03*
X813035Y591314D03*
X799999Y591414D03*
X791488Y593714D03*
X819378Y606700D03*
Y591364D03*
X823225Y604750D03*
X823175Y593500D03*
X843503Y591414D03*
X828312Y604536D03*
X843503Y606549D03*
X836810D03*
X828325Y612350D03*
X836810Y591414D03*
X828299Y593714D03*
X870275Y9114D03*
X865086Y9100D03*
X860010Y9098D03*
X876968Y9114D03*
Y-1751D03*
X873621Y-7851D03*
X865123Y-9864D03*
X860036Y-9650D03*
X849810Y-7851D03*
X856189Y-7700D03*
X860010Y-1801D03*
X865136Y-2050D03*
X853543Y-1751D03*
X870275D03*
X853393Y9114D03*
X860036Y28150D03*
X859986Y16900D03*
X865110Y17114D03*
X856189Y14814D03*
X849846Y14714D03*
X873621Y14814D03*
Y29949D03*
X865123Y27936D03*
X849810Y29949D03*
X856189Y30100D03*
X896847Y-9650D03*
X910432Y-7851D03*
X883661Y-1801D03*
X880314Y-7851D03*
X886621D03*
X907086Y-1751D03*
X890354D03*
X896821Y-1801D03*
X901947Y-2050D03*
X901934Y-9864D03*
X893000Y-7700D03*
X883661Y9114D03*
X907086D03*
X896821Y9098D03*
X901897Y9100D03*
X890204Y9114D03*
X910432Y29949D03*
X896797Y16900D03*
X893000Y14814D03*
X901921Y17114D03*
X901934Y27936D03*
X893000Y30100D03*
X880314Y14814D03*
X886657Y14714D03*
X886621Y29949D03*
X880314D03*
X896847Y28150D03*
X910432Y14814D03*
X859986Y54700D03*
X870275Y36049D03*
X865136Y35750D03*
X865086Y46900D03*
X876968Y46914D03*
Y36049D03*
X873621Y67749D03*
Y52614D03*
X860010Y46898D03*
X860036Y65950D03*
X865123Y65736D03*
X849810Y67749D03*
X856189Y67900D03*
X853393Y46914D03*
X870275D03*
X865110Y54914D03*
X860010Y35999D03*
X856189Y52614D03*
X853543Y36049D03*
X849846Y52514D03*
X876968Y84714D03*
Y73849D03*
X873621Y90414D03*
X870275Y73849D03*
X853543D03*
X860010Y73799D03*
X849846Y90314D03*
X856189Y90414D03*
X865110Y92714D03*
X870275Y84714D03*
X865086Y84700D03*
X853393Y84714D03*
X860010Y84698D03*
X859986Y92500D03*
X865136Y73550D03*
X910432Y67749D03*
X893000Y67900D03*
X901934Y65736D03*
X896847Y65950D03*
X910432Y52614D03*
X890204Y46914D03*
X896821Y35999D03*
X901921Y54914D03*
X896797Y54700D03*
X883661Y35999D03*
X886621Y67749D03*
X880314D03*
X883661Y46914D03*
X880314Y52614D03*
X886657Y52514D03*
X901947Y35750D03*
X901897Y46900D03*
X896821Y46898D03*
X893000Y52614D03*
X890354Y36049D03*
X907086D03*
X883661Y73799D03*
X910432Y90414D03*
X907086Y84714D03*
X901897Y84700D03*
X907086Y46914D03*
X896821Y84698D03*
X893000Y90414D03*
X890204Y84714D03*
X896797Y92500D03*
X901921Y92714D03*
X890354Y73849D03*
X896821Y73799D03*
X901947Y73550D03*
X907086Y73849D03*
X883661Y84714D03*
X886657Y90314D03*
X880314Y90414D03*
X886657Y109884D03*
X907086Y104284D03*
X901934Y105051D03*
X896847Y105265D03*
X890204Y104284D03*
X893000Y109534D03*
X896821Y113114D03*
X901947Y112865D03*
X910432Y109984D03*
X883661Y104284D03*
X873621Y515814D03*
X876968Y510114D03*
X870275D03*
X859986Y517900D03*
X865086Y510100D03*
X860010Y510098D03*
X865110Y518114D03*
X853393Y510114D03*
X856189Y515814D03*
X849846Y515714D03*
X907000Y495800D03*
X882900Y495900D03*
X893000Y493094D03*
X886500Y493400D03*
X910432Y491044D03*
X901921Y490514D03*
X896785D03*
X901921Y498514D03*
X896785D03*
X889100Y498500D03*
X901897Y510100D03*
X893000Y515814D03*
X890204Y510114D03*
X896821Y510098D03*
X901921Y518114D03*
X896797Y517900D03*
X880314Y515814D03*
X886657Y515714D03*
X883661Y510114D03*
X910432Y515814D03*
X907086Y510114D03*
X860010Y536999D03*
X865123Y528936D03*
X873621Y530949D03*
Y553614D03*
X876968Y537049D03*
Y547914D03*
X860010Y547898D03*
X870275Y547914D03*
X853393D03*
X865086Y547900D03*
X856189Y553614D03*
X849846Y553514D03*
X870275Y537049D03*
X853543D03*
X856189Y531100D03*
X849810Y530949D03*
X865136Y536750D03*
X860036Y529150D03*
X849810Y568749D03*
X865086Y585700D03*
X860010Y585698D03*
X865136Y574550D03*
X859986Y555700D03*
X865110Y555914D03*
X860010Y574799D03*
X853393Y585714D03*
X870275D03*
X873621Y568749D03*
X876968Y574849D03*
Y585714D03*
X860036Y566950D03*
X865123Y566736D03*
X870275Y574849D03*
X853543D03*
X856189Y568900D03*
X890354Y537049D03*
X893000Y531100D03*
X896821Y536999D03*
X901934Y528936D03*
X901947Y536750D03*
X910432Y530949D03*
X907086Y537049D03*
X886621Y530949D03*
X883661Y536999D03*
X880314Y530949D03*
Y553614D03*
X886657Y553514D03*
X883661Y547914D03*
X893000Y553614D03*
X910432D03*
X890204Y547914D03*
X896821Y547898D03*
X901897Y547900D03*
X907086Y547914D03*
X880314Y568749D03*
X886621D03*
X883661Y574799D03*
Y585714D03*
X901921Y555914D03*
X896797Y555700D03*
X901934Y566736D03*
X896847Y566950D03*
X901897Y585700D03*
X890354Y574849D03*
X896821Y574799D03*
X893000Y568900D03*
X901947Y574550D03*
X896821Y585698D03*
X890204Y585714D03*
X910432Y568749D03*
X907086Y574849D03*
Y585714D03*
X890354Y612649D03*
X896821Y612599D03*
X883661D03*
X907086Y612649D03*
X870275D03*
X876968D03*
X860010Y612599D03*
X853543Y612649D03*
X859986Y593500D03*
X865110Y593714D03*
X856189Y591414D03*
X849846Y591314D03*
X860036Y604750D03*
X865123Y604536D03*
X856189Y606700D03*
X849810Y606549D03*
X865136Y612350D03*
X873621Y606549D03*
Y591414D03*
X886657Y591314D03*
X896847Y604750D03*
X901934Y604536D03*
X901947Y612350D03*
X896797Y593500D03*
X901921Y593714D03*
X893000Y591414D03*
X910432D03*
Y606549D03*
X893000Y606700D03*
X880314Y606549D03*
X886621D03*
X880314Y591414D03*
X923432Y-7851D03*
X929811Y-7700D03*
X933658Y-9650D03*
X917125Y-7851D03*
X913779Y-1751D03*
X933632Y-1801D03*
X927165Y-1751D03*
X920472Y-1801D03*
X927015Y9114D03*
X933632Y9098D03*
X913779Y9114D03*
X920472D03*
X923432Y29949D03*
X917125D03*
Y14814D03*
X929811D03*
X933608Y16900D03*
X923468Y14714D03*
X933658Y28150D03*
X929811Y30100D03*
X938745Y-9864D03*
X938758Y-2050D03*
X938708Y9100D03*
X947243Y-7851D03*
X950590Y-1751D03*
X957283Y-1843D03*
X953936Y-7851D03*
X943897Y-1751D03*
Y9114D03*
X950590D03*
X938745Y27936D03*
X938732Y17114D03*
X957283Y9300D03*
X953936Y14814D03*
Y29949D03*
X957600Y13200D03*
X957700Y32100D03*
X970800Y13200D03*
X970942Y32100D03*
X947243Y29949D03*
Y14814D03*
X933658Y65950D03*
X923432Y67749D03*
X929811Y67900D03*
X917125Y67749D03*
X920472Y35999D03*
X917125Y52614D03*
X913779Y46914D03*
Y36049D03*
X927015Y73849D03*
X913779D03*
X920472Y73799D03*
X933632D03*
X913779Y84714D03*
X920472D03*
X933608Y92500D03*
X920472Y46914D03*
X933632Y35999D03*
X927165Y36049D03*
X927015Y46914D03*
X933608Y54700D03*
X933632Y46898D03*
X929811Y52614D03*
X933632Y84698D03*
X927015Y84714D03*
X923468Y90314D03*
X929811Y90414D03*
X917125D03*
X953936Y52614D03*
X957558Y50729D03*
X938758Y35750D03*
X938708Y46900D03*
X938732Y54914D03*
X938745Y65736D03*
X950590Y36049D03*
X953936Y67749D03*
X950590Y46914D03*
X970800Y50860D03*
X947243Y67749D03*
X943897Y36049D03*
Y46914D03*
X947243Y52614D03*
X957283Y35957D03*
X960629Y89964D03*
X963976Y87392D03*
X967322Y89964D03*
X970669Y87392D03*
X938708Y84700D03*
X938732Y92714D03*
X938758Y73550D03*
X957600Y70400D03*
X970942Y69900D03*
X943897Y84714D03*
X947243Y90414D03*
X943897Y73849D03*
X950590D03*
X953886Y90414D03*
X950590Y84714D03*
X957774Y87394D03*
X957200Y73800D03*
X933658Y105265D03*
X929811Y109534D03*
X933632Y113114D03*
X923468Y109884D03*
X917125Y109984D03*
X920472Y104284D03*
X913779D03*
X927015D03*
X938758Y112865D03*
X938745Y105051D03*
X947250Y107700D03*
X950600Y112300D03*
X953800Y105000D03*
X927607Y203260D03*
Y207159D03*
X934367D03*
Y199360D03*
X930987Y201309D03*
X934367Y214960D03*
X930987Y213009D03*
X920847Y211060D03*
X927607Y214960D03*
Y211060D03*
X937747Y216909D03*
X924227D03*
Y213009D03*
X968166Y218860D03*
X951256Y194841D03*
X958026Y201309D03*
X967036Y193507D03*
X947887Y203260D03*
Y207159D03*
X944507Y213009D03*
Y201309D03*
X947887Y199360D03*
X941127D03*
Y207159D03*
X947887Y211060D03*
Y218860D03*
X941127D03*
Y214960D03*
X962526Y205210D03*
X961406Y214960D03*
Y211060D03*
Y218860D03*
X951267Y209109D03*
X958026Y213009D03*
X954647Y211060D03*
Y218860D03*
X964786Y213009D03*
Y216909D03*
Y209109D03*
X934367Y226660D03*
X924227Y236409D03*
X920847Y238360D03*
X913787Y226660D03*
X913700Y222710D03*
X913787Y238360D03*
X924227Y232509D03*
X927607Y230559D03*
Y234460D03*
X930987Y232509D03*
X934367Y234460D03*
X924227Y228610D03*
X930987Y220809D03*
X924227Y224709D03*
X937747Y232509D03*
Y236409D03*
X924227Y240309D03*
X917467D03*
X930987D03*
X924227Y248109D03*
Y244209D03*
X917467D03*
X913787Y250060D03*
X934367Y246160D03*
X927607Y250060D03*
X924227Y220809D03*
X913787Y253960D03*
X927607D03*
X934367D03*
X937747Y252009D03*
X930987D03*
X924227D03*
X917467D03*
Y259809D03*
X924227D03*
X930987D03*
X920847Y265660D03*
X930987Y275409D03*
X937747D03*
Y271509D03*
Y255909D03*
X934367Y277360D03*
X930987Y271509D03*
X934367Y273460D03*
X927607Y269560D03*
X917467Y263709D03*
X913787Y265660D03*
X924227Y267609D03*
X934367Y265660D03*
X924227Y263709D03*
Y275409D03*
X927607Y277360D03*
X920847Y273460D03*
Y269560D03*
X924227Y255909D03*
X951267Y248109D03*
X958026Y244209D03*
X968166Y242260D03*
X944507Y228610D03*
Y224709D03*
Y244209D03*
Y248109D03*
X941127Y242260D03*
Y250060D03*
Y246160D03*
X947887D03*
X941127Y222760D03*
X947887Y226660D03*
Y234460D03*
X941127Y238360D03*
Y234460D03*
Y230559D03*
Y226660D03*
X971546Y248109D03*
X968166Y246160D03*
X951267Y240309D03*
X958026D03*
X964786D03*
X954647Y246160D03*
Y250060D03*
X958026Y228610D03*
Y236409D03*
X961406Y238360D03*
X951267Y228610D03*
X954647Y226660D03*
X958026Y224709D03*
Y232509D03*
X954647Y230559D03*
X961406Y222760D03*
X968166Y226660D03*
X971546Y236409D03*
X968166Y238360D03*
X971546Y220809D03*
X964786Y232509D03*
Y220809D03*
X947887Y253960D03*
X941127D03*
X958026Y252009D03*
X968166Y277360D03*
X951267Y275409D03*
X961406Y277360D03*
X958026Y263709D03*
X968166Y269560D03*
X961406Y261760D03*
X958026Y255909D03*
X951267Y259809D03*
X958026D03*
X954647Y277360D03*
Y265660D03*
X951267Y267609D03*
X954647Y273460D03*
X958026Y275409D03*
X954647Y269560D03*
X961406D03*
X971546Y275409D03*
Y263709D03*
X941127Y277360D03*
Y265660D03*
X944507Y275409D03*
Y263709D03*
X941127Y269560D03*
Y257860D03*
Y261760D03*
X947887Y277360D03*
Y265660D03*
X971546Y259809D03*
Y255909D03*
X964786Y279310D03*
X934367Y285160D03*
Y300760D03*
X927607D03*
Y308560D03*
X934367D03*
X927607Y285160D03*
Y292959D03*
X934367D03*
X937747Y318309D03*
Y341709D03*
Y326110D03*
X917467Y333909D03*
Y341709D03*
X913787Y339760D03*
X924227Y333909D03*
Y337809D03*
Y341709D03*
X913787Y328060D03*
X924227Y330009D03*
X920847Y328060D03*
X917467Y330009D03*
X930987Y326110D03*
X934367Y331960D03*
X927607Y328060D03*
X934367Y324160D03*
X924227Y322209D03*
X927607Y320260D03*
X930987Y318309D03*
X934367Y316360D03*
X927607D03*
X930987Y337809D03*
X924227Y326110D03*
X961406Y292959D03*
Y285160D03*
X954647Y292959D03*
Y285160D03*
X968166Y292959D03*
Y300760D03*
X971546Y310509D03*
X964786D03*
X954647Y308560D03*
X961406D03*
X954647Y300760D03*
X961406D03*
X964786Y283209D03*
X971546D03*
X947887Y308560D03*
X941127D03*
Y300760D03*
X947887D03*
X941127Y285160D03*
Y292959D03*
X947887D03*
Y285160D03*
X968166Y281260D03*
X958026Y333909D03*
Y337809D03*
Y341709D03*
Y318309D03*
X951267D03*
X954647Y316360D03*
X961406D03*
Y324160D03*
X971546Y337809D03*
X964786Y330009D03*
X971546D03*
X951267D03*
X958026D03*
X968166Y312460D03*
X964786Y314409D03*
X951267Y337809D03*
X954647Y331960D03*
Y328060D03*
X971546Y322209D03*
X968166Y320260D03*
X964786Y322209D03*
X958026Y326110D03*
X947887Y316360D03*
X941127D03*
X944507Y322209D03*
Y318309D03*
X947887Y331960D03*
Y328060D03*
X941127Y331960D03*
Y328060D03*
Y339760D03*
Y335860D03*
X944507Y333909D03*
X937747Y365109D03*
Y345609D03*
Y361209D03*
X924227Y365109D03*
X930987D03*
X927607Y367060D03*
X934367Y370959D03*
Y363160D03*
X927607D03*
X924227Y369010D03*
X913787Y343660D03*
X934367D03*
X927607D03*
Y347560D03*
X934367Y351460D03*
X930987Y357309D03*
Y345609D03*
X917467Y353409D03*
Y349509D03*
X913787Y355360D03*
X924227Y349509D03*
Y345609D03*
Y353409D03*
Y361209D03*
Y357309D03*
X920847Y355360D03*
X917167Y361209D03*
Y369010D03*
X934367Y382660D03*
X930987Y384609D03*
Y376809D03*
X934367Y390460D03*
X927607Y386560D03*
Y390460D03*
X930987Y396309D03*
X934367Y398260D03*
X927607Y394359D03*
X917467Y388509D03*
X924227Y392410D03*
X920847Y390460D03*
X924227Y372909D03*
X937747Y400209D03*
X917100Y380709D03*
X937747D03*
X924227D03*
X920847Y382660D03*
X924227Y376809D03*
X927607Y382660D03*
X968166Y370959D03*
X958026Y361209D03*
X954647Y347560D03*
X961406Y359260D03*
X958026Y357309D03*
X951267D03*
X941127Y355360D03*
Y347560D03*
Y351460D03*
X958026Y345609D03*
X951267Y349509D03*
X954647Y351460D03*
X958026Y353409D03*
X968166Y355360D03*
Y351460D03*
X964786Y357309D03*
X971546Y361209D03*
X968166Y359260D03*
X958026Y365109D03*
X964786D03*
X954647Y370959D03*
Y367060D03*
X958026Y369010D03*
X951267D03*
X971546Y349509D03*
X947887Y363160D03*
X941127D03*
X947887Y370959D03*
X941127D03*
Y367060D03*
X944507Y369010D03*
X947887Y343660D03*
X941127Y359260D03*
X944507Y349509D03*
Y353409D03*
X941127Y343660D03*
X947887Y351460D03*
X958026Y372909D03*
X941127Y374860D03*
X961406D03*
X944507Y372909D03*
X941127Y382660D03*
Y378760D03*
X947887D03*
X944507Y384609D03*
X947887Y390460D03*
Y386560D03*
X941127Y390460D03*
X947887Y398260D03*
X941127D03*
X944507Y396309D03*
X947887Y394359D03*
X964786Y376809D03*
X971546D03*
X968166Y378760D03*
Y386560D03*
X964786Y392410D03*
X968166Y390460D03*
Y394359D03*
X964786Y388509D03*
X961406Y378760D03*
X954647D03*
X958026Y384609D03*
X961406Y382660D03*
X951267Y388509D03*
X958026D03*
X954647Y394359D03*
X961406Y386560D03*
X952216Y402421D03*
X970416Y401941D03*
X971546Y380709D03*
X968166Y382660D03*
X920700Y495944D03*
X913800Y495800D03*
X927165Y495944D03*
X929811Y515814D03*
X933632Y510098D03*
X923600Y491144D03*
X917192Y491219D03*
X933632Y490644D03*
X929811D03*
X933632Y498644D03*
X933608Y517900D03*
X913779Y510114D03*
X917125Y515814D03*
X923468Y515714D03*
X920472Y510114D03*
X927015D03*
X938732Y490644D03*
X950700Y490700D03*
X943897Y490444D03*
X970669Y512792D03*
X967322Y515364D03*
X963976Y512792D03*
X960629Y515364D03*
X938708Y510100D03*
X938732Y518114D03*
Y498644D03*
X954000Y497300D03*
X953886Y515814D03*
X950590Y510114D03*
X943897D03*
X947243Y515814D03*
X947443Y497644D03*
X957774Y512794D03*
X933632Y536999D03*
X929811Y531100D03*
X933658Y529150D03*
X913779Y537049D03*
X917125Y530949D03*
X927015Y537049D03*
X923432Y530949D03*
X920472Y536999D03*
X923468Y553514D03*
X917125Y553614D03*
X913779Y547914D03*
X927015D03*
X920472D03*
X933632Y547898D03*
X929811Y553614D03*
X933608Y555700D03*
X933632Y585698D03*
X933658Y566950D03*
X929811Y568900D03*
X933632Y574799D03*
X920472D03*
X927015Y585714D03*
X920472D03*
X913779Y574849D03*
X917125Y568749D03*
X913779Y585714D03*
X923432Y568749D03*
X927015Y574849D03*
X938745Y528936D03*
X938758Y536750D03*
X938708Y547900D03*
X957600Y533100D03*
X970942D03*
X957701Y552000D03*
X970731D03*
X950590Y537049D03*
X957283Y536957D03*
X953936Y530949D03*
X957283Y548200D03*
X953886Y553614D03*
X950590Y547914D03*
X947243Y530949D03*
X943897Y537049D03*
Y547914D03*
X947243Y553614D03*
X938732Y555914D03*
X938745Y566736D03*
X938758Y574550D03*
X938708Y585700D03*
X957600Y570900D03*
X970942D03*
X950590Y574849D03*
Y585714D03*
X957283Y574757D03*
X957456Y588334D03*
X953936Y568749D03*
X943897Y574849D03*
X947243Y568749D03*
X943897Y585714D03*
X933632Y612599D03*
X923432Y606549D03*
X917125D03*
X933658Y604750D03*
X923468Y591314D03*
X917125Y591414D03*
X933608Y593500D03*
X929811Y591414D03*
X927015Y612449D03*
X920472Y612399D03*
X913779Y612449D03*
X929811Y606700D03*
X938758Y612350D03*
X938745Y604536D03*
X938732Y593714D03*
X957500Y591000D03*
X970731Y589800D03*
X953936Y606549D03*
X957283Y611600D03*
X950590Y612249D03*
X953886Y591414D03*
X947243Y606549D03*
X943897Y612249D03*
X947243Y591414D03*
X983900Y13200D03*
Y32100D03*
X1028400Y6500D03*
X1030407Y-8938D03*
X1008200Y30736D03*
X1007100Y11714D03*
X1008227Y33342D03*
X1030400Y26150D03*
X1030450Y23150D03*
X1007100Y14314D03*
X983900Y51000D03*
X997441Y92757D03*
X990748Y87392D03*
X977362Y92757D03*
X987401Y89964D03*
X980708Y84714D03*
X983900Y69900D03*
X1007370Y52333D03*
Y49659D03*
X1014350Y73000D03*
X1017919Y92500D03*
X1017519Y87500D03*
X1000787Y84599D03*
X1007480Y87500D03*
X1007573Y92500D03*
X1007380Y68335D03*
X1030400Y56500D03*
X1031600Y42900D03*
X1007380Y70935D03*
X1023900Y74100D03*
Y77200D03*
X974100Y103500D03*
X983936Y199108D03*
X973808Y201308D03*
X998586Y209109D03*
X981686Y218860D03*
X974926Y211060D03*
X985066Y216909D03*
X988446Y211058D03*
X979426Y214958D03*
X1005345Y209109D03*
X1001965Y211060D03*
X1025625Y209109D03*
X1012105D03*
X1032385D03*
X995206Y238360D03*
X988446Y234460D03*
X998586Y248109D03*
Y220809D03*
X985066Y248109D03*
X981686Y250060D03*
X974926D03*
X988446Y246160D03*
X981686Y242260D03*
X974926D03*
X988446D03*
Y238360D03*
X985066Y236409D03*
X981686Y234460D03*
X974926Y226660D03*
X991826Y220809D03*
X974926Y230559D03*
Y234460D03*
Y222760D03*
X985066Y224709D03*
X978306Y232509D03*
Y220809D03*
X974926Y253960D03*
X988446D03*
X978306Y252009D03*
X985066D03*
X974926Y265660D03*
X991826Y259809D03*
X985066D03*
X981686Y269560D03*
X995206D03*
X985066Y267609D03*
X991826Y263709D03*
X988446Y265660D03*
X998586Y263709D03*
X991826Y271509D03*
X995206Y273460D03*
X991826Y279310D03*
Y275409D03*
X974926Y269560D03*
X978306Y267609D03*
Y259809D03*
X991826Y255909D03*
X995206Y265660D03*
X991826Y267609D03*
X974926Y273460D03*
X1029005Y238360D03*
X1005345Y248109D03*
X1008725Y238360D03*
X1001965D03*
X1005345Y220809D03*
X1029005Y250060D03*
X1032385Y248109D03*
X1025625D03*
X1022245Y250060D03*
X1025625Y220809D03*
X1012105D03*
X1015485Y238360D03*
X1022245D03*
X1018865Y220809D03*
X1032385D03*
X1001965Y261760D03*
X1012105Y255909D03*
X1015485Y253960D03*
X1018865Y252009D03*
X1005345Y259809D03*
X1008725Y257860D03*
X981686Y281260D03*
Y292959D03*
Y300760D03*
X988446D03*
X978306Y310509D03*
X991826D03*
X985066D03*
X974926Y300760D03*
X988446Y292959D03*
X991826Y283209D03*
X988446Y281260D03*
X985066Y283209D03*
X978306D03*
X974926Y292959D03*
Y281260D03*
X991826Y333909D03*
X995206Y335860D03*
Y339760D03*
Y328060D03*
X991826Y326110D03*
X981686Y339760D03*
X978306Y333909D03*
Y330009D03*
Y326110D03*
X981686Y331960D03*
X985066Y330009D03*
X974926Y324160D03*
X988446Y339760D03*
X974926Y312460D03*
X981686D03*
X988446D03*
X991826Y314409D03*
Y330009D03*
X995206Y331960D03*
X988446D03*
X995206Y324160D03*
X988446Y316360D03*
X991826Y318309D03*
X995206Y320260D03*
X991826Y322209D03*
X998586Y333909D03*
X974926Y339760D03*
Y335860D03*
X1017957Y312421D03*
X1025438Y312381D03*
X1022915Y312372D03*
X1020404Y312408D03*
X1028039Y312414D03*
X1008725Y339760D03*
X1005345Y337809D03*
X1001965Y335860D03*
X1012105Y341709D03*
X995206Y343660D03*
X985066Y361209D03*
X974926Y355360D03*
Y347560D03*
X981686D03*
X978306Y345609D03*
X981686Y355360D03*
X985066Y349509D03*
X998586D03*
X978306Y365109D03*
X981686Y363160D03*
X974926D03*
Y367060D03*
Y370959D03*
Y343660D03*
X995206Y359260D03*
X988446D03*
Y347560D03*
X991826Y345609D03*
X988446Y351460D03*
Y355360D03*
X985066Y372909D03*
X974926Y374860D03*
X985066Y384609D03*
X998586Y376809D03*
X991826Y388509D03*
X995206Y390460D03*
X974926Y386560D03*
X991826Y376809D03*
X974066Y399911D03*
X978306Y376809D03*
X974926Y378760D03*
X981686D03*
X985066Y380709D03*
X1001965Y359260D03*
X1005345Y349509D03*
X1008725Y359260D03*
X1015485D03*
X1018865Y345609D03*
X1022245Y347560D03*
X1015485Y343660D03*
X1025625Y345609D03*
X1022245Y359260D03*
X1029005Y347560D03*
Y359260D03*
X1032385Y349509D03*
Y388509D03*
Y376809D03*
X1005345D03*
Y388509D03*
X1001965Y386560D03*
X1025625Y376809D03*
Y388509D03*
X1018865Y376809D03*
X1012105D03*
X1018865Y388509D03*
X1012105D03*
X987401Y515364D03*
X990748Y512792D03*
X997441Y518157D03*
X973795Y499793D03*
X980708Y510114D03*
X977362Y518157D03*
X1034200Y506956D03*
X1000490Y509999D03*
X1016473Y515152D03*
Y510114D03*
X1008650Y515200D03*
X1008526Y510114D03*
X983900Y533100D03*
Y552000D03*
Y570900D03*
X1007147Y550511D03*
Y553111D03*
X1007207Y534137D03*
X1013500Y529200D03*
X1026500Y538500D03*
Y541000D03*
X1007207Y531537D03*
X1026500Y546400D03*
X1006406Y588366D03*
X1007332Y572010D03*
X1016473Y585714D03*
X1026500Y577500D03*
X1007332Y569410D03*
X983900Y589800D03*
X1023200Y610700D03*
X1022950Y593650D03*
X1025450D03*
X1006406Y590966D03*
X1043800Y-9700D03*
X1047637Y9107D03*
X1057677D03*
X1057792Y13200D03*
Y32100D03*
X1083116Y13200D03*
Y32100D03*
X1070976Y13200D03*
Y32100D03*
X1047637Y46907D03*
X1057677D03*
X1057676Y87392D03*
X1050983Y92757D03*
X1047637Y84599D03*
X1057792Y51000D03*
Y69900D03*
X1083116Y51000D03*
X1070976D03*
X1083116Y69900D03*
X1070976D03*
X1067716Y89964D03*
Y84599D03*
X1081102D03*
X1091141Y87392D03*
Y92657D03*
X1077755Y92757D03*
X1074409Y84714D03*
X1084448Y92757D03*
X1061023Y89964D03*
X1035900Y98800D03*
X1057314Y209109D03*
X1045904D03*
X1039145D03*
X1072202Y216196D03*
X1065242Y208397D03*
X1068822Y214247D03*
X1065242Y212296D03*
Y204496D03*
X1071072Y199583D03*
X1095861Y218147D03*
X1089101Y214247D03*
Y210346D03*
X1092481Y216196D03*
X1095861Y206446D03*
X1091351Y199841D03*
X1075582Y206446D03*
Y218147D03*
X1082341D03*
X1078962Y216196D03*
X1078961Y212296D03*
X1082341Y214247D03*
X1085721Y212296D03*
Y216196D03*
X1084591Y198931D03*
X1045904Y220809D03*
X1057314D03*
X1035765Y238360D03*
Y250060D03*
X1057314Y248109D03*
X1039145D03*
X1042524Y250060D03*
X1049284D03*
X1045904Y248109D03*
X1042524Y238360D03*
X1039145Y220809D03*
X1095861Y229847D03*
X1068822Y233746D03*
X1065242Y235696D03*
Y223996D03*
X1068822Y237647D03*
Y249347D03*
X1065242Y247396D03*
X1068822Y241547D03*
X1072202Y243496D03*
Y251296D03*
X1092481Y223996D03*
Y231797D03*
X1089101Y233746D03*
Y237647D03*
X1095861D03*
Y245447D03*
X1078962Y251296D03*
X1082341Y245447D03*
Y249347D03*
X1078962Y247396D03*
X1092481Y243496D03*
X1075582Y245447D03*
X1085721Y251296D03*
X1075582Y249347D03*
X1085721Y243496D03*
X1089101Y241547D03*
X1085721Y223996D03*
X1075582Y229847D03*
X1082341D03*
X1078962Y227896D03*
Y220096D03*
Y223996D03*
X1085721Y231797D03*
X1082341Y237647D03*
X1075582D03*
X1072202Y231797D03*
Y223996D03*
X1089101Y253247D03*
X1092481Y255196D03*
X1095861Y257147D03*
X1042524Y359260D03*
X1049284Y351460D03*
X1045904Y353409D03*
X1035765Y351460D03*
Y359260D03*
X1039145Y353409D03*
X1042524Y351460D03*
X1054914Y347000D03*
X1039145Y388509D03*
X1045904D03*
X1052664D03*
X1039145Y376809D03*
X1045904D03*
X1052664D03*
X1060694Y351460D03*
X1086841Y358547D03*
X1094731Y346546D03*
X1086841Y354647D03*
X1090221Y352696D03*
X1091351Y348497D03*
X1073322Y354647D03*
X1076702Y356596D03*
X1080082Y354647D03*
X1083462Y368296D03*
X1076702Y372197D03*
Y368296D03*
X1073322Y362447D03*
X1086841D03*
X1090221Y372197D03*
Y364396D03*
X1093601Y366347D03*
X1090221Y368296D03*
X1076702Y360496D03*
X1083462D03*
Y352696D03*
X1076702D03*
X1093601Y358547D03*
X1090221Y379996D03*
X1073323Y401449D03*
X1078962Y399496D03*
X1093601Y401447D03*
X1060694Y374860D03*
X1073322Y374146D03*
X1086841D03*
X1073323Y397548D03*
X1073322Y385847D03*
X1080082Y393647D03*
X1083462Y391696D03*
X1080082Y385847D03*
X1083462Y376096D03*
X1080082Y378047D03*
X1083462Y379996D03*
X1076702Y376096D03*
X1090221Y395595D03*
X1086841Y389747D03*
X1093601Y393647D03*
X1090221Y391696D03*
X1093601Y385847D03*
X1086841D03*
X1093601Y397546D03*
Y378047D03*
X1086841Y381947D03*
X1093601Y405347D03*
X1077832Y407800D03*
X1035750Y503006D03*
X1047637Y509999D03*
X1057676Y512792D03*
X1050983Y518157D03*
X1067716Y509999D03*
X1074409Y510114D03*
X1061023Y515364D03*
X1091141Y518057D03*
X1077755Y518157D03*
X1081102Y509999D03*
X1084448Y518157D03*
X1091141Y512792D03*
X1067716Y515364D03*
X1057792Y552000D03*
Y533100D03*
X1057677Y547907D03*
X1047637D03*
X1057677Y585707D03*
X1047637D03*
X1057792Y570900D03*
X1070976Y552000D03*
Y533100D03*
X1084003Y532904D03*
X1083116Y552000D03*
X1070976Y570900D03*
X1083116D03*
X1057792Y589800D03*
X1070242D03*
X1083108D03*
X1119453Y-9864D03*
X1097352Y-7180D03*
X1104141Y-7851D03*
X1110520Y-7700D03*
X1114340Y-1801D03*
X1107874Y-1751D03*
X1101181Y-1801D03*
X1107724Y9114D03*
X1101181D03*
X1114340Y9098D03*
X1114400Y28100D03*
X1110520Y14814D03*
X1104177Y14714D03*
X1098500Y17000D03*
X1114300Y16900D03*
X1119400Y9300D03*
X1119453Y27936D03*
X1119440Y17114D03*
X1097900Y13700D03*
Y31900D03*
X1110520Y30100D03*
X1097834Y28100D03*
X1104141Y29949D03*
X1156300Y-2000D03*
X1151152Y-1801D03*
X1131299Y9114D03*
X1124606D03*
X1151152Y9098D03*
X1137992Y9114D03*
X1144535D03*
X1127952Y-7851D03*
X1124606Y-1751D03*
X1131299D03*
X1134645Y-7851D03*
X1156265Y-9864D03*
X1151200Y-9700D03*
X1147331Y-7700D03*
X1140952Y-7851D03*
X1137992Y-1801D03*
X1144685Y-1751D03*
X1156212Y9300D03*
X1127952Y14814D03*
X1151211Y28100D03*
X1156252Y17114D03*
X1151112Y16900D03*
X1147331Y30100D03*
Y14814D03*
X1134645Y29949D03*
X1140952D03*
X1140988Y14714D03*
X1134645Y14814D03*
X1156265Y27936D03*
X1127952Y29949D03*
X1114340Y35999D03*
X1098235Y68090D03*
X1110520Y67900D03*
X1104141Y67749D03*
X1114366Y65950D03*
X1119440Y54914D03*
X1119400Y47100D03*
Y35800D03*
X1098100Y51000D03*
X1119453Y65736D03*
X1107874Y36049D03*
X1098022Y35761D03*
X1101181Y35999D03*
X1107724Y46914D03*
X1110520Y52614D03*
X1098581Y54883D03*
X1104177Y52514D03*
X1101181Y46900D03*
X1098125Y46975D03*
X1114300Y54700D03*
X1114340Y46898D03*
X1098259Y70896D03*
X1101181Y84714D03*
X1098218Y85296D03*
X1114340Y73799D03*
X1107874Y73849D03*
X1101181Y73799D03*
X1098207Y73589D03*
X1110520Y90314D03*
X1114340Y84698D03*
X1114316Y92500D03*
X1107724Y84714D03*
X1119440Y92714D03*
X1119416Y84700D03*
X1119466Y73550D03*
X1098300Y89900D03*
X1104177Y90314D03*
X1127952Y67749D03*
X1156211Y35800D03*
X1156200Y47000D03*
X1151152Y35999D03*
Y46898D03*
X1151100Y54700D03*
X1147331Y52614D03*
X1134645D03*
X1137992Y46914D03*
Y35999D03*
X1144535Y46914D03*
X1144685Y36049D03*
X1156252Y54914D03*
X1134645Y67749D03*
X1140952D03*
X1156265Y65736D03*
X1151178Y65950D03*
X1147331Y67900D03*
X1131299Y46914D03*
X1124606D03*
X1127952Y52614D03*
X1131299Y36049D03*
X1124606D03*
X1131299Y73849D03*
X1124606D03*
X1127952Y90414D03*
X1131299Y84714D03*
X1124606D03*
X1147331Y90414D03*
X1137992Y73799D03*
X1144535Y84714D03*
X1140988Y90314D03*
X1137992Y84714D03*
X1134645Y90414D03*
X1144685Y73849D03*
X1156252Y92714D03*
X1151128Y92500D03*
X1151152Y84698D03*
X1156228Y84700D03*
X1156278Y73550D03*
X1151152Y73799D03*
X1138242Y104314D03*
X1144685D03*
X1156278Y112865D03*
X1151152Y113114D03*
X1141038Y109564D03*
X1147331D03*
X1156265Y105051D03*
X1151178Y105265D03*
X1116141Y206446D03*
X1136420Y210346D03*
X1099241Y216196D03*
Y212296D03*
X1109381Y214247D03*
X1116141Y218147D03*
X1106001Y212296D03*
X1102621Y218147D03*
Y214247D03*
X1119521Y216196D03*
X1119520Y212296D03*
X1104871Y198050D03*
X1106001Y216196D03*
X1112761D03*
X1129660Y206447D03*
X1126280Y216196D03*
Y212296D03*
X1125300Y199900D03*
X1122900Y214247D03*
Y218147D03*
X1129660Y214247D03*
X1147950Y209900D03*
X1136420Y218147D03*
Y214247D03*
X1151060Y212296D03*
X1157820D03*
X1099241Y227896D03*
Y220096D03*
X1102621Y229847D03*
X1099241Y223996D03*
X1109381Y233746D03*
X1112761Y231797D03*
Y223996D03*
X1116141Y237647D03*
X1109381D03*
X1106001Y223996D03*
X1102621Y237647D03*
Y245447D03*
X1112761Y251296D03*
X1116141Y245447D03*
X1106001Y243496D03*
X1112761D03*
X1109381Y241547D03*
X1106001Y251296D03*
X1099241D03*
Y247396D03*
X1119521Y223996D03*
Y220096D03*
Y227896D03*
Y247396D03*
Y251296D03*
X1106001Y231797D03*
X1116141Y229847D03*
X1107561Y269038D03*
X1116141Y264947D03*
X1111631Y271300D03*
X1106001Y262996D03*
Y259096D03*
X1099241Y255196D03*
Y259096D03*
X1119521Y270796D03*
X1118391Y274997D03*
X1119521Y255196D03*
X1102621Y261047D03*
Y257147D03*
X1109381Y261047D03*
X1116141Y257147D03*
X1112761Y259096D03*
X1110648Y276899D03*
X1100200Y273300D03*
X1129660Y237647D03*
X1126280Y223996D03*
Y231797D03*
X1122900Y229847D03*
Y237647D03*
X1129660Y233746D03*
Y241547D03*
X1126280Y251296D03*
Y243496D03*
X1122900Y245447D03*
X1144300Y243496D03*
X1151060Y247396D03*
X1154440Y245447D03*
X1144300Y247396D03*
Y251296D03*
X1136420Y245447D03*
X1154440Y241547D03*
X1136420D03*
X1157820Y239596D03*
X1147680Y222047D03*
X1144300Y235696D03*
X1136420Y229847D03*
Y233746D03*
Y222047D03*
Y225947D03*
Y237647D03*
X1133040Y223996D03*
Y235696D03*
Y243496D03*
Y251296D03*
X1147680Y225947D03*
X1151060Y223996D03*
X1147680Y233746D03*
X1154440Y229847D03*
X1157820Y220096D03*
Y223996D03*
Y231797D03*
X1154440Y253247D03*
X1130780Y278596D03*
X1129660Y261047D03*
X1130780Y274696D03*
X1126280Y259096D03*
X1122900Y257147D03*
X1157820Y278596D03*
Y270796D03*
X1151060Y266896D03*
Y274696D03*
X1137540D03*
X1151060Y259096D03*
X1144300Y255196D03*
X1133040Y259096D03*
X1134160Y268847D03*
X1136420Y257147D03*
X1144300Y278596D03*
Y270796D03*
X1137540Y278596D03*
X1119521Y286396D03*
Y305896D03*
X1108251Y338746D03*
X1117261Y340996D03*
X1104871Y340697D03*
X1119521Y321496D03*
X1130780Y290296D03*
X1127400Y288347D03*
X1130780Y309797D03*
Y301996D03*
X1127400Y303947D03*
Y307847D03*
X1157820Y290296D03*
X1151060Y298096D03*
Y290296D03*
Y282496D03*
X1144300Y286396D03*
Y294196D03*
X1157820D03*
X1140920Y300047D03*
X1134160Y292247D03*
Y300047D03*
X1140920Y292247D03*
X1137540Y282496D03*
X1144300Y309797D03*
X1137540D03*
X1147680Y303947D03*
X1154440Y307847D03*
X1130780Y313696D03*
X1157820D03*
X1124021Y340996D03*
Y337096D03*
X1127400Y327347D03*
X1157820Y337096D03*
Y333196D03*
X1134160Y323446D03*
X1151060Y340996D03*
Y333196D03*
X1154440Y319547D03*
X1157820Y317596D03*
X1137540D03*
X1157820Y329296D03*
X1147680Y327347D03*
X1154440Y335147D03*
X1144300Y340996D03*
Y337096D03*
X1140920Y339047D03*
Y331247D03*
X1154440Y323446D03*
Y315647D03*
X1147680Y319547D03*
X1157820Y325396D03*
X1154440Y339047D03*
Y331247D03*
X1127400Y319547D03*
Y315647D03*
X1100361Y350747D03*
X1113881D03*
Y358547D03*
X1117261Y348796D03*
X1100361Y358547D03*
X1103741Y348796D03*
Y352696D03*
X1110501D03*
X1107121Y346847D03*
Y354647D03*
Y358547D03*
Y362447D03*
X1103741Y372197D03*
X1110501Y364396D03*
X1103741D03*
X1113881Y366347D03*
X1117261Y372197D03*
Y368296D03*
X1110501Y372197D03*
X1096981Y368296D03*
Y372197D03*
X1100361Y366347D03*
X1113881Y401447D03*
X1110501Y391696D03*
Y395595D03*
X1107121Y389747D03*
X1100361Y385847D03*
X1107121D03*
X1100361Y393647D03*
X1103741Y391696D03*
X1100361Y397547D03*
X1113881Y385847D03*
Y397546D03*
Y393647D03*
X1103741Y379996D03*
X1113881Y378047D03*
X1117261Y376096D03*
X1110501Y379996D03*
X1107121Y381947D03*
X1096981Y376096D03*
X1100361Y378047D03*
X1151060Y368296D03*
X1147680Y366347D03*
X1120641Y350747D03*
Y358547D03*
Y366347D03*
X1127400Y362447D03*
X1124021Y348796D03*
Y352696D03*
X1127400Y354647D03*
Y358547D03*
X1130780Y360496D03*
X1127400Y342947D03*
X1134160Y346847D03*
Y362447D03*
Y366347D03*
Y370247D03*
X1147680Y342947D03*
X1151060Y356596D03*
Y360496D03*
X1144300D03*
X1137540D03*
X1144300Y356596D03*
X1140920Y358547D03*
X1147680Y346847D03*
Y350747D03*
X1151060Y352696D03*
Y348796D03*
X1147680Y358547D03*
X1157820Y360496D03*
X1154440Y358547D03*
Y342947D03*
Y354647D03*
X1157820Y352696D03*
X1147680Y354647D03*
X1144300Y348796D03*
X1140920Y346847D03*
Y350747D03*
X1144300Y344896D03*
X1151060D03*
X1154440Y346847D03*
X1140920Y362447D03*
X1154440Y366347D03*
X1144300Y372197D03*
X1137540D03*
Y368296D03*
X1140920Y366347D03*
Y370247D03*
X1151060Y364396D03*
X1144300D03*
X1137540D03*
X1147680Y362447D03*
X1130780Y352696D03*
Y344896D03*
X1124021Y372197D03*
X1130780D03*
X1124021Y364396D03*
X1137540Y403396D03*
Y399496D03*
X1124021Y391696D03*
X1130780Y395596D03*
X1127400Y385847D03*
Y389747D03*
X1130780Y391696D03*
X1124021Y379996D03*
X1127400Y381947D03*
X1130780Y379996D03*
X1137540Y395597D03*
X1140920Y397546D03*
X1137540Y376096D03*
X1157820Y387796D03*
X1140920Y378047D03*
Y381947D03*
X1147680Y393647D03*
X1120641Y385847D03*
Y393647D03*
Y378047D03*
Y401447D03*
X1140920Y374146D03*
X1151060Y395597D03*
Y391696D03*
X1147680Y385847D03*
Y397546D03*
X1151060Y379996D03*
X1154440Y378047D03*
Y381947D03*
X1140920Y389747D03*
X1134160Y393647D03*
Y385847D03*
Y378047D03*
X1140920Y385847D03*
X1144300Y391696D03*
X1117261Y407296D03*
X1113881Y405347D03*
X1096699Y407782D03*
X1134160Y405347D03*
X1119440Y518114D03*
X1114316Y517900D03*
X1114340Y510098D03*
X1110520Y515714D03*
X1097343Y512794D03*
X1104177Y515714D03*
X1101181Y510114D03*
X1098300Y515300D03*
X1107724Y510114D03*
X1137992Y495887D03*
X1144385D03*
X1140988Y493744D03*
X1156252Y490867D03*
X1147331Y493494D03*
X1151168Y490867D03*
X1127952Y515814D03*
X1124606Y510114D03*
X1131299D03*
X1156252Y518114D03*
X1147331Y515814D03*
X1151128Y517900D03*
X1156252Y498867D03*
X1151168D03*
X1151152Y510098D03*
X1134645Y515814D03*
X1137992Y510114D03*
X1140988Y515714D03*
X1144535Y510114D03*
X1156228Y510100D03*
X1104141Y530949D03*
X1098040Y536723D03*
X1098160Y533809D03*
X1119416Y547900D03*
X1119466Y536750D03*
X1119453Y528936D03*
X1098300Y553100D03*
X1114340Y547898D03*
X1107724Y547914D03*
X1101181D03*
X1110520Y553514D03*
X1104177D03*
X1098118Y549843D03*
X1098018Y531156D03*
X1114366Y529150D03*
X1114340Y536999D03*
X1110520Y531100D03*
X1107874Y537049D03*
X1101181Y536999D03*
X1119440Y555914D03*
X1114316Y555700D03*
X1119416Y585700D03*
X1119466Y574550D03*
X1119453Y566736D03*
X1104141Y568749D03*
X1097899Y574773D03*
X1101181Y585714D03*
X1097834Y569200D03*
X1107724Y585714D03*
X1107874Y574849D03*
X1110520Y568900D03*
X1101181Y574799D03*
X1114340D03*
Y585698D03*
X1114366Y566950D03*
X1140988Y553514D03*
X1151152Y547898D03*
X1156228Y547900D03*
X1137992Y547914D03*
X1144535D03*
X1127952Y553614D03*
X1131299Y547914D03*
X1124606D03*
X1131299Y537049D03*
X1124606D03*
X1127952Y530949D03*
X1151178Y529150D03*
X1151152Y536999D03*
X1147331Y531100D03*
X1156278Y536750D03*
X1156265Y528936D03*
X1134645Y530949D03*
X1140952D03*
X1137992Y536999D03*
X1144685Y537049D03*
X1147331Y553614D03*
X1134645D03*
X1156252Y555914D03*
X1151128Y555700D03*
X1156265Y566736D03*
X1151178Y566950D03*
X1134645Y568749D03*
X1137992Y585714D03*
X1144535D03*
X1140952Y568749D03*
X1137992Y574799D03*
X1144685Y574849D03*
X1151152Y585698D03*
Y574799D03*
X1147331Y568900D03*
X1156228Y585700D03*
X1156278Y574550D03*
X1131299Y585714D03*
X1124606D03*
X1131299Y574849D03*
X1127952Y568749D03*
X1124606Y574849D03*
X1137992Y612599D03*
X1144685Y612649D03*
X1151152Y612599D03*
X1124606Y612649D03*
X1131299D03*
X1114340Y612599D03*
X1107874Y612649D03*
X1101181Y612599D03*
X1097352Y607220D03*
X1110520Y606700D03*
X1119453Y604536D03*
X1119466Y612350D03*
X1119440Y593714D03*
X1104177Y591314D03*
X1110520D03*
X1114316Y593500D03*
X1098300Y590900D03*
X1114366Y604750D03*
X1104141Y606549D03*
X1156265Y604536D03*
X1147331Y606700D03*
X1134645Y606549D03*
X1140952D03*
X1156278Y612350D03*
X1134645Y591414D03*
X1140988Y591314D03*
X1151128Y593500D03*
X1147331Y591414D03*
X1156252Y593714D03*
X1151178Y604750D03*
X1127952Y606549D03*
Y591414D03*
X1161417Y9114D03*
X1168110D03*
X1174803D03*
X1171456Y-7851D03*
X1164763D03*
X1177763D03*
X1168110Y-1751D03*
X1161417D03*
X1174803Y-1801D03*
X1171456Y14814D03*
X1164763Y29949D03*
X1171456D03*
X1164763Y14814D03*
X1177799Y14714D03*
X1177763Y29949D03*
X1181496Y-1751D03*
X1181346Y9114D03*
X1187963Y9098D03*
X1204921Y9114D03*
X1198228D03*
X1188011Y-9700D03*
X1193076Y-9864D03*
X1184142Y-7700D03*
X1193111Y-2000D03*
X1187963Y-1801D03*
X1201574Y-7851D03*
X1204921Y-1751D03*
X1198228D03*
X1218307D03*
X1211614Y-1801D03*
X1214574Y-7851D03*
X1208267D03*
X1218157Y9114D03*
X1211614D03*
X1193023Y9300D03*
X1184142Y30100D03*
Y14814D03*
X1188023Y28100D03*
X1187923Y16900D03*
X1193063Y17114D03*
X1193076Y27936D03*
X1201574Y14814D03*
Y29949D03*
X1208267Y14814D03*
Y29949D03*
X1214600Y14714D03*
X1214574Y29949D03*
X1161417Y36049D03*
X1164763Y52614D03*
X1168110Y36049D03*
Y46914D03*
X1161417D03*
X1174803D03*
X1171456Y52614D03*
X1174803Y35999D03*
X1177763Y67749D03*
X1171456D03*
X1164763D03*
X1177799Y90314D03*
X1174803Y84714D03*
X1168110D03*
Y73849D03*
X1161417D03*
X1174803Y73799D03*
X1161417Y84714D03*
X1164763Y90414D03*
X1171456D03*
X1181346Y46914D03*
X1181496Y36049D03*
X1184142Y52614D03*
X1193012Y47000D03*
X1187963Y46898D03*
Y35999D03*
X1187912Y54700D03*
X1187989Y65950D03*
X1193076Y65736D03*
X1193063Y54914D03*
X1193023Y35800D03*
X1204921Y36049D03*
X1198228D03*
Y46914D03*
X1204921D03*
X1201574Y52614D03*
X1184142Y67900D03*
X1201574Y67749D03*
X1218307Y36049D03*
X1211614Y35999D03*
X1214960Y52864D03*
X1211614Y46914D03*
X1218157D03*
X1208267Y52614D03*
X1211614Y73799D03*
X1218307Y73849D03*
X1208267Y90414D03*
X1218157Y84714D03*
X1211614D03*
X1214574Y67749D03*
X1208267D03*
X1181346Y84714D03*
X1181496Y73849D03*
X1184142Y90414D03*
X1193039Y84700D03*
X1193063Y92714D03*
X1187939Y92500D03*
X1187963Y84698D03*
Y73799D03*
X1193089Y73550D03*
X1198228Y73849D03*
X1204921D03*
X1198228Y84714D03*
X1204921D03*
X1201574Y90414D03*
X1177799Y109914D03*
X1161632Y104314D03*
X1170721Y109564D03*
X1164428D03*
X1168075Y104314D03*
X1174742D03*
X1208267Y110014D03*
X1181346Y104314D03*
X1187963Y113114D03*
X1193089Y112865D03*
X1184142Y109564D03*
X1193076Y105051D03*
X1187989Y105265D03*
X1201574Y110014D03*
X1198228Y104314D03*
X1204921D03*
X1161200Y206446D03*
X1167960Y206447D03*
Y218147D03*
X1171339Y208397D03*
X1174719Y218147D03*
Y206447D03*
X1178099Y208397D03*
Y216196D03*
X1161200Y210346D03*
Y218147D03*
X1181479Y206447D03*
X1188239Y210346D03*
Y206447D03*
X1201759Y218147D03*
X1205759Y206682D03*
X1197492Y201356D03*
X1198379Y212296D03*
X1194999Y210346D03*
X1184859Y204496D03*
X1188239Y214247D03*
X1164580Y235696D03*
X1167960Y229847D03*
X1164580Y223996D03*
Y227896D03*
Y239596D03*
X1178099Y247396D03*
X1161200Y241547D03*
X1164580Y247396D03*
X1161200Y249347D03*
X1171339Y247396D03*
X1178099Y243496D03*
X1171339Y235696D03*
Y220096D03*
Y231797D03*
X1178099Y227896D03*
Y235696D03*
Y220096D03*
X1174719Y237647D03*
X1167960Y253247D03*
X1174719D03*
X1164580Y270796D03*
X1171339Y274696D03*
X1174719Y280547D03*
X1171339Y266896D03*
X1164580Y278596D03*
X1159578Y265117D03*
X1171339Y259096D03*
X1178099Y274696D03*
X1181479Y222047D03*
X1188239D03*
X1191619Y239596D03*
X1188239Y225947D03*
X1184859Y235696D03*
X1188239Y237647D03*
X1184859Y247396D03*
X1188239Y249347D03*
X1201759Y229847D03*
Y225947D03*
Y233746D03*
X1198379Y235696D03*
Y243496D03*
X1201759Y241547D03*
Y249347D03*
X1198379Y239596D03*
X1194999Y225947D03*
Y222047D03*
Y233746D03*
X1184859Y239596D03*
Y251296D03*
X1212199D03*
Y243496D03*
X1208519Y233746D03*
X1215700Y223600D03*
X1194999Y264947D03*
Y268847D03*
Y272747D03*
Y280547D03*
X1188239Y257147D03*
X1208519Y272747D03*
X1208819Y280547D03*
X1181479Y261047D03*
Y268847D03*
Y276646D03*
X1212199Y274696D03*
X1217200Y270500D03*
X1213808Y264800D03*
X1208519Y264947D03*
X1184859Y259096D03*
X1191619Y274696D03*
X1205139D03*
X1198379Y278596D03*
X1201759Y261047D03*
X1198379Y255196D03*
X1201759Y257147D03*
X1174719Y300047D03*
Y284447D03*
X1164580Y294196D03*
Y290296D03*
Y286396D03*
X1161200Y284447D03*
X1178099Y294196D03*
Y298096D03*
Y286396D03*
X1164580Y301996D03*
X1171339D03*
X1161200Y307847D03*
Y335147D03*
Y339047D03*
X1164580Y329296D03*
Y333196D03*
Y337096D03*
X1167960Y339047D03*
Y327347D03*
X1161200Y331247D03*
Y327347D03*
X1178099Y337096D03*
Y317596D03*
X1164580Y321496D03*
Y317596D03*
X1161200Y323446D03*
Y319547D03*
Y315647D03*
X1167960Y323446D03*
Y315647D03*
Y319547D03*
X1174719Y315647D03*
X1171339Y317596D03*
X1164580Y325396D03*
X1171339D03*
X1174719Y335147D03*
X1205500Y309797D03*
X1198379D03*
X1194999Y288347D03*
Y292247D03*
Y296147D03*
Y300047D03*
Y307847D03*
Y303947D03*
X1191619Y298096D03*
X1181479Y300047D03*
Y288347D03*
Y292247D03*
Y311747D03*
Y307847D03*
Y303947D03*
X1188239Y288347D03*
Y284447D03*
Y292247D03*
X1184859Y294196D03*
Y290296D03*
X1191619Y294196D03*
X1184859Y309797D03*
X1188239Y311747D03*
X1184859Y301996D03*
X1201759Y284447D03*
Y288347D03*
X1205439Y298096D03*
X1198379Y286396D03*
X1205439Y305896D03*
X1194999Y335147D03*
Y331247D03*
X1212200Y333196D03*
X1208519Y339047D03*
X1208826Y319544D03*
X1181479Y327347D03*
Y319547D03*
Y335147D03*
X1198379Y313696D03*
X1188239Y319547D03*
X1184859Y321496D03*
X1188239Y339047D03*
Y335147D03*
X1184859Y329296D03*
X1191619Y321496D03*
X1198379Y325396D03*
Y340996D03*
X1201759Y323446D03*
X1205139Y333196D03*
X1194999Y319547D03*
Y315647D03*
X1167960Y370247D03*
X1164580Y372197D03*
X1171339Y356596D03*
Y360496D03*
X1164580Y356596D03*
X1167960Y342947D03*
X1171339Y348796D03*
X1174719Y354647D03*
Y342947D03*
X1161200Y370247D03*
X1171339Y372197D03*
X1167960Y362447D03*
X1178099Y364396D03*
X1171339Y399496D03*
X1164580Y403396D03*
X1178099D03*
X1167960Y389747D03*
X1161200Y397546D03*
X1167960Y397547D03*
X1174719Y393647D03*
X1161200Y378047D03*
X1164580Y379996D03*
X1174719Y381947D03*
X1194999Y346847D03*
Y354647D03*
X1209219Y370247D03*
X1212199Y356597D03*
Y344896D03*
Y352696D03*
X1181479Y346847D03*
X1188239Y366347D03*
X1194999D03*
X1191619Y348796D03*
X1184859Y356596D03*
X1191619Y360496D03*
X1201759Y350747D03*
X1205139Y360496D03*
X1181479Y374146D03*
Y389747D03*
X1209769Y374146D03*
X1184859Y383896D03*
X1188239Y393647D03*
X1201759Y389747D03*
X1197258Y397546D03*
X1194999Y385847D03*
X1188239Y378047D03*
X1201759D03*
X1208819Y393647D03*
Y381897D03*
X1195555Y405773D03*
X1192200Y409550D03*
X1185989Y407800D03*
X1180400Y495787D03*
X1167500Y495800D03*
X1174203Y495787D03*
X1161320Y495800D03*
X1170656Y491144D03*
X1164363Y491044D03*
X1177849Y490944D03*
X1168110Y510114D03*
X1164763Y515814D03*
X1161417Y510114D03*
X1177799Y515714D03*
X1171456Y515814D03*
X1174803Y510114D03*
X1208267Y493444D03*
X1200974Y490744D03*
X1193063Y490909D03*
X1187978Y490609D03*
X1184142Y490794D03*
X1181346Y510114D03*
X1204400Y495887D03*
X1198100Y495800D03*
X1208267Y515814D03*
X1211614Y510114D03*
X1218157D03*
X1187963Y510098D03*
X1204921Y510114D03*
X1198228D03*
X1201574Y515814D03*
X1184142D03*
X1187939Y517900D03*
X1193039Y510100D03*
X1193063Y518114D03*
X1187978Y498609D03*
X1193063Y498909D03*
X1161417Y547914D03*
X1168110D03*
X1174803D03*
X1177799Y553514D03*
X1177763Y530949D03*
X1168110Y537049D03*
X1164763Y530949D03*
X1161417Y537049D03*
X1171456Y530949D03*
X1174803Y536999D03*
X1164763Y553614D03*
X1171456D03*
X1174803Y574799D03*
X1161417Y574849D03*
X1171456Y568749D03*
X1168110Y585714D03*
X1161417D03*
X1168110Y574849D03*
X1164763Y568749D03*
X1174803Y585714D03*
X1177763Y568749D03*
X1181496Y537049D03*
X1181346Y547914D03*
X1211614Y536999D03*
X1214574Y530949D03*
X1184142Y531100D03*
X1193076Y528936D03*
X1198228Y547914D03*
X1204921D03*
X1201574Y553614D03*
Y530949D03*
X1204921Y537049D03*
X1198228D03*
X1193039Y547900D03*
X1187963Y547898D03*
X1184142Y553614D03*
X1193089Y536750D03*
X1187989Y529150D03*
X1187963Y536999D03*
X1218307Y537049D03*
X1211614Y547914D03*
X1208267Y553614D03*
Y530949D03*
X1218157Y547914D03*
X1181346Y585714D03*
X1181496Y574849D03*
X1193063Y555914D03*
X1187939Y555700D03*
X1218157Y585714D03*
X1218307Y574849D03*
X1208267Y568749D03*
X1214574D03*
X1211614Y574799D03*
Y585714D03*
X1184142Y568900D03*
X1187989Y566950D03*
X1193076Y566736D03*
X1193039Y585700D03*
X1187963Y585698D03*
X1193089Y574550D03*
X1187963Y574799D03*
X1198228Y585714D03*
Y574849D03*
X1204921Y585714D03*
Y574849D03*
X1201574Y568749D03*
X1181496Y612649D03*
X1218307D03*
X1211614Y612599D03*
X1187963D03*
X1204921Y612649D03*
X1198228D03*
X1168110D03*
X1161417D03*
X1174803Y612599D03*
X1171456Y606549D03*
X1164763D03*
Y591414D03*
X1171456D03*
X1177799Y591314D03*
X1177763Y606549D03*
X1208267Y591414D03*
X1214574Y606549D03*
X1208267D03*
X1187939Y593500D03*
X1184142Y591414D03*
X1193063Y593714D03*
X1187989Y604750D03*
X1193076Y604536D03*
X1193089Y612350D03*
X1184142Y606700D03*
X1201574Y591414D03*
Y606549D03*
X1238385Y29949D03*
Y14814D03*
X1245078Y29949D03*
Y14814D03*
X1251771Y16999D03*
X1248425Y27899D03*
X1269700Y13078D03*
X1267960Y28494D03*
X1241732Y-1751D03*
X1238385Y-7851D03*
X1241732Y9114D03*
X1248425Y-1751D03*
Y-9901D03*
X1251771D03*
X1245078Y-7851D03*
X1248425Y9157D03*
X1269800Y-5822D03*
X1235039Y9114D03*
X1224774Y9098D03*
X1224822Y-9700D03*
X1229887Y-9864D03*
X1224774Y-1801D03*
X1235039Y-1751D03*
X1229922Y-2000D03*
X1220953Y-7700D03*
X1229800Y9300D03*
X1224790Y16900D03*
X1229874Y17114D03*
X1229887Y27936D03*
X1220953Y30100D03*
X1224800Y28100D03*
X1220953Y14814D03*
X1241732Y36049D03*
Y46914D03*
X1238385Y52614D03*
Y67749D03*
X1245078Y52614D03*
X1251771Y65699D03*
X1248425D03*
Y36049D03*
Y46957D03*
X1245078Y67749D03*
X1267976Y73676D03*
X1268022Y54443D03*
X1241732Y84714D03*
Y73849D03*
X1238385Y90414D03*
X1251771Y92599D03*
X1245078Y90414D03*
X1248425Y84757D03*
Y73849D03*
X1268581Y92706D03*
X1224774Y84698D03*
X1224750Y92500D03*
X1224774Y73799D03*
X1235039Y84714D03*
Y73849D03*
X1229800Y35750D03*
X1229874Y54914D03*
X1235039Y46914D03*
Y36049D03*
X1224774Y46898D03*
X1220953Y52614D03*
X1224774Y35999D03*
X1229887Y65736D03*
X1224800Y65950D03*
X1220953Y67900D03*
X1229900Y73550D03*
X1229850Y84700D03*
X1229874Y92714D03*
X1220953Y90414D03*
X1240927Y154932D03*
X1266200Y122500D03*
X1254024Y128013D03*
X1246251Y130066D03*
X1257800Y110900D03*
X1260500Y117500D03*
X1247326Y122802D03*
X1254300Y105200D03*
X1277660Y109450D03*
X1277230Y117570D03*
X1237400Y103100D03*
X1241712Y187710D03*
X1220167Y194407D03*
X1220017Y220323D03*
X1220194Y243384D03*
X1223100Y258600D03*
X1223508Y262600D03*
X1259800Y463300D03*
X1255530Y474770D03*
X1269050Y486650D03*
X1269600Y480800D03*
X1272830Y471660D03*
X1257720Y493060D03*
X1255388Y483557D03*
X1256130Y467820D03*
X1241732Y510114D03*
X1238385Y515814D03*
X1269000Y514700D03*
X1245078Y515814D03*
X1251771Y517999D03*
X1248425Y510157D03*
X1235039Y510114D03*
X1220953Y515814D03*
X1229874Y518114D03*
X1229850Y510100D03*
X1224750Y517900D03*
X1224774Y510098D03*
X1241732Y547914D03*
Y537049D03*
X1238385Y530949D03*
Y553614D03*
X1269800Y532978D03*
X1251771Y528899D03*
X1248425Y537049D03*
Y528899D03*
X1245078Y553614D03*
Y530949D03*
X1248425Y547957D03*
X1241732Y574849D03*
Y585714D03*
X1238385Y568749D03*
X1268500Y555800D03*
X1267900Y574300D03*
X1248425Y585757D03*
Y574849D03*
Y566699D03*
X1245078Y568749D03*
X1220953Y531100D03*
X1229887Y528936D03*
X1229900Y536750D03*
X1224800Y529150D03*
X1224774Y536999D03*
X1235039Y537049D03*
Y547914D03*
X1229850Y547900D03*
X1224774Y547898D03*
X1220953Y553614D03*
X1229874Y555914D03*
X1224750Y555700D03*
X1220953Y568900D03*
X1229900Y574550D03*
X1224774Y574799D03*
X1229850Y585700D03*
X1224774Y585698D03*
X1229887Y566736D03*
X1224800Y566950D03*
X1235039Y585714D03*
Y574849D03*
X1241732Y612649D03*
X1238385Y606549D03*
Y591414D03*
X1263800Y606800D03*
X1267800Y593600D03*
X1248425Y612649D03*
X1251771Y604499D03*
X1248425D03*
X1245078Y606549D03*
X1251771Y593599D03*
X1245078Y591414D03*
X1224774Y612599D03*
X1235039Y612649D03*
X1220953Y591414D03*
X1229874Y593714D03*
X1224750Y593500D03*
X1224800Y604750D03*
X1229887Y604536D03*
X1220953Y606700D03*
X1229900Y612350D03*
X1304940Y32350D03*
X1296928Y48700D03*
X1301000Y62000D03*
X1323500Y68000D03*
X1318341Y60000D03*
X1321841Y63000D03*
X1304000Y62000D03*
X1318341Y63000D03*
X1341400Y46100D03*
X1336900Y89896D03*
X1323500Y75000D03*
Y71500D03*
X1335120Y94450D03*
X1286000Y134500D03*
Y139500D03*
Y137000D03*
X1298400Y144500D03*
X1288500Y137000D03*
Y139500D03*
Y134500D03*
X1286000Y132000D03*
X1288500D03*
X1338500Y96000D03*
X1322628Y100134D03*
X1323800Y104250D03*
X1326800D03*
Y107250D03*
X1323800D03*
X1326600Y123450D03*
X1323600D03*
X1326600Y126450D03*
X1323600D03*
X1340100Y145000D03*
X1335100Y155000D03*
Y145000D03*
X1330100Y150000D03*
X1340100D03*
Y155000D03*
X1315100Y145000D03*
X1335100Y150000D03*
X1330100Y145000D03*
Y155000D03*
Y160000D03*
X1340100D03*
X1306363Y169928D03*
X1335100Y160000D03*
X1324938Y209251D03*
X1322500D03*
X1320390Y216824D03*
X1303838Y169922D03*
X1320400Y234959D03*
X1325900D03*
X1314900D03*
X1336900D03*
X1331400D03*
X1342400D03*
X1334113Y273115D03*
X1340866Y268795D03*
X1327625Y275971D03*
X1336480Y309755D03*
X1336793Y303784D03*
X1342500Y312100D03*
X1316300Y282000D03*
X1325300Y282600D03*
X1341920Y309755D03*
X1342480Y303852D03*
X1319906Y338025D03*
X1338500Y319600D03*
X1326626Y464400D03*
X1300100Y442500D03*
X1301000Y460900D03*
X1305100Y432500D03*
X1320100Y427500D03*
Y432500D03*
X1325100Y427500D03*
Y432500D03*
X1305181Y427834D03*
X1310100Y427500D03*
Y432500D03*
X1315100Y427500D03*
Y432500D03*
X1340100Y427500D03*
X1330100Y432500D03*
Y427500D03*
X1335100Y457500D03*
Y452500D03*
Y447500D03*
Y442500D03*
X1330100D03*
X1305100D03*
X1310100D03*
X1320100D03*
X1315100D03*
X1325100D03*
X1340100Y457500D03*
Y452500D03*
Y447500D03*
Y442500D03*
X1319738Y477497D03*
X1326877Y469279D03*
X1319699Y472327D03*
X1301000Y466500D03*
X1319300Y525450D03*
X1321800D03*
X1311772Y501000D03*
X1319075D03*
X1316675Y500983D03*
X1314272Y501000D03*
X1343100Y566300D03*
X1340700D03*
X1338000D03*
X1340526Y563337D03*
X1343026D03*
X1338026D03*
X1333026D03*
X1335526D03*
Y566237D03*
X1321800Y532750D03*
X1319300Y532650D03*
X1321800Y527850D03*
X1319300D03*
Y530250D03*
X1321800D03*
X1333026Y566237D03*
X1298100Y598300D03*
Y595800D03*
Y590000D03*
Y592500D03*
X1307600Y620100D03*
X1357400Y-19800D03*
X1360400Y10600D03*
X1350654Y-18411D03*
X1348154Y-15911D03*
Y-18411D03*
X1357600Y5140D03*
X1345518Y-18476D03*
X1353154Y-18411D03*
X1375676Y7630D03*
X1385608Y-17485D03*
X1388294Y-5675D03*
X1389523Y4966D03*
X1355950Y-16507D03*
X1359450Y-7D03*
X1355950D03*
X1357489Y-1924D03*
X1359450Y2493D03*
X1355950D03*
X1357489Y-14424D03*
Y-10524D03*
Y-6124D03*
X1355889Y-8524D03*
X1355847Y-12275D03*
X1355989Y-3924D03*
X1356261Y32017D03*
X1356300Y20100D03*
X1356376Y24167D03*
X1356200Y28200D03*
X1357900Y30200D03*
X1357800Y26100D03*
X1357803Y22200D03*
X1356261Y15517D03*
X1357700Y17800D03*
X1359761Y32317D03*
X1371650Y-907D03*
X1371589Y-3424D03*
Y-5924D03*
X1371900Y28600D03*
Y26100D03*
Y31100D03*
X1369408Y50479D03*
X1375500Y76000D03*
X1397500Y51000D03*
X1365855Y46972D03*
X1359800Y37300D03*
X1357300D03*
X1361634Y95519D03*
X1347000Y87500D03*
X1343500D03*
X1360700Y86550D03*
X1344000Y83000D03*
X1402700Y51100D03*
X1381817Y46484D03*
X1388627Y35032D03*
X1380500Y54500D03*
X1380900Y59820D03*
X1372400Y37785D03*
X1389138Y58499D03*
X1370100Y82500D03*
X1366100D03*
X1364700Y86550D03*
X1389068Y78556D03*
X1389100Y74600D03*
X1350830Y60730D03*
X1356261Y34517D03*
X1356950Y54370D03*
X1356760Y66660D03*
X1357000Y60500D03*
X1359761Y34817D03*
X1350800Y66600D03*
X1351190Y54710D03*
X1363170Y54280D03*
X1362900Y60500D03*
X1363040Y66660D03*
X1380500Y50500D03*
X1356230Y126500D03*
X1359230D03*
X1360730Y129000D03*
X1362230Y126500D03*
X1355100Y155000D03*
Y145000D03*
Y150000D03*
X1360100Y155000D03*
Y145000D03*
Y150000D03*
X1361634Y97919D03*
X1345100Y150000D03*
X1350100Y155000D03*
Y150000D03*
Y145000D03*
X1345100D03*
Y155000D03*
X1397994Y103350D03*
X1397952Y105998D03*
X1395326Y100913D03*
Y103413D03*
X1395347Y106040D03*
X1386700Y125450D03*
Y128450D03*
X1383700Y125450D03*
Y128450D03*
X1380700Y125450D03*
Y128450D03*
X1376100Y116100D03*
X1376669Y121763D03*
Y118763D03*
X1376100Y124950D03*
X1373850Y114450D03*
X1369730Y129000D03*
X1363730D03*
X1366730D03*
X1373850Y117450D03*
X1368230Y126500D03*
X1373850Y123450D03*
X1365230Y126500D03*
X1397193Y112602D03*
X1394253Y116989D03*
X1385100Y155000D03*
X1375100D03*
X1365100D03*
X1380100D03*
Y145000D03*
X1385100D03*
X1380100Y150000D03*
X1385100D03*
X1365100Y145000D03*
Y150000D03*
X1375100D03*
X1370100Y155000D03*
Y145000D03*
X1375100D03*
X1370100Y150000D03*
X1352200Y104950D03*
Y108400D03*
X1357700D03*
Y104950D03*
X1373850Y120450D03*
X1380100Y160000D03*
X1360100D03*
X1355100D03*
X1345100D03*
X1350100D03*
X1390100D03*
X1370100D03*
X1390100Y170000D03*
X1385100Y160000D03*
Y165000D03*
Y170000D03*
X1365100Y160000D03*
X1375100D03*
X1390100Y165000D03*
X1383753Y265548D03*
X1397400Y234959D03*
X1391900D03*
X1386400D03*
X1358900D03*
X1353400D03*
X1347900D03*
X1349500Y265500D03*
X1359100Y265600D03*
X1380900Y234959D03*
X1369900D03*
X1364400D03*
X1375400Y235100D03*
X1369100Y265500D03*
X1374864Y265629D03*
X1398062Y315743D03*
X1403100Y321350D03*
X1383639Y315274D03*
X1389600Y315200D03*
X1384024Y320225D03*
X1386048Y310310D03*
X1386265Y304310D03*
X1389600Y320100D03*
X1397640Y310631D03*
X1397880Y304640D03*
X1392380D03*
X1392340Y310625D03*
X1403260Y310623D03*
X1403300Y304640D03*
X1388208Y341489D03*
X1348080Y309825D03*
X1353142Y309761D03*
X1358792Y309760D03*
X1358800Y303700D03*
X1353359Y303767D03*
X1348190Y303810D03*
X1346550Y322350D03*
X1350650Y315050D03*
X1357452Y319395D03*
X1369540Y310125D03*
X1374900Y310130D03*
X1381100Y304360D03*
X1380910Y310300D03*
X1364044Y309691D03*
X1364213Y303694D03*
X1375040Y304135D03*
X1369540D03*
X1371000Y322400D03*
X1363059Y314514D03*
X1368947Y313993D03*
X1358500Y338400D03*
X1370200D03*
X1364300Y338300D03*
X1392144Y364617D03*
X1389450Y372250D03*
X1384700Y359700D03*
X1392500Y344600D03*
X1392805Y360466D03*
X1388500Y350864D03*
X1391200Y386300D03*
X1384531Y382957D03*
X1394760Y394720D03*
X1362510Y360717D03*
X1354024Y398985D03*
X1352338Y404153D03*
X1351379Y399227D03*
X1352239Y401593D03*
X1358512Y371792D03*
X1360450Y402100D03*
X1359360Y398810D03*
X1357880Y403760D03*
X1356560Y398910D03*
X1362250Y399160D03*
X1354681Y401444D03*
X1354982Y404154D03*
X1357542Y401381D03*
X1364856Y366666D03*
X1382017Y367584D03*
X1363250Y401700D03*
X1371200Y402100D03*
X1381500Y396200D03*
X1375201Y396303D03*
X1365731Y360698D03*
X1358500Y374500D03*
X1360200Y377400D03*
X1358655Y379352D03*
X1362068Y393385D03*
X1360300Y381100D03*
X1360200Y384700D03*
Y389000D03*
X1358700Y386700D03*
X1358568Y390885D03*
Y393385D03*
X1358600Y382800D03*
X1362068Y390885D03*
X1374268Y389985D03*
X1374207Y384968D03*
Y387468D03*
X1370300Y350200D03*
X1358300Y344200D03*
X1358400Y350100D03*
X1370200Y343900D03*
X1364100Y350200D03*
X1385416Y410502D03*
X1404558Y416575D03*
X1402725Y408136D03*
X1402520Y413246D03*
X1388085Y410479D03*
X1403998Y429775D03*
X1404558Y421575D03*
X1398275Y453561D03*
X1397975Y457561D03*
X1403998Y434775D03*
X1382849Y410471D03*
X1380449Y410479D03*
X1358990Y411040D03*
X1358910Y408480D03*
X1358980Y406060D03*
X1355100Y427500D03*
Y432500D03*
X1361558Y410527D03*
X1345100Y442500D03*
X1350100D03*
X1345100Y437500D03*
X1350100D03*
X1355100D03*
Y442500D03*
X1369034Y458075D03*
X1369907Y410513D03*
X1372535Y410512D03*
X1375239Y410590D03*
X1377928Y410451D03*
X1366984Y410481D03*
X1364403Y410496D03*
X1380100Y447500D03*
X1370100Y442500D03*
X1365100Y452500D03*
X1379857Y458108D03*
X1365100Y442500D03*
X1375100D03*
X1380100Y452500D03*
X1365100Y447500D03*
X1388900Y525230D03*
X1395581Y525357D03*
X1383600Y482504D03*
X1386041Y493723D03*
X1383519Y487445D03*
X1390330Y516690D03*
X1385033Y516848D03*
X1387568Y516892D03*
X1388865Y519788D03*
X1388850Y522266D03*
X1386033Y498811D03*
X1344073Y508263D03*
X1363800Y481600D03*
X1363662Y486636D03*
X1365741Y492723D03*
X1382578Y516805D03*
X1377492Y516892D03*
X1369757Y517465D03*
X1365719Y497545D03*
X1352490Y515470D03*
X1346870Y515450D03*
X1352590Y519170D03*
X1346970Y519150D03*
X1401777Y557632D03*
X1385033Y544267D03*
X1390623Y574986D03*
X1400830Y564090D03*
X1400288Y570099D03*
X1404420Y576330D03*
X1404519Y560280D03*
Y557380D03*
X1361600Y559400D03*
X1358529Y537492D03*
X1361163Y540052D03*
X1358518Y540073D03*
X1356018D03*
X1356029Y537492D03*
X1363674Y537471D03*
X1355548Y559959D03*
X1361926Y584037D03*
Y586537D03*
X1359100Y586200D03*
X1357400Y588400D03*
X1360100D03*
X1344613Y556376D03*
Y561376D03*
Y558876D03*
X1347700Y554100D03*
X1353520Y537480D03*
X1344613Y553876D03*
X1361174Y537471D03*
X1358439Y559959D03*
X1375479Y540117D03*
X1375500Y537717D03*
X1366265Y537437D03*
X1363663Y540052D03*
X1363568Y550589D03*
X1380521Y535276D03*
X1378021D03*
X1375621Y535254D03*
X1371265Y537437D03*
X1368765D03*
X1366459Y550589D03*
X1377979Y537717D03*
Y540117D03*
X1380479Y537717D03*
X1368596Y539889D03*
X1371096D03*
X1366096D03*
X1380479Y540117D03*
X1376800Y584328D03*
X1364426Y586637D03*
Y584137D03*
X1360500Y570900D03*
Y574700D03*
X1360261Y578873D03*
X1360247Y567390D03*
X1360261Y562373D03*
Y581373D03*
X1362000Y576700D03*
Y572800D03*
X1362100Y569100D03*
X1362000Y565600D03*
X1363761Y581373D03*
X1375961Y577973D03*
X1376000Y575456D03*
Y572956D03*
X1387050Y615350D03*
X1392500Y592000D03*
X1376556Y615756D03*
X1357726Y591037D03*
X1360226D03*
X1363761Y612573D03*
X1360261D03*
X1360200Y597800D03*
X1361600Y599900D03*
X1361500Y595700D03*
X1360100Y610100D03*
X1360200Y606300D03*
Y602000D03*
X1361900Y608200D03*
X1361500Y604200D03*
X1360261Y593573D03*
X1363761Y610073D03*
X1375961Y609173D03*
X1375900Y604156D03*
Y606656D03*
X1454715Y2784D03*
X1450508Y2756D03*
X1410571Y13170D03*
X1420019Y13466D03*
X1448367Y13533D03*
X1438918D03*
X1429469Y13466D03*
X1457814D03*
X1436131Y5248D03*
X1432661Y5220D03*
X1406674Y46120D03*
X1411254Y46018D03*
X1412250Y65359D03*
X1407150Y58859D03*
X1410150D03*
X1407150Y52859D03*
X1410150D03*
X1409250Y65359D03*
X1407150Y55859D03*
X1410150D03*
X1413721Y36749D03*
X1412250Y68359D03*
X1409250D03*
X1409150Y71259D03*
X1412150D03*
X1442067Y34830D03*
X1423170Y36635D03*
X1432619Y34830D03*
X1451516D03*
X1460965D03*
X1452648Y103788D03*
X1451273Y148905D03*
X1449847Y202322D03*
X1439000Y208500D03*
X1442251Y180818D03*
X1418300Y199900D03*
X1440150Y175550D03*
X1440124Y166180D03*
X1451427Y167818D03*
X1434800Y248900D03*
X1462700Y221700D03*
X1464200Y231400D03*
X1458800Y254882D03*
X1410800Y316100D03*
X1408580Y310632D03*
X1408760Y304637D03*
X1410550Y320800D03*
X1419343Y310652D03*
X1419283Y304570D03*
X1413983Y304645D03*
X1413943Y310628D03*
X1417656Y367547D03*
X1420101Y396236D03*
X1418138Y386361D03*
X1415000Y399000D03*
X1412220Y388360D03*
X1417217Y379129D03*
X1417349Y382137D03*
X1417773Y374107D03*
X1464124Y353776D03*
X1465500Y395400D03*
X1456750Y381850D03*
X1459033Y395334D03*
X1446700Y387900D03*
X1437897Y402315D03*
X1443100Y368950D03*
X1439934Y403730D03*
X1411900Y429775D03*
X1405375Y453561D03*
X1405608Y456761D03*
X1411900Y434775D03*
X1435479Y423107D03*
X1439350Y406900D03*
X1459200Y459800D03*
Y454100D03*
X1459000Y449997D03*
X1451400Y454100D03*
Y459800D03*
X1445000Y437000D03*
X1429000Y437059D03*
X1444800Y442500D03*
X1444500Y448000D03*
X1429100Y453400D03*
X1429000Y448000D03*
Y442600D03*
X1448800Y427800D03*
X1412447Y416368D03*
X1412545Y421974D03*
X1413300Y454400D03*
X1413075Y457561D03*
X1448800Y416500D03*
X1464300Y404900D03*
X1439000Y423000D03*
X1464600Y428000D03*
X1459300Y430000D03*
X1464525Y420014D03*
X1464731Y432942D03*
X1445100Y431500D03*
X1459200Y465500D03*
X1451400D03*
X1408753Y527518D03*
X1415541Y489523D03*
X1416100Y483500D03*
X1415800Y477500D03*
Y495200D03*
X1420200Y520500D03*
X1447749Y485395D03*
X1439314Y477723D03*
X1439400Y483600D03*
X1439341Y489323D03*
X1453700Y501600D03*
X1458357Y523271D03*
X1461100Y523600D03*
X1439400Y494700D03*
X1409693Y560343D03*
X1412093D03*
X1410850Y564210D03*
X1410340Y570370D03*
X1407019Y557380D03*
X1412019D03*
X1409519D03*
X1406993Y560343D03*
X1447852Y575687D03*
X1445800Y574300D03*
X1445750Y539000D03*
X1461500Y540000D03*
X1439861Y540497D03*
X1461653Y580762D03*
X1461707Y583162D03*
X1461878Y585556D03*
X1441805Y570887D03*
X1443797Y572482D03*
X1422500Y579800D03*
X1414800D03*
X1461930Y587956D03*
X1409500Y538000D03*
X1420500Y549800D03*
X1420400Y538000D03*
X1462039Y590354D03*
X1462155Y592761D03*
X1465334Y618564D03*
X1451314Y623298D03*
X1458000Y623400D03*
X1455000D03*
X1461000D03*
X1442200D03*
X1445200D03*
X1448200D03*
X1463419Y606912D03*
X1527700Y6963D03*
X1506900Y3500D03*
X1469807Y2967D03*
X1473674Y2953D03*
X1476712Y13466D03*
X1467264Y13533D03*
X1492900Y4000D03*
X1489600D03*
X1495611Y13466D03*
X1486162Y13500D03*
X1470414Y34830D03*
X1479863D03*
X1497711Y34427D03*
X1489311Y34830D03*
X1499613Y84046D03*
X1515294Y91306D03*
X1523563Y93565D03*
X1511700Y84600D03*
X1482300Y118400D03*
X1469747Y148276D03*
X1483093Y130796D03*
X1523950Y104050D03*
X1523889Y99033D03*
X1523557Y116165D03*
X1523813Y120546D03*
X1523756Y108762D03*
X1501603Y108500D03*
X1499618Y124520D03*
X1497699Y112140D03*
X1511634Y121195D03*
X1511635Y114535D03*
X1511650Y109400D03*
Y103400D03*
X1511651Y98675D03*
X1500775Y98101D03*
X1501700Y103300D03*
X1513023Y140630D03*
X1511664Y133603D03*
X1488350Y149450D03*
X1523719Y149488D03*
X1499800Y199300D03*
X1491196Y218527D03*
X1523400Y217900D03*
X1483523Y181100D03*
X1517328Y186208D03*
X1527500Y167726D03*
X1502192Y164871D03*
X1494783Y177907D03*
X1469150Y242931D03*
X1479500Y238500D03*
X1498685Y224715D03*
X1491700Y241661D03*
X1491407Y258353D03*
X1523470Y242580D03*
X1472500Y341074D03*
X1526722Y295400D03*
X1501583Y339389D03*
X1521817Y330937D03*
X1526000Y341000D03*
X1517600Y320940D03*
X1487426Y330100D03*
X1514722Y293257D03*
X1515482Y280800D03*
X1512300Y280847D03*
X1511900Y287500D03*
X1472550Y397500D03*
X1470800Y402250D03*
X1472680Y380630D03*
X1483172Y351806D03*
X1474500Y365500D03*
X1478500D03*
X1483500D03*
X1482000Y395098D03*
Y399035D03*
Y383287D03*
Y387224D03*
X1473255Y376254D03*
X1528146Y349842D03*
X1519626Y365817D03*
X1488394Y365466D03*
X1497275Y401174D03*
X1508975D03*
X1483950Y401650D03*
X1491425Y391034D03*
X1503125Y377514D03*
X1491425D03*
X1526525D03*
X1514825D03*
X1526525Y384274D03*
Y391034D03*
X1514825Y384274D03*
X1520675Y387654D03*
Y380894D03*
X1514825Y391034D03*
X1508975Y387654D03*
Y380894D03*
X1503125Y384274D03*
Y391034D03*
X1497275Y380894D03*
X1491425Y384274D03*
X1497275Y387654D03*
Y394414D03*
X1491425Y397794D03*
X1503125D03*
X1508975Y394414D03*
X1514825Y397794D03*
X1524575Y401174D03*
X1491425Y418074D03*
X1487525D03*
X1472449Y439421D03*
X1467000Y454100D03*
Y459800D03*
X1466800Y449997D03*
X1467401Y411557D03*
X1471900Y406900D03*
X1472530Y432731D03*
X1472400Y428063D03*
X1472800Y420689D03*
X1467000Y465500D03*
X1482000Y418720D03*
Y406909D03*
Y410846D03*
Y414783D03*
Y422658D03*
Y426595D03*
X1483400Y438100D03*
X1482603Y442418D03*
X1482000Y462028D03*
X1483115Y454379D03*
X1483200Y450455D03*
X1482500Y434600D03*
X1503125Y404554D03*
X1509200Y413600D03*
X1510925Y404554D03*
X1497275Y414694D03*
X1503125Y424834D03*
X1497275Y428214D03*
X1495325Y424834D03*
X1503125Y433406D03*
X1491425D03*
X1495325D03*
X1524950Y419900D03*
X1518650D03*
X1483818Y430597D03*
X1528100Y410550D03*
X1501219Y416596D03*
X1487525Y404554D03*
X1526525D03*
X1515500Y416750D03*
X1518700Y406500D03*
X1491425Y404554D03*
X1495325Y411314D03*
X1512350Y445100D03*
X1509200D03*
Y454550D03*
X1512400Y454500D03*
X1503125Y440166D03*
X1501175Y436786D03*
X1495325Y440166D03*
X1497275Y436786D03*
X1510925Y460446D03*
X1505442Y443900D03*
X1507025Y460446D03*
X1503125Y453786D03*
Y460446D03*
X1501175Y457066D03*
X1487525Y453686D03*
X1497275Y457066D03*
Y450306D03*
X1495325Y446926D03*
Y453686D03*
X1497275Y443546D03*
X1501175Y463826D03*
X1493375D03*
X1515500Y445100D03*
X1514825Y460446D03*
X1520675Y457066D03*
X1518725Y460446D03*
X1521800Y441950D03*
Y448250D03*
X1526525Y460446D03*
X1522625D03*
X1524950Y441950D03*
X1473140Y525407D03*
X1482000Y481713D03*
Y469902D03*
X1476800Y498900D03*
X1482300D03*
X1476800Y507300D03*
X1481700Y524200D03*
X1473800Y495800D03*
X1499225Y480726D03*
X1508975Y477346D03*
X1510925Y480726D03*
X1508975Y470586D03*
X1510925Y473966D03*
X1505075Y470586D03*
X1501175D03*
X1503125Y467206D03*
X1507025Y487486D03*
X1487525Y473966D03*
X1491425D03*
X1489475Y470586D03*
X1490100Y489700D03*
X1487525Y487486D03*
X1489475Y484106D03*
X1516775D03*
X1514825Y480726D03*
Y473966D03*
X1516775Y470586D03*
X1518725Y487486D03*
Y480726D03*
Y473966D03*
Y467206D03*
X1522625D03*
Y473966D03*
Y487486D03*
X1526525D03*
Y473966D03*
Y467206D03*
X1514825Y487486D03*
X1511752Y498780D03*
X1490929Y507104D03*
X1506060Y508180D03*
X1501490Y504988D03*
X1501934Y513047D03*
X1505743Y516117D03*
X1511215Y507781D03*
X1512400Y519020D03*
X1493930Y522800D03*
X1488410Y517810D03*
X1497267Y505323D03*
X1496174Y514221D03*
X1509000Y498750D03*
X1488500Y498900D03*
X1526500Y498671D03*
Y506400D03*
X1485300Y498962D03*
X1483804Y509928D03*
X1484200Y524200D03*
X1475316Y527194D03*
X1468101Y573963D03*
X1527698Y578870D03*
X1474776Y572315D03*
X1491776Y573571D03*
X1479893Y572315D03*
X1482293D03*
X1477493D03*
X1487093D03*
X1489493D03*
X1484693D03*
X1518000Y562330D03*
X1510740Y557860D03*
X1494422Y574000D03*
X1481400Y539700D03*
X1494200Y530600D03*
X1497106Y531368D03*
X1511388Y531045D03*
X1503200Y530500D03*
X1505600D03*
X1508772Y530416D03*
X1514118Y530411D03*
X1483900Y539700D03*
X1525500Y582674D03*
Y580184D03*
X1525837Y574700D03*
X1523416Y573949D03*
X1527822Y576130D03*
X1525500Y577684D03*
X1499900Y574000D03*
X1496900D03*
X1469701Y599554D03*
X1470353Y592128D03*
X1469767Y596353D03*
X1503008Y620018D03*
X1472412Y596032D03*
Y599532D03*
X1479029Y596132D03*
X1477129Y597656D03*
X1474912Y596032D03*
X1480760Y611602D03*
X1485429Y597571D03*
X1491412Y596032D03*
X1489229Y597571D03*
X1487329Y596032D03*
X1512500Y598639D03*
X1510450Y597300D03*
X1507950D03*
X1510450Y600800D03*
X1508031Y599922D03*
X1524800Y598778D03*
X1522900Y597300D03*
X1526950D03*
X1518800Y597200D03*
X1520813Y598508D03*
X1516800Y598639D03*
X1514500Y597300D03*
X1511350Y613000D03*
X1513867Y612939D03*
X1516367D03*
X1475812Y611732D03*
X1474912Y599532D03*
X1478329Y611671D03*
X1483104Y596072D03*
X1481229Y597571D03*
X1584447Y-6702D03*
X1579447D03*
X1570200Y12900D03*
X1579773Y13257D03*
X1589259Y10241D03*
X1541400Y12500D03*
X1528384Y28040D03*
X1551309Y12792D03*
X1560700Y13000D03*
X1589500Y-600D03*
X1589900Y84422D03*
X1583621Y87213D03*
X1588700Y94288D03*
X1573473Y37216D03*
X1582923D03*
X1532800Y78590D03*
X1542179Y39695D03*
X1554573Y37216D03*
X1564023D03*
X1578000Y113000D03*
X1585500Y101000D03*
X1555000Y139000D03*
X1548955Y101358D03*
X1558189Y107067D03*
X1554800Y129100D03*
Y98200D03*
X1558100D03*
X1558383Y121500D03*
X1554945Y133400D03*
X1583600Y207495D03*
X1535399Y190920D03*
X1533132Y158068D03*
X1531565Y176645D03*
X1537298Y162703D03*
X1557634Y175948D03*
X1562079Y163580D03*
X1530200Y257200D03*
X1528460Y244371D03*
X1563440Y250955D03*
X1559577Y236300D03*
X1547000Y263500D03*
Y269400D03*
X1541000Y263500D03*
Y269500D03*
X1544000Y266500D03*
X1578630Y293430D03*
X1580150Y329483D03*
X1528250Y311900D03*
X1530033Y340799D03*
X1539400Y320200D03*
X1544904Y334008D03*
X1557250Y315410D03*
X1554800Y290600D03*
X1586400Y392900D03*
X1567475Y380894D03*
Y387654D03*
X1582420Y377830D03*
X1582350Y374567D03*
X1582124Y381164D03*
X1573000Y391161D03*
X1571366Y401154D03*
X1582000Y396250D03*
X1567475Y394414D03*
X1570672Y362134D03*
X1567121Y365817D03*
X1576380Y362890D03*
X1582500Y369600D03*
X1573521Y365500D03*
X1532375Y380894D03*
Y387654D03*
Y394414D03*
X1538225Y377514D03*
Y384274D03*
X1544075Y380894D03*
Y387654D03*
X1538225Y391034D03*
Y397794D03*
X1544075Y394414D03*
X1558996Y365817D03*
X1555775Y394414D03*
X1549925Y397794D03*
X1561625D03*
X1555775Y401174D03*
X1549925Y377514D03*
X1561625D03*
Y391034D03*
Y384274D03*
X1549925Y391034D03*
Y384274D03*
X1555775Y387654D03*
Y380894D03*
X1571375Y421454D03*
X1569425Y418074D03*
X1571375Y414694D03*
X1559675Y463826D03*
X1563575Y421454D03*
X1557725Y424834D03*
X1567475Y450306D03*
X1565525Y440166D03*
X1571375Y457066D03*
X1567475D03*
X1569425Y460446D03*
X1582200Y456200D03*
X1565525Y431594D03*
X1569425D03*
Y404554D03*
X1583208Y412815D03*
X1569425Y411314D03*
X1571390Y464480D03*
X1567475Y421454D03*
X1531250Y419900D03*
Y451400D03*
Y441950D03*
X1530425Y460446D03*
X1551875Y407934D03*
Y414694D03*
X1563575Y407934D03*
X1559675Y414694D03*
X1546025Y404554D03*
X1561625Y424834D03*
X1551990Y421158D03*
X1551875Y428214D03*
X1561625Y431594D03*
X1563575Y428214D03*
X1555775Y443546D03*
Y436786D03*
X1563575Y457066D03*
X1549938Y453714D03*
X1547975Y457066D03*
X1549925Y446926D03*
X1557725D03*
X1561625Y460446D03*
X1555775Y457066D03*
X1551875D03*
X1557725Y453686D03*
X1559675Y443546D03*
Y436786D03*
X1547975Y463826D03*
X1551875D03*
X1555775D03*
X1534400Y419900D03*
X1540700D03*
X1543850Y429350D03*
Y426200D03*
X1537550Y419900D03*
X1534325Y404554D03*
X1538225D03*
X1542125D03*
X1540700Y410450D03*
X1534400Y451400D03*
Y441950D03*
X1537550D03*
X1534325Y460446D03*
X1537550Y451400D03*
X1544075Y457066D03*
X1540175D03*
X1540700Y451400D03*
Y441950D03*
X1540175Y463826D03*
X1543850Y435650D03*
X1537550D03*
X1582644Y495077D03*
X1568600Y494500D03*
X1565210Y509160D03*
X1567817Y499735D03*
X1569425Y473966D03*
X1571375Y470586D03*
X1565525Y480726D03*
X1570062Y487039D03*
X1587970Y472370D03*
X1587433Y490425D03*
X1567475Y470586D03*
X1532375D03*
X1530425Y473966D03*
X1528475Y470586D03*
Y477346D03*
X1534180Y498580D03*
X1534039Y502906D03*
X1531580Y510790D03*
X1534325Y487486D03*
X1536275Y484106D03*
X1544075Y470586D03*
X1542125Y473966D03*
X1540175Y477346D03*
X1536275Y470586D03*
X1544075Y477346D03*
X1538225Y473966D03*
X1542475Y504400D03*
X1542425Y512200D03*
X1546025Y467206D03*
X1553825Y487486D03*
Y480726D03*
X1557725D03*
X1549925Y473966D03*
X1547975Y470586D03*
X1553825Y473966D03*
Y467206D03*
X1555775Y470586D03*
X1557725Y473966D03*
X1555775Y477346D03*
Y484106D03*
X1549925Y487486D03*
X1546025Y480726D03*
X1548300Y499000D03*
X1564600Y500414D03*
X1555424Y504609D03*
X1555832Y512288D03*
X1548300Y506600D03*
X1580360Y565524D03*
X1580400Y568000D03*
X1580300Y563000D03*
Y560500D03*
X1566000Y575820D03*
X1565940Y573120D03*
X1565800Y570600D03*
X1565600Y568100D03*
Y565700D03*
X1529944Y574725D03*
X1529894Y577342D03*
X1532354Y577283D03*
X1532642Y579853D03*
X1529600Y582300D03*
X1532400D03*
X1529942Y579853D03*
X1563800Y564100D03*
X1561300Y564000D03*
X1558800Y563900D03*
X1563448Y566766D03*
X1563432Y569340D03*
X1589604Y585896D03*
X1581704D03*
X1587504Y605496D03*
Y607996D03*
X1563827Y621376D03*
X1554800Y620910D03*
X1537711Y613397D03*
X1538679Y615641D03*
X1534928Y610532D03*
X1538337Y601097D03*
X1534948Y613302D03*
X1545000Y591100D03*
X1581704Y590196D03*
X1589604D03*
X1558800Y599300D03*
X1560400Y611600D03*
X1564300Y599400D03*
X1564400Y605500D03*
X1561700Y602200D03*
X1552400Y607600D03*
X1554900Y607100D03*
X1556200Y602400D03*
X1554400Y599300D03*
X1564300Y611500D03*
X1602504Y-17346D03*
X1646200Y5300D03*
X1646400Y13400D03*
X1597700Y9000D03*
X1615000Y12000D03*
X1634200Y9700D03*
X1627500Y11700D03*
X1608123Y13302D03*
X1619100Y6500D03*
X1626400Y4600D03*
X1606700D03*
X1636500D03*
X1591270Y93940D03*
X1592200Y37700D03*
X1590464Y77962D03*
X1637700Y67400D03*
X1639623Y38100D03*
X1649073Y38200D03*
X1620050Y35550D03*
X1608500Y72688D03*
X1606730Y84230D03*
X1632000Y83000D03*
X1625451Y84288D03*
X1605184Y61044D03*
X1610450Y37300D03*
X1627380Y36652D03*
X1630121Y37609D03*
X1595943Y71522D03*
X1603138Y65890D03*
X1602840Y37382D03*
X1635900Y83000D03*
X1595335Y98135D03*
X1641600Y96500D03*
X1638500D03*
X1595522Y127278D03*
X1650300Y195251D03*
X1648400Y214100D03*
X1643887Y181841D03*
X1604401Y213500D03*
X1618500Y181680D03*
X1625524Y184531D03*
X1635100Y182800D03*
X1620036Y196186D03*
X1635112Y195181D03*
X1605250Y197250D03*
X1591174Y225017D03*
X1640871Y235210D03*
X1608489Y252095D03*
X1635503Y340146D03*
X1629503D03*
X1603307Y393224D03*
X1591912Y391052D03*
X1650624Y357884D03*
X1650480Y368215D03*
X1642126Y357894D03*
X1642114Y368142D03*
X1601060Y401010D03*
X1599100Y399100D03*
X1610828Y381387D03*
X1596151D03*
X1596168Y375135D03*
X1609761Y372584D03*
X1613474Y391105D03*
X1620447Y373926D03*
X1610642Y375135D03*
X1608020Y356500D03*
X1619889Y352841D03*
X1607443Y398649D03*
X1629503Y346146D03*
X1635503Y346046D03*
X1632503Y343146D03*
X1621010Y435870D03*
X1620500Y463727D03*
X1634500Y418500D03*
X1603650Y415469D03*
X1646540Y441240D03*
X1604200Y464387D03*
X1594880Y494880D03*
X1646700Y480300D03*
X1639394Y507798D03*
X1627032Y510226D03*
X1627068Y512626D03*
X1606200Y487100D03*
X1623814Y471400D03*
X1614000Y469500D03*
X1617700Y489700D03*
X1615200D03*
X1611506Y474768D03*
X1620500Y475000D03*
X1603500Y495300D03*
X1597178Y472226D03*
X1599900Y487100D03*
X1603802Y487205D03*
X1629530Y496374D03*
X1644800Y532800D03*
X1636848Y533794D03*
X1649900Y583500D03*
X1638674Y556178D03*
X1622040Y554827D03*
X1609829Y556599D03*
X1624293Y561747D03*
X1615030Y584260D03*
X1610080Y561367D03*
X1603060Y582920D03*
X1603120Y578020D03*
X1599170Y572780D03*
X1602000Y565700D03*
X1590004Y605496D03*
Y607996D03*
X1601504Y591526D03*
X1613721Y592325D03*
X1614700Y597000D03*
X1615862Y605507D03*
X1601489Y602812D03*
X1601270Y597200D03*
X1602150Y610720D03*
X1654800Y13518D03*
X1711863Y13276D03*
X1672427Y9700D03*
X1664200Y5400D03*
X1656600Y6300D03*
X1664823Y13287D03*
X1685500Y3000D03*
X1682985Y2901D03*
X1675800Y4100D03*
X1702421Y13231D03*
X1684902Y13472D03*
X1691541Y13226D03*
X1700710Y73292D03*
X1700300Y94703D03*
X1672000Y51500D03*
X1669350Y69962D03*
X1709600Y45800D03*
X1692573Y85833D03*
X1702513Y79885D03*
X1668009Y37000D03*
X1706500D03*
X1678000D03*
X1687500D03*
X1696795Y38260D03*
X1658559Y37890D03*
X1659038Y95111D03*
X1659000Y85500D03*
X1670250Y87873D03*
X1674455Y169991D03*
X1677605Y169986D03*
X1687950Y186150D03*
X1708250Y164950D03*
X1671556Y208379D03*
X1657498Y277300D03*
Y267100D03*
X1657949Y257240D03*
X1653091Y331618D03*
X1652991Y318741D03*
Y323941D03*
X1657500Y287800D03*
X1657600Y304500D03*
X1681192Y454286D03*
X1668000Y416200D03*
X1695658Y486945D03*
X1694410Y499830D03*
X1692120Y501410D03*
X1699900Y512300D03*
X1709400Y513000D03*
X1652500Y575600D03*
X1667277Y535221D03*
X1698600Y584800D03*
X1664113Y548380D03*
X1658466D03*
X1661880Y583900D03*
X1686036Y548251D03*
X1677300Y550200D03*
X1680007Y547917D03*
X1669121Y547923D03*
X1708140Y547538D03*
X1697839Y545759D03*
X1709183Y588700D03*
X1654100Y615790D03*
X1653970Y607340D03*
X1652700Y591300D03*
Y600850D03*
X1662580Y593200D03*
X1661200Y601300D03*
Y607300D03*
X1730550Y21160D03*
X1721559Y13500D03*
X1730768Y13313D03*
X1763100Y21500D03*
X1768807Y21512D03*
X1753903Y22116D03*
X1749941Y21163D03*
X1741000Y21200D03*
X1715259Y35602D03*
X1715100Y46100D03*
X1713550Y56000D03*
X1716900Y87900D03*
X1753059Y35300D03*
X1735150Y60650D03*
X1748500Y79500D03*
X1748854Y58533D03*
X1717600Y46100D03*
X1724758Y38600D03*
X1720600Y70200D03*
X1733910Y38233D03*
X1757054Y66059D03*
X1758100Y37000D03*
X1749364Y38971D03*
X1743500Y39300D03*
X1768450Y77376D03*
X1765900Y83700D03*
X1754703Y84053D03*
X1771459Y52695D03*
X1733900Y92200D03*
X1754600Y109200D03*
X1767250Y99500D03*
Y104500D03*
X1770850Y109500D03*
X1714189Y159550D03*
X1714528Y190189D03*
X1758650Y158650D03*
X1750189Y159550D03*
X1745689D03*
X1741189D03*
X1727689D03*
X1723189D03*
X1718689D03*
X1732189D03*
X1736689D03*
X1745777Y179574D03*
X1751975Y179374D03*
X1739377D03*
X1733178Y179574D03*
X1758375D03*
X1764673Y179374D03*
X1770973Y179574D03*
X1726700Y179400D03*
X1740900Y198800D03*
X1744000D03*
X1769100Y209700D03*
X1765950Y209600D03*
X1769016Y198872D03*
X1765866Y198772D03*
X1731260Y209600D03*
X1740709D03*
X1756000Y210000D03*
X1753400Y209900D03*
X1743900Y209700D03*
X1728616Y198872D03*
X1753311Y198700D03*
X1756600Y198800D03*
X1731216Y198872D03*
X1763554Y237712D03*
X1762795Y232106D03*
X1772244D03*
X1752554Y237712D03*
X1771451D03*
X1724944Y250324D03*
X1727444D03*
X1771243Y250100D03*
X1729944Y250324D03*
X1768516Y249983D03*
X1744603Y232489D03*
X1753347Y232106D03*
X1763300Y250100D03*
X1766100Y447900D03*
X1762992Y447938D03*
X1740963Y448476D03*
X1753543Y448100D03*
X1750393Y448037D03*
X1737795Y448100D03*
X1722000Y513000D03*
X1742900Y485000D03*
X1734000Y488100D03*
X1755000Y485000D03*
X1748600D03*
X1749396Y493969D03*
X1751868Y494045D03*
X1770325Y490255D03*
X1773500Y472100D03*
X1767300Y472700D03*
X1765325Y490255D03*
X1758500Y493800D03*
X1760900Y472800D03*
X1772459Y467005D03*
X1769309D03*
X1759860D03*
X1756710D03*
X1747262D03*
X1744112D03*
X1734663D03*
X1729200Y519000D03*
X1733830Y502650D03*
X1768900Y521124D03*
X1749090Y513790D03*
X1740400Y496300D03*
X1726600Y519000D03*
X1728700Y502600D03*
X1713600Y513000D03*
X1756417Y563840D03*
X1746000Y574000D03*
X1718000Y587723D03*
X1749000Y552863D03*
X1769000Y576378D03*
X1742381Y585530D03*
X1730814Y568814D03*
X1733000Y560000D03*
X1767455Y571695D03*
X1767000Y563500D03*
X1728245Y585244D03*
X1746052Y614796D03*
X1724092Y618700D03*
X1772158Y610960D03*
X1750739Y618718D03*
X1742509Y595869D03*
X1742381Y591530D03*
X1763500Y599100D03*
X1727843Y597142D03*
X1732443Y592342D03*
Y597142D03*
X1727743Y592342D03*
X1832449Y-8950D03*
X1785612Y10729D03*
X1782371Y26832D03*
X1804508Y11858D03*
X1798676Y11726D03*
X1830344Y13397D03*
X1828824Y3699D03*
X1816693Y13331D03*
X1819800Y35500D03*
X1790700Y34900D03*
X1799774Y34890D03*
X1808444Y37152D03*
X1800000Y80000D03*
X1827000Y87000D03*
X1834300Y41100D03*
X1788200Y93000D03*
Y89000D03*
Y85000D03*
X1818383Y133277D03*
X1788448Y98820D03*
X1788648Y101490D03*
X1807745Y104500D03*
X1803400Y114000D03*
X1796059Y104402D03*
X1801366Y151937D03*
X1811348Y143448D03*
X1800264Y143789D03*
X1800000Y132627D03*
X1820648Y155537D03*
X1816348D03*
X1777172Y179374D03*
X1778466Y198772D03*
X1783572Y179574D03*
X1802369Y179374D03*
X1808769Y179574D03*
X1815000Y179300D03*
X1789870Y179374D03*
X1796170Y179574D03*
X1795348Y172037D03*
X1797848D03*
X1792748Y171937D03*
X1821367Y179574D03*
X1827565Y179174D03*
X1833388Y179500D03*
X1791150Y209600D03*
X1794300Y209700D03*
X1794216Y198872D03*
X1791066Y198772D03*
X1819457Y198872D03*
X1828700Y198800D03*
X1820349Y209586D03*
X1828950Y209600D03*
X1832274Y209734D03*
X1816266Y198772D03*
X1804166Y198472D03*
X1807751Y209586D03*
X1803072Y209728D03*
X1806821Y198600D03*
X1815670Y209728D03*
X1781700Y209700D03*
X1778550Y209600D03*
X1781616Y198872D03*
X1816348Y163437D03*
X1818500Y159500D03*
X1820648Y163437D03*
X1782452Y237712D03*
X1820281Y250498D03*
X1809281D03*
X1801384D03*
X1790383D03*
X1791141Y232106D03*
X1828936Y249900D03*
X1819488Y232106D03*
X1810040D03*
X1800591D03*
X1781693D03*
X1775590Y448100D03*
X1778740D03*
X1828600Y450100D03*
X1825984Y448030D03*
X1816535Y448300D03*
X1813385Y447945D03*
X1804000Y447900D03*
X1800787Y447943D03*
X1791338Y448400D03*
X1788189Y448300D03*
X1779700Y472100D03*
X1784525Y491830D03*
X1781907Y467005D03*
X1785057D03*
X1779303Y497246D03*
X1832301Y467005D03*
X1835550Y466870D03*
X1789774Y476403D03*
X1801500Y471055D03*
X1795164Y476406D03*
X1789525Y491830D03*
X1801125D03*
X1796125D03*
X1817325Y481320D03*
X1806600Y471055D03*
X1812325Y481320D03*
X1806975Y491630D03*
X1830220Y479950D03*
X1824960Y473980D03*
X1824125Y491830D03*
X1822852Y467005D03*
X1819702D03*
X1819125Y491830D03*
X1807104Y467005D03*
X1810254D03*
X1811975Y491630D03*
X1797655Y467005D03*
X1794505D03*
X1810508Y515900D03*
X1804000Y498176D03*
X1834540Y519600D03*
X1796400Y498000D03*
X1781510Y546362D03*
X1786500Y562200D03*
X1783700Y579200D03*
X1828800Y546500D03*
X1828700Y540252D03*
X1828900Y552300D03*
X1834000Y534900D03*
X1811704Y554341D03*
X1807600Y552047D03*
X1806200Y549200D03*
X1786900Y552500D03*
X1801200Y529800D03*
X1806200Y582900D03*
X1810387Y571435D03*
X1794000Y568800D03*
X1793320Y557968D03*
X1828700Y569474D03*
X1836281Y589122D03*
X1828800Y575600D03*
X1828875Y563674D03*
X1828824Y557663D03*
X1810385Y568821D03*
X1807958Y565690D03*
X1812452Y538501D03*
Y533601D03*
X1807852D03*
X1807752Y538501D03*
X1779000Y598900D03*
X1787500Y597791D03*
X1825014Y593695D03*
X1811500Y603500D03*
X1808152Y591601D03*
X1812852Y596401D03*
X1808252D03*
X1812852Y591601D03*
X1893094Y-10142D03*
X1838100Y3900D03*
X1889218Y43530D03*
Y53530D03*
X1846800Y95400D03*
X1847000Y86500D03*
X1848000Y56500D03*
X1850500D03*
X1890803Y63189D03*
X1884500Y79300D03*
X1882000D03*
X1895330Y64390D03*
X1877270Y63473D03*
X1880230Y76820D03*
X1879500Y79300D03*
X1880986Y53299D03*
X1860995Y84509D03*
X1856873Y91200D03*
X1856778Y87397D03*
X1864208Y87724D03*
X1864195Y84509D03*
X1864153Y91241D03*
X1860815Y91184D03*
X1875100Y51300D03*
X1872340Y147236D03*
X1895800Y149200D03*
X1885400Y147000D03*
X1878550Y99470D03*
X1882550D03*
X1894834Y139286D03*
X1863908Y140992D03*
X1878950Y137400D03*
X1871855Y104188D03*
X1856700Y110167D03*
X1869000Y153900D03*
X1887830Y102227D03*
X1852600Y97500D03*
X1887300Y121500D03*
X1850700Y156000D03*
X1875700Y115700D03*
Y121500D03*
X1881500Y115700D03*
Y121500D03*
Y127300D03*
X1887300D03*
X1875700D03*
X1887300Y115700D03*
X1846663Y153748D03*
X1839500Y212700D03*
X1857044Y186292D03*
X1863750Y163750D03*
X1868375Y171900D03*
X1846163Y168448D03*
X1886800Y210600D03*
X1871708Y213442D03*
X1854663Y158248D03*
X1846663D03*
X1852300Y252000D03*
X1858400Y251200D03*
X1843700Y253400D03*
X1839400Y450440D03*
X1838768Y454120D03*
X1847185Y454368D03*
X1860158Y450322D03*
X1864300Y447900D03*
X1882677Y447930D03*
X1895275Y454422D03*
X1898425Y447930D03*
Y454422D03*
X1845330Y466870D03*
X1843000Y505000D03*
X1857480Y466800D03*
X1861300D03*
X1881285Y467049D03*
X1849795Y493379D03*
X1850290Y486610D03*
X1872908Y471338D03*
X1870138Y485732D03*
X1852340Y509140D03*
X1877518Y527560D03*
X1889800Y580200D03*
X1878000Y539000D03*
X1861080Y537090D03*
X1842500Y534500D03*
X1844100Y551000D03*
X1848900Y545500D03*
X1878450Y548650D03*
X1870250Y541950D03*
X1896500Y555300D03*
X1879800Y579000D03*
X1858000Y574000D03*
X1870892Y583245D03*
X1874825Y564125D03*
X1859167Y559350D03*
X1894299Y557790D03*
X1906438Y-15968D03*
X1909406Y76790D03*
X1907986Y82393D03*
X1907929Y84793D03*
X1907907Y87223D03*
X1918379Y84788D03*
X1905501Y79790D03*
X1902796Y79820D03*
X1900100Y145100D03*
X1921199Y140499D03*
X1929711Y155759D03*
X1904136Y140160D03*
X1937000Y150000D03*
X1906871Y106049D03*
X1911231Y137097D03*
X1908715Y104512D03*
X1912100Y142600D03*
X1915030Y147250D03*
X1911440Y128840D03*
X1952440Y98520D03*
X1942637Y100877D03*
X1914152Y115928D03*
X1950983Y147344D03*
X1928100Y136078D03*
X1953200Y195530D03*
X1937100Y206800D03*
X1908967Y201609D03*
X1909186Y211906D03*
X1944500Y183900D03*
X1903524Y208156D03*
X1905074Y198163D03*
X1943200Y214800D03*
X1928400Y212500D03*
X1926000Y212400D03*
X1933898Y216707D03*
X1945156Y160236D03*
X1950994Y173745D03*
X1939316Y173600D03*
X1900740Y178720D03*
X1900700Y172990D03*
Y167290D03*
X1906440Y178720D03*
X1906500Y173100D03*
X1906400Y167290D03*
X1912190Y178870D03*
X1912230Y167330D03*
Y173030D03*
X1946105Y230344D03*
X1902909Y223195D03*
X1943517Y223637D03*
X1943800Y241800D03*
X1943900Y238500D03*
X1934750Y242700D03*
Y240300D03*
X1925600Y242700D03*
X1929000Y445800D03*
X1910500Y435600D03*
X1927100Y436200D03*
X1930100D03*
X1904724Y454422D03*
X1901574Y447930D03*
X1907500Y435600D03*
X1911023Y448400D03*
X1907874Y454422D03*
Y448400D03*
X1933100Y436200D03*
X1957100Y502990D03*
X1955790Y499790D03*
X1947380Y482450D03*
X1915100Y480050D03*
X1905010Y479410D03*
X1939000Y479400D03*
X1952500Y508000D03*
X1959260Y506010D03*
X1938410Y490650D03*
X1929480Y472880D03*
X1905000Y533900D03*
X1906050Y569100D03*
X1923600Y554200D03*
X1955400Y530500D03*
X1923600Y572300D03*
X1908400Y556800D03*
X1915593Y576807D03*
X1953500Y551900D03*
X1943300Y535700D03*
X1921800Y586100D03*
X1936770Y607210D03*
X1906200Y607800D03*
X1916050Y604450D03*
X1924000Y611391D03*
X1968179Y77969D03*
X1965679D03*
Y75369D03*
X1968179D03*
X1965679Y82969D03*
Y80469D03*
X1968179D03*
X1966212Y72897D03*
X1970679Y75369D03*
Y80469D03*
Y77969D03*
X1962800Y143700D03*
X1971200Y152500D03*
X1965400Y149700D03*
X1961472Y165760D03*
X1967817Y201029D03*
X1965900Y184600D03*
X1965057Y176447D03*
X1966542Y179606D03*
X1965973Y166190D03*
X1970270Y474640D03*
X1968870Y481710D03*
X1970500Y502720D03*
X1963500Y521000D03*
X1961500Y561700D03*
Y582700D03*
X1972700Y552700D03*
G54D40*
X1952756Y605708D03*
G54D22*
X320784Y203219D03*
X330948Y201258D03*
X458640Y200596D03*
X970392Y203219D03*
X980556Y201258D03*
X1108248Y200596D03*
X1111631Y198327D03*
X1451753Y276753D03*
X1454902Y279902D03*
X1445454Y270454D03*
X1448603Y273603D03*
X1454902Y305098D03*
X1448603Y311397D03*
X1458051Y301949D03*
X1464351Y295649D03*
Y289351D03*
X1458051Y283051D03*
X1489546Y270454D03*
X1486397Y273603D03*
X1483247Y276753D03*
X1470649Y295649D03*
Y289351D03*
X1480098Y305098D03*
X1476949Y301949D03*
X1486397Y311397D03*
X1489546Y314546D03*
X1483247Y308247D03*
X1476949Y283051D03*
X1606470Y93759D03*
X1638938Y109192D03*
X1638250Y125750D03*
X1651536Y121790D03*
X1638938Y118641D03*
X1645378Y128378D03*
X1638902Y112305D03*
X1648430Y150163D03*
X1638937Y131239D03*
Y143837D03*
Y137538D03*
X1638938Y153286D03*
X1616900Y153200D03*
X1629489Y150136D03*
X1616891Y146987D03*
X1616893Y140782D03*
X1635788Y137538D03*
Y143837D03*
Y131239D03*
X1616891Y134389D03*
X1629489Y137538D03*
Y143837D03*
Y131239D03*
X1620040Y106042D03*
X1623189Y118640D03*
X1629489D03*
X1610793Y109190D03*
X1607441Y118640D03*
X1616891Y124939D03*
X1596220Y109470D03*
X1613741Y115491D03*
X1602717Y102240D03*
X1620040Y162735D03*
X1627998Y172854D03*
X1601142Y172185D03*
X1674685Y134217D03*
X1693625Y133220D03*
X1680402Y128652D03*
X1678127Y117293D03*
X1673883Y124308D03*
X1654685Y146987D03*
X1654678Y137530D03*
X1657835Y134389D03*
X1671000Y103000D03*
X1709000Y127200D03*
X1691207Y139891D03*
X1667284Y137537D03*
X1657835Y124940D03*
Y150136D03*
X1667284Y121790D03*
Y128089D03*
Y150136D03*
X1664134Y140688D03*
X1668213Y172608D03*
X1729444Y123782D03*
X1726294Y101785D03*
X1742212Y117451D03*
X1717014Y108000D03*
Y139500D03*
X1739064Y108000D03*
X1742214Y101700D03*
X1745364Y114300D03*
X1755089Y150750D03*
X1752189Y136750D03*
X1752389Y132250D03*
X1754189Y124250D03*
X1757689Y123850D03*
X1752889Y146250D03*
X1745364Y145800D03*
X1731903Y133712D03*
X1720164Y97550D03*
Y111150D03*
X1723314D03*
Y117450D03*
X1720164Y120600D03*
Y133200D03*
Y126800D03*
X1751800Y141700D03*
X1742214Y98550D03*
Y126900D03*
X1745364Y120600D03*
X1742214Y111150D03*
X1739064Y114300D03*
G54D13*
X-15748Y101221D03*
Y148465D03*
Y357362D03*
Y373110D03*
Y388858D03*
Y404606D03*
X12205Y156339D03*
X-4331D03*
X17323Y101221D03*
Y116969D03*
Y132717D03*
Y148465D03*
X787Y101221D03*
Y116969D03*
Y148465D03*
X33858Y101221D03*
Y116969D03*
Y132717D03*
Y148465D03*
X28740Y109095D03*
Y156339D03*
X12205Y109095D03*
Y140591D03*
X-4331Y109095D03*
Y124843D03*
Y140591D03*
X17323Y357362D03*
Y373110D03*
Y388858D03*
Y404606D03*
X787Y357362D03*
Y373110D03*
Y388858D03*
Y404606D03*
X33858Y357362D03*
Y373110D03*
Y388858D03*
Y404606D03*
X28740Y365236D03*
Y380984D03*
Y396732D03*
X12205Y365236D03*
Y380984D03*
Y396732D03*
X-4331Y365236D03*
Y380984D03*
Y396732D03*
X12205Y412480D03*
X-4331D03*
X28740D03*
G54D31*
X1895945Y21654D03*
G54D41*
X1969883Y207007D03*
Y242441D03*
G54D32*
X1887327Y511202D03*
X1929453Y532541D03*
G54D14*
X30500Y-42250D03*
Y-52250D03*
X12290Y264640D03*
X18450Y267010D03*
X22970Y244400D03*
X28720Y244450D03*
X17120Y244220D03*
X24200Y267060D03*
X50500Y-42250D03*
X70500D03*
X90500D03*
X110500D03*
X50500Y-52250D03*
X70500D03*
X90500D03*
X110500D03*
X130500Y-42250D03*
Y-52250D03*
X457246Y-52301D03*
Y-42301D03*
X477246Y-52301D03*
Y-42301D03*
X497246Y-52301D03*
Y-42301D03*
X517246Y-52301D03*
Y-42301D03*
X537246Y-52301D03*
Y-42301D03*
X557246Y-52301D03*
Y-42301D03*
X788984Y-52057D03*
Y-42057D03*
X808984Y-52057D03*
Y-42057D03*
X828984Y-52057D03*
Y-42057D03*
X848984Y-52057D03*
Y-42057D03*
X868984Y-52057D03*
Y-42057D03*
X888984Y-52057D03*
Y-42057D03*
X1125583Y-52285D03*
Y-42285D03*
X1145583Y-52285D03*
Y-42285D03*
X1382258Y-52257D03*
Y-42257D03*
X1402258Y-52257D03*
Y-42257D03*
X1422258Y-52257D03*
Y-42257D03*
X1442258Y-52257D03*
Y-42257D03*
G54D23*
X1392264Y23976D03*
X1513918D03*
G54D33*
X1887327Y532541D03*
X1929453Y511202D03*
G54D15*
X18228Y178386D03*
X-1969D03*
X44291D03*
G54D24*
X1526871Y23968D03*
X1819665Y618663D03*
X1881595Y23968D03*
G54D42*
G01X-9569Y-9569D02*
X0Y0D01*
G01D02*
X9569Y9569D01*
G01X-9569D02*
X0Y0D01*
G01D02*
X9569Y-9569D01*
G01X1602685Y292308D02*
X1613069Y302692D01*
G01D02*
X1623453Y313076D01*
G01X1602685D02*
X1613069Y302692D01*
G01D02*
X1623453Y292308D01*
X1961890Y211043D03*
Y238405D03*
G54D43*
G01X105174Y102925D02*
X107249Y105000D01*
G01D02*
X109324Y107075D01*
G01X105174D02*
X107249Y105000D01*
G01D02*
X109324Y102925D01*
G01X1562041Y-17959D02*
X1565000Y-15000D01*
G01D02*
X1567959Y-12041D01*
G01X1562041D02*
X1565000Y-15000D01*
G01D02*
X1567959Y-17959D01*
G01X1684953Y534539D02*
X1687205Y536791D01*
G01D02*
X1689457Y539043D01*
G01X1684953D02*
X1687205Y536791D01*
G01D02*
X1689457Y534539D01*
G01X1699953D02*
X1702205Y536791D01*
G01D02*
X1704457Y539043D01*
G01X1699953D02*
X1702205Y536791D01*
G01D02*
X1704457Y534539D01*
G01X1747417Y534680D02*
X1749528Y536791D01*
G01D02*
X1751639Y538902D01*
G01X1747417D02*
X1749528Y536791D01*
G01D02*
X1751639Y534680D01*
G01X1751354D02*
X1753465Y536791D01*
G01D02*
X1755576Y538902D01*
G01X1751354D02*
X1753465Y536791D01*
G01D02*
X1755576Y534680D01*
G01X1714953Y534539D02*
X1717205Y536791D01*
G01D02*
X1719457Y539043D01*
G01X1714953D02*
X1717205Y536791D01*
G01D02*
X1719457Y534539D01*
G01X1816918Y615916D02*
X1819665Y618663D01*
G01D02*
X1822412Y621410D01*
G01X1816918D02*
X1819665Y618663D01*
G01D02*
X1822412Y615916D01*
G01X1893410Y19119D02*
X1895945Y21654D01*
G01X1893410Y24189D02*
X1895945Y21654D01*
G01X1891282Y490182D02*
X1894100Y493000D01*
G01D02*
X1896918Y495818D01*
G01X1891282D02*
X1894100Y493000D01*
G01D02*
X1896918Y490182D01*
G01X1897500Y579500D02*
X1900106Y576894D01*
G01X1848892Y558642D02*
X1851250Y561000D01*
G01D02*
X1853608Y563358D01*
G01X1848892D02*
X1851250Y561000D01*
G01D02*
X1853608Y558642D01*
G01X1848892Y574390D02*
X1851250Y576748D01*
G01D02*
X1853608Y579106D01*
G01X1848892D02*
X1851250Y576748D01*
G01D02*
X1853608Y574390D01*
G01X1888268Y599287D02*
X1891086Y602105D01*
G01D02*
X1893904Y604923D01*
G01X1888268D02*
X1891086Y602105D01*
G01D02*
X1893904Y599287D01*
G01X1919960Y516040D02*
X1922248Y518328D01*
G01D02*
X1924536Y520616D01*
G01X1919960D02*
X1922248Y518328D01*
G01D02*
X1924536Y516040D01*
G01X1898000Y589409D02*
X1900606Y586803D01*
G01X1950115Y603067D02*
X1952756Y605708D01*
G01D02*
X1955397Y608349D01*
G01X1950115D02*
X1952756Y605708D01*
G01D02*
X1955397Y603067D01*
G54D34*
X1851250Y576748D03*
Y561000D03*
G54D25*
X1565000Y-15000D03*
X1723503Y-5000D03*
Y-15000D03*
X1753503Y-5000D03*
Y-15000D03*
G54D16*
X3937Y204370D03*
X-3937D03*
X-11811D03*
X35433D03*
X27559D03*
X19685D03*
X3937Y227992D03*
X-3937D03*
X-11811D03*
X35433D03*
X27559D03*
X19685D03*
X3937Y313504D03*
X-3937D03*
X-11811D03*
X3937Y337126D03*
X-3937D03*
X-11811D03*
X35433D03*
X27559D03*
X19685D03*
X35433Y313504D03*
X27559D03*
X19685D03*
G54D44*
G01X1887327Y508300D02*
Y511202D01*
G01D02*
Y514104D01*
G01X1883225Y511202D02*
X1887327D01*
G01D02*
X1891429D01*
G01X1887327Y529639D02*
Y532541D01*
G01D02*
Y535443D01*
G01X1881825Y532541D02*
X1887327D01*
G01D02*
X1892829D01*
G01X1929453Y508300D02*
Y511202D01*
G01D02*
Y514104D01*
G01X1923951Y511202D02*
X1929453D01*
G01D02*
X1934955D01*
G54D35*
X1952756Y-14960D03*
Y58268D03*
G54D26*
X1647327Y-315D03*
G54D17*
X15512Y434094D03*
X119980Y145531D03*
G54D45*
G01X548049Y-193422D02*
Y-210922D01*
G01X543027Y-193422D02*
X553071D01*
G01X565549Y-199256D02*
Y-210922D01*
G01Y-194589D02*
X565112Y-194297D01*
Y-193714D01*
X565549Y-193422D01*
X565986Y-193714D01*
Y-194297D01*
X565549Y-194589D01*
G01X583049Y-210922D02*
X581739Y-210630D01*
X580429Y-209464D01*
X579555Y-207422D01*
X579119Y-205089D01*
X579555Y-202755D01*
X580429Y-200714D01*
X581739Y-199547D01*
X583049Y-199256D01*
X584359Y-199547D01*
X585669Y-200714D01*
X586542Y-202755D01*
X586761Y-205089D01*
X586542Y-207422D01*
X585669Y-209464D01*
X584359Y-210630D01*
X583049Y-210922D01*
G01X597492Y-215297D02*
X599021Y-216464D01*
X600767Y-216755D01*
X602295Y-216464D01*
X603606Y-215006D01*
X604479Y-212964D01*
Y-199256D01*
G01Y-201589D02*
X603606Y-200422D01*
X602295Y-199547D01*
X600767Y-199256D01*
X599021Y-199839D01*
X597929Y-201005D01*
X597055Y-203047D01*
X596619Y-205089D01*
X596837Y-206839D01*
X597711Y-208881D01*
X599021Y-210339D01*
X600767Y-210922D01*
X602077Y-210630D01*
X603606Y-209464D01*
X604479Y-208298D01*
G01X621979Y-210922D02*
Y-199256D01*
G01Y-201297D02*
X621106Y-200131D01*
X619795Y-199547D01*
X618267Y-199256D01*
X616739Y-199839D01*
X615429Y-201005D01*
X614555Y-202755D01*
X614119Y-205089D01*
X614555Y-207422D01*
X615429Y-209172D01*
X616739Y-210339D01*
X618267Y-210922D01*
X619795Y-210630D01*
X621106Y-209756D01*
X621979Y-208589D01*
G01X648682Y-210922D02*
Y-193422D01*
X653922D01*
X655669Y-194297D01*
X656979Y-196339D01*
X657416Y-198672D01*
X656979Y-201005D01*
X655887Y-202755D01*
X653922Y-203631D01*
X648682D01*
G01X674479Y-210922D02*
Y-199256D01*
G01Y-201297D02*
X673606Y-200131D01*
X672295Y-199547D01*
X670767Y-199256D01*
X669239Y-199839D01*
X667929Y-201005D01*
X667055Y-202755D01*
X666619Y-205089D01*
X667055Y-207422D01*
X667929Y-209172D01*
X669239Y-210339D01*
X670767Y-210922D01*
X672295Y-210630D01*
X673606Y-209756D01*
X674479Y-208589D01*
G01X684774Y-208881D02*
X685866Y-210047D01*
X687394Y-210922D01*
X688704D01*
X690014Y-210339D01*
X690887Y-209464D01*
X691324Y-208298D01*
X691106Y-206547D01*
X690232Y-205672D01*
X686302Y-203922D01*
X685429Y-201880D01*
X685866Y-200422D01*
X686739Y-199547D01*
X688049Y-199256D01*
X689359Y-199547D01*
X690669Y-200422D01*
G01X702274Y-208881D02*
X703366Y-210047D01*
X704894Y-210922D01*
X706204D01*
X707514Y-210339D01*
X708387Y-209464D01*
X708824Y-208298D01*
X708606Y-206547D01*
X707732Y-205672D01*
X703802Y-203922D01*
X702929Y-201880D01*
X703366Y-200422D01*
X704239Y-199547D01*
X705549Y-199256D01*
X706859Y-199547D01*
X708169Y-200422D01*
G01X735746Y-210922D02*
Y-193422D01*
X740112D01*
X741859Y-194297D01*
X743169Y-195464D01*
X744261Y-197213D01*
X745134Y-199256D01*
X745352Y-202172D01*
X745134Y-205089D01*
X744261Y-207131D01*
X743169Y-208881D01*
X741859Y-210047D01*
X740112Y-210922D01*
X735746D01*
G01X752590Y-193422D02*
X758049Y-210922D01*
X763508Y-193422D01*
G01X775549D02*
Y-210922D01*
G01X770527Y-193422D02*
X780571D01*
G01X804872Y-210922D02*
Y-193422D01*
X810549Y-208005D01*
X816226Y-193422D01*
Y-210922D01*
G01X829795Y-201589D02*
X830669Y-200714D01*
X831324Y-199256D01*
X831761Y-197213D01*
X831324Y-195464D01*
X830451Y-194297D01*
X828922Y-193422D01*
X823027D01*
Y-210922D01*
X830232D01*
X831761Y-209756D01*
X832634Y-208005D01*
X833071Y-205964D01*
X832634Y-203922D01*
X831324Y-202172D01*
X829795Y-201589D01*
X823027D01*
G01X647372Y-165922D02*
Y-148422D01*
X653049Y-163005D01*
X658726Y-148422D01*
Y-165922D01*
G01X670549D02*
X669239Y-165630D01*
X667929Y-164464D01*
X667055Y-162422D01*
X666619Y-160089D01*
X667055Y-157755D01*
X667929Y-155714D01*
X669239Y-154547D01*
X670549Y-154256D01*
X671859Y-154547D01*
X673169Y-155714D01*
X674042Y-157755D01*
X674261Y-160089D01*
X674042Y-162422D01*
X673169Y-164464D01*
X671859Y-165630D01*
X670549Y-165922D01*
G01X691979Y-148422D02*
Y-165922D01*
G01Y-163298D02*
X691106Y-164756D01*
X689795Y-165630D01*
X688267Y-165922D01*
X686521Y-165339D01*
X685211Y-163881D01*
X684337Y-162131D01*
X684119Y-160089D01*
X684337Y-158047D01*
X685211Y-156297D01*
X686521Y-154839D01*
X688267Y-154256D01*
X689795Y-154547D01*
X690887Y-155131D01*
X691979Y-156297D01*
G01X702274Y-158047D02*
X709261D01*
X708606Y-156005D01*
X707514Y-154839D01*
X705986Y-154256D01*
X704457Y-154547D01*
X703147Y-155422D01*
X702274Y-157464D01*
X701837Y-159214D01*
Y-160964D01*
X702274Y-162714D01*
X703366Y-164464D01*
X704676Y-165630D01*
X706204Y-165922D01*
X707732Y-165339D01*
X709261Y-163589D01*
G01X723049Y-165922D02*
Y-148422D01*
G01X975549Y-210922D02*
Y-193422D01*
X972929Y-196922D01*
G01Y-210922D02*
X978169D01*
G01X988246Y-208298D02*
X989555Y-209756D01*
X991084Y-210630D01*
X993049Y-210922D01*
X995014Y-210339D01*
X996542Y-209172D01*
X997634Y-207131D01*
X997852Y-204797D01*
X997416Y-202464D01*
X996324Y-201005D01*
X994795Y-199839D01*
X993267Y-199547D01*
X991739Y-199839D01*
X989774Y-201005D01*
X990429Y-193422D01*
X996324D01*
G01X1010549Y-210922D02*
Y-193422D01*
X1007929Y-196922D01*
G01Y-210922D02*
X1013169D01*
G01X1023901Y-196339D02*
X1025211Y-194589D01*
X1026739Y-193714D01*
X1028486Y-193422D01*
X1030669Y-194005D01*
X1032197Y-195464D01*
X1032634Y-197213D01*
X1032416Y-198964D01*
X1031542Y-200422D01*
X1027176Y-203339D01*
X1025211Y-205380D01*
X1023901Y-208298D01*
X1023464Y-210922D01*
X1032634D01*
G01X1041401Y-203631D02*
X1042929Y-201589D01*
X1044239Y-200422D01*
X1045986Y-199839D01*
X1047514Y-200422D01*
X1048606Y-201589D01*
X1049479Y-203339D01*
X1049697Y-205380D01*
X1049479Y-207131D01*
X1048606Y-208881D01*
X1047295Y-210339D01*
X1045767Y-210922D01*
X1044021Y-210339D01*
X1042492Y-208589D01*
X1041619Y-205964D01*
X1041401Y-203047D01*
X1041837Y-199256D01*
X1042492Y-197213D01*
X1043584Y-195172D01*
X1045112Y-193714D01*
X1046641Y-193422D01*
X1048169Y-194005D01*
X1049261Y-195464D01*
G01X962432Y-165922D02*
Y-148422D01*
X967672D01*
X969419Y-149297D01*
X970729Y-151339D01*
X971166Y-153672D01*
X970729Y-156005D01*
X969637Y-157755D01*
X967672Y-158631D01*
X962432D01*
G01X989102Y-149881D02*
X987792Y-149005D01*
X986264Y-148422D01*
X984517D01*
X982552Y-149297D01*
X981024Y-150755D01*
X979932Y-152506D01*
X979059Y-155422D01*
X978840Y-158047D01*
X979277Y-160672D01*
X979932Y-162422D01*
X981242Y-164172D01*
X982771Y-165339D01*
X984299Y-165922D01*
X985827D01*
X987356Y-165339D01*
X988666Y-164464D01*
X989758Y-163298D01*
G01X1003545Y-156589D02*
X1004419Y-155714D01*
X1005074Y-154256D01*
X1005511Y-152213D01*
X1005074Y-150464D01*
X1004201Y-149297D01*
X1002672Y-148422D01*
X996777D01*
Y-165922D01*
X1003982D01*
X1005511Y-164756D01*
X1006384Y-163005D01*
X1006821Y-160964D01*
X1006384Y-158922D01*
X1005074Y-157172D01*
X1003545Y-156589D01*
X996777D01*
G01X1012749Y-171755D02*
X1025849D01*
G01X1031777Y-165922D02*
Y-148422D01*
X1041821Y-165922D01*
Y-148422D01*
G01X1054299Y-165922D02*
X1052552Y-165630D01*
X1051024Y-164464D01*
X1049714Y-162714D01*
X1048840Y-160672D01*
X1048404Y-158339D01*
Y-156005D01*
X1048840Y-153672D01*
X1049714Y-151630D01*
X1051024Y-149881D01*
X1052552Y-148714D01*
X1054299Y-148422D01*
X1056045Y-148714D01*
X1057574Y-149881D01*
X1058884Y-151630D01*
X1059758Y-153672D01*
X1060194Y-156005D01*
Y-158339D01*
X1059758Y-160672D01*
X1058884Y-162714D01*
X1057574Y-164464D01*
X1056045Y-165630D01*
X1054299Y-165922D01*
G01X1128099Y-210922D02*
Y-193422D01*
X1125479Y-196922D01*
G01Y-210922D02*
X1130719D01*
G01X1147345Y-201589D02*
X1148219Y-200714D01*
X1148874Y-199256D01*
X1149311Y-197213D01*
X1148874Y-195464D01*
X1148001Y-194297D01*
X1146472Y-193422D01*
X1140577D01*
Y-210922D01*
X1147782D01*
X1149311Y-209756D01*
X1150184Y-208005D01*
X1150621Y-205964D01*
X1150184Y-203922D01*
X1148874Y-202172D01*
X1147345Y-201589D01*
X1140577D01*
G01X1105140Y-148422D02*
X1110599Y-165922D01*
X1116058Y-148422D01*
G01X1132466Y-165922D02*
X1123732D01*
Y-148422D01*
X1132466D01*
G01X1128972Y-156880D02*
X1123732D01*
G01X1141232Y-165922D02*
Y-148422D01*
X1146691D01*
X1148437Y-149297D01*
X1149529Y-150464D01*
X1149966Y-152797D01*
X1149529Y-155131D01*
X1148219Y-156589D01*
X1146691Y-157464D01*
X1141232D01*
G01X1146691D02*
X1149966Y-165922D01*
G01X1163099Y-166505D02*
X1162662Y-166214D01*
Y-165630D01*
X1163099Y-165339D01*
X1163536Y-165630D01*
Y-166214D01*
X1163099Y-166505D01*
G01X1326166Y-193422D02*
Y-210922D01*
X1317432D01*
G01X1304299D02*
Y-193422D01*
X1306919Y-196922D01*
G01Y-210922D02*
X1301679D01*
G01X1291602Y-207422D02*
X1290293Y-209464D01*
X1288546Y-210630D01*
X1286581Y-210922D01*
X1284834Y-210630D01*
X1283087Y-209172D01*
X1281996Y-207422D01*
X1281777Y-205672D01*
X1282214Y-203631D01*
X1283742Y-202172D01*
X1285271Y-201589D01*
X1287236D01*
G01X1285271D02*
X1283961Y-200714D01*
X1282869Y-199256D01*
X1282432Y-197506D01*
X1282869Y-195755D01*
X1283961Y-194297D01*
X1285926Y-193422D01*
X1287891Y-193714D01*
X1289856Y-194881D01*
G01X1267989Y-202172D02*
X1263622D01*
Y-207422D01*
X1264932Y-209172D01*
X1266461Y-210339D01*
X1268644Y-210922D01*
X1270827Y-210339D01*
X1272356Y-209172D01*
X1273666Y-207422D01*
X1274539Y-205380D01*
X1274976Y-203047D01*
Y-201005D01*
X1274539Y-199256D01*
X1273666Y-197213D01*
X1272356Y-195464D01*
X1271046Y-194297D01*
X1269299Y-193422D01*
X1267771D01*
X1266024Y-194005D01*
X1264714Y-195172D01*
G01X1256821Y-210922D02*
Y-193422D01*
X1246777Y-210922D01*
Y-193422D01*
G01X1239102Y-210922D02*
Y-193422D01*
X1234736D01*
X1232989Y-194297D01*
X1231679Y-195464D01*
X1230587Y-197213D01*
X1229714Y-199256D01*
X1229496Y-202172D01*
X1229714Y-205089D01*
X1230587Y-207131D01*
X1231679Y-208881D01*
X1232989Y-210047D01*
X1234736Y-210922D01*
X1239102D01*
G01X1238682Y-148422D02*
Y-165922D01*
X1247416D01*
G01X1264479D02*
Y-154256D01*
G01Y-156297D02*
X1263606Y-155131D01*
X1262295Y-154547D01*
X1260767Y-154256D01*
X1259239Y-154839D01*
X1257929Y-156005D01*
X1257055Y-157755D01*
X1256619Y-160089D01*
X1257055Y-162422D01*
X1257929Y-164172D01*
X1259239Y-165339D01*
X1260767Y-165922D01*
X1262295Y-165630D01*
X1263606Y-164756D01*
X1264479Y-163589D01*
G01X1273464Y-171172D02*
X1274774Y-171755D01*
X1276521Y-171172D01*
X1277612Y-170006D01*
X1278486Y-168547D01*
X1279795Y-163881D01*
X1282634Y-154256D01*
G01X1275647D02*
X1279795Y-163881D01*
G01X1292274Y-158047D02*
X1299261D01*
X1298606Y-156005D01*
X1297514Y-154839D01*
X1295986Y-154256D01*
X1294457Y-154547D01*
X1293147Y-155422D01*
X1292274Y-157464D01*
X1291837Y-159214D01*
Y-160964D01*
X1292274Y-162714D01*
X1293366Y-164464D01*
X1294676Y-165630D01*
X1296204Y-165922D01*
X1297732Y-165339D01*
X1299261Y-163589D01*
G01X1309992Y-165922D02*
Y-154256D01*
G01Y-156589D02*
X1311084Y-155422D01*
X1312176Y-154547D01*
X1313704Y-154256D01*
X1314795Y-154547D01*
X1316106Y-155422D01*
G01X1380796Y-165922D02*
Y-148422D01*
X1385162D01*
X1386909Y-149297D01*
X1388219Y-150464D01*
X1389311Y-152213D01*
X1390184Y-154256D01*
X1390402Y-157172D01*
X1390184Y-160089D01*
X1389311Y-162131D01*
X1388219Y-163881D01*
X1386909Y-165047D01*
X1385162Y-165922D01*
X1380796D01*
G01X1399824Y-158047D02*
X1406811D01*
X1406156Y-156005D01*
X1405064Y-154839D01*
X1403536Y-154256D01*
X1402007Y-154547D01*
X1400697Y-155422D01*
X1399824Y-157464D01*
X1399387Y-159214D01*
Y-160964D01*
X1399824Y-162714D01*
X1400916Y-164464D01*
X1402226Y-165630D01*
X1403754Y-165922D01*
X1405282Y-165339D01*
X1406811Y-163589D01*
G01X1417324Y-163881D02*
X1418416Y-165047D01*
X1419944Y-165922D01*
X1421254D01*
X1422564Y-165339D01*
X1423437Y-164464D01*
X1423874Y-163298D01*
X1423656Y-161547D01*
X1422782Y-160672D01*
X1418852Y-158922D01*
X1417979Y-156880D01*
X1418416Y-155422D01*
X1419289Y-154547D01*
X1420599Y-154256D01*
X1421909Y-154547D01*
X1423219Y-155422D01*
G01X1438099Y-154256D02*
Y-165922D01*
G01Y-149589D02*
X1437662Y-149297D01*
Y-148714D01*
X1438099Y-148422D01*
X1438536Y-148714D01*
Y-149297D01*
X1438099Y-149589D01*
G01X1452542Y-170297D02*
X1454071Y-171464D01*
X1455817Y-171755D01*
X1457345Y-171464D01*
X1458656Y-170006D01*
X1459529Y-167964D01*
Y-154256D01*
G01Y-156589D02*
X1458656Y-155422D01*
X1457345Y-154547D01*
X1455817Y-154256D01*
X1454071Y-154839D01*
X1452979Y-156005D01*
X1452105Y-158047D01*
X1451669Y-160089D01*
X1451887Y-161839D01*
X1452761Y-163881D01*
X1454071Y-165339D01*
X1455817Y-165922D01*
X1457127Y-165630D01*
X1458656Y-164464D01*
X1459529Y-163298D01*
G01X1469387Y-165922D02*
Y-154256D01*
G01Y-157172D02*
X1470261Y-155714D01*
X1471571Y-154547D01*
X1473317Y-154256D01*
X1474845Y-154547D01*
X1476156Y-155714D01*
X1476811Y-157755D01*
Y-165922D01*
G01X1487324Y-158047D02*
X1494311D01*
X1493656Y-156005D01*
X1492564Y-154839D01*
X1491036Y-154256D01*
X1489507Y-154547D01*
X1488197Y-155422D01*
X1487324Y-157464D01*
X1486887Y-159214D01*
Y-160964D01*
X1487324Y-162714D01*
X1488416Y-164464D01*
X1489726Y-165630D01*
X1491254Y-165922D01*
X1492782Y-165339D01*
X1494311Y-163589D01*
G01X1505042Y-165922D02*
Y-154256D01*
G01Y-156589D02*
X1506134Y-155422D01*
X1507226Y-154547D01*
X1508754Y-154256D01*
X1509845Y-154547D01*
X1511156Y-155422D01*
G01X1426729Y-193422D02*
X1431969D01*
G01X1429349D02*
Y-210922D01*
G01X1426729D02*
X1431969D01*
G01X1441390Y-193422D02*
X1446849Y-210922D01*
X1452308Y-193422D01*
G01X1464349Y-210922D02*
Y-203047D01*
X1459982Y-193422D01*
G01X1468716D02*
X1464349Y-203047D01*
G01X1551799Y-193422D02*
X1550052Y-194005D01*
X1548742Y-195464D01*
X1547869Y-197213D01*
X1547214Y-199547D01*
X1546996Y-202172D01*
X1547214Y-204797D01*
X1547869Y-207131D01*
X1548742Y-208881D01*
X1550052Y-210339D01*
X1551799Y-210922D01*
X1553545Y-210339D01*
X1554856Y-208881D01*
X1555729Y-207131D01*
X1556384Y-204797D01*
X1556602Y-202172D01*
X1556384Y-199547D01*
X1555729Y-197213D01*
X1554856Y-195464D01*
X1553545Y-194005D01*
X1551799Y-193422D01*
G01X1565151Y-196339D02*
X1566461Y-194589D01*
X1567989Y-193714D01*
X1569736Y-193422D01*
X1571919Y-194005D01*
X1573447Y-195464D01*
X1573884Y-197213D01*
X1573666Y-198964D01*
X1572792Y-200422D01*
X1568426Y-203339D01*
X1566461Y-205380D01*
X1565151Y-208298D01*
X1564714Y-210922D01*
X1573884D01*
G01X1582869Y-211505D02*
X1590729Y-193422D01*
G01X1604299Y-210922D02*
Y-193422D01*
X1601679Y-196922D01*
G01Y-210922D02*
X1606919D01*
G01X1621799Y-193422D02*
X1620052Y-194005D01*
X1618742Y-195464D01*
X1617869Y-197213D01*
X1617214Y-199547D01*
X1616996Y-202172D01*
X1617214Y-204797D01*
X1617869Y-207131D01*
X1618742Y-208881D01*
X1620052Y-210339D01*
X1621799Y-210922D01*
X1623545Y-210339D01*
X1624856Y-208881D01*
X1625729Y-207131D01*
X1626384Y-204797D01*
X1626602Y-202172D01*
X1626384Y-199547D01*
X1625729Y-197213D01*
X1624856Y-195464D01*
X1623545Y-194005D01*
X1621799Y-193422D01*
G01X1635369Y-211505D02*
X1643229Y-193422D01*
G01X1652651Y-196339D02*
X1653961Y-194589D01*
X1655489Y-193714D01*
X1657236Y-193422D01*
X1659419Y-194005D01*
X1660947Y-195464D01*
X1661384Y-197213D01*
X1661166Y-198964D01*
X1660292Y-200422D01*
X1655926Y-203339D01*
X1653961Y-205380D01*
X1652651Y-208298D01*
X1652214Y-210922D01*
X1661384D01*
G01X1674299Y-193422D02*
X1672552Y-194005D01*
X1671242Y-195464D01*
X1670369Y-197213D01*
X1669714Y-199547D01*
X1669496Y-202172D01*
X1669714Y-204797D01*
X1670369Y-207131D01*
X1671242Y-208881D01*
X1672552Y-210339D01*
X1674299Y-210922D01*
X1676045Y-210339D01*
X1677356Y-208881D01*
X1678229Y-207131D01*
X1678884Y-204797D01*
X1679102Y-202172D01*
X1678884Y-199547D01*
X1678229Y-197213D01*
X1677356Y-195464D01*
X1676045Y-194005D01*
X1674299Y-193422D01*
G01X1691799Y-210922D02*
Y-193422D01*
X1689179Y-196922D01*
G01Y-210922D02*
X1694419D01*
G01X1708862D02*
X1709299Y-207131D01*
X1709954Y-203922D01*
X1710827Y-201005D01*
X1711919Y-197797D01*
X1713666Y-193422D01*
X1704932D01*
G01X1599496Y-165922D02*
Y-148422D01*
X1603862D01*
X1605609Y-149297D01*
X1606919Y-150464D01*
X1608011Y-152213D01*
X1608884Y-154256D01*
X1609102Y-157172D01*
X1608884Y-160089D01*
X1608011Y-162131D01*
X1606919Y-163881D01*
X1605609Y-165047D01*
X1603862Y-165922D01*
X1599496D01*
G01X1625729D02*
Y-154256D01*
G01Y-156297D02*
X1624856Y-155131D01*
X1623545Y-154547D01*
X1622017Y-154256D01*
X1620489Y-154839D01*
X1619179Y-156005D01*
X1618305Y-157755D01*
X1617869Y-160089D01*
X1618305Y-162422D01*
X1619179Y-164172D01*
X1620489Y-165339D01*
X1622017Y-165922D01*
X1623545Y-165630D01*
X1624856Y-164756D01*
X1625729Y-163589D01*
G01X1639299Y-148422D02*
Y-165922D01*
G01X1636242Y-154256D02*
X1642356D01*
G01X1653524Y-158047D02*
X1660511D01*
X1659856Y-156005D01*
X1658764Y-154839D01*
X1657236Y-154256D01*
X1655707Y-154547D01*
X1654397Y-155422D01*
X1653524Y-157464D01*
X1653087Y-159214D01*
Y-160964D01*
X1653524Y-162714D01*
X1654616Y-164464D01*
X1655926Y-165630D01*
X1657454Y-165922D01*
X1658982Y-165339D01*
X1660511Y-163589D01*
G54D27*
X1613069Y302692D03*
G54D36*
X1949650Y220787D03*
Y228661D03*
G54D18*
X42724Y644684D03*
Y644656D03*
Y654684D03*
Y654656D03*
X67724Y644684D03*
Y644656D03*
Y654684D03*
Y654656D03*
X221656Y644656D03*
X196656D03*
X231446Y644756D03*
Y644784D03*
X221656Y644684D03*
X196656D03*
X221656Y654656D03*
X196656D03*
X231446Y654756D03*
Y654784D03*
X221656Y654684D03*
X196656D03*
X256446Y644756D03*
Y644784D03*
Y654756D03*
Y654784D03*
X409240Y644564D03*
X384240D03*
X418914Y644486D03*
Y644514D03*
X409240Y644536D03*
X384240D03*
X409240Y654564D03*
X384240D03*
X418914Y654486D03*
Y654514D03*
X409240Y654536D03*
X384240D03*
X443914Y644486D03*
Y644514D03*
Y654486D03*
Y654514D03*
X596707Y644293D03*
X571707D03*
X596708Y644266D03*
X571708D03*
X596707Y654293D03*
X571707D03*
X596708Y654266D03*
X571708D03*
X606462Y644245D03*
X631462D03*
X606462Y644217D03*
X631462D03*
X606462Y654245D03*
X631462D03*
X606462Y654217D03*
X631462D03*
X912351Y644245D03*
X887351D03*
X912351Y644273D03*
X887351D03*
X912351Y654245D03*
X887351D03*
X912351Y654273D03*
X887351D03*
X922116Y644206D03*
X947116D03*
X922116Y644234D03*
X947116D03*
X922116Y654206D03*
X947116D03*
X922116Y654234D03*
X947116D03*
X1200877Y644262D03*
Y644234D03*
Y654262D03*
Y654234D03*
X1225877Y644262D03*
X1235614Y644236D03*
X1260614D03*
X1235614Y644264D03*
X1260614D03*
X1225877Y644234D03*
Y654262D03*
X1235614Y654236D03*
X1260614D03*
X1235614Y654264D03*
X1260614D03*
X1225877Y654234D03*
X1514375Y644292D03*
Y644264D03*
Y654292D03*
Y654264D03*
X1539375Y644292D03*
Y644264D03*
Y654292D03*
Y654264D03*
G54D46*
G01X1462729Y310537D02*
X1462737Y310545D01*
G01X1465292Y309842D02*
X1463399D01*
G01X1465244Y306670D02*
X1463484D01*
G01X1457150Y306726D02*
X1458910D01*
G01X1459643Y304014D02*
Y305978D01*
G01X1462737Y310545D02*
Y312142D01*
G36*
G01X1956463Y209274D02*
G02X1954500Y205493I-1963J-1381D01*
G01X1950000D01*
G02X1947600Y207893I0J2400D01*
G01Y210293D01*
G02X1952400I2400J0D01*
G01X1954500D01*
G02X1954986Y210243I-1J-2400D01*
G03X1956463Y209274I1904J1292D01*
G37*
G54D19*
X107249Y105000D03*
G54D28*
X1643803Y585591D03*
X1640850Y582835D03*
X1631992D03*
X1623134D03*
X1640850Y567874D03*
X1631992D03*
X1623134D03*
X1646756Y595039D03*
X1623134Y612756D03*
X1640850Y597795D03*
X1631992D03*
X1623134D03*
X1640850Y612756D03*
X1631992D03*
X1691047Y585591D03*
X1688094Y582835D03*
X1679236D03*
X1670378D03*
X1688094Y567874D03*
X1679236D03*
X1670378D03*
X1694000Y595039D03*
X1688094Y612756D03*
X1679236D03*
X1670378D03*
X1688094Y597795D03*
X1679236D03*
X1670378D03*
G54D38*
X1952250Y240355D03*
G54D29*
X1702205Y536791D03*
X1687205D03*
X1717205D03*
G54D39*
X1922248Y518328D03*
M02*
